PCBA:DATE:2023/07/13REV:V02REV:CGT AMD MB8 RETIMERPROJECT NAME:GT AMDWed Sep 13 22:10:40 2023<NAME_2><NAME_1>MB FABCGT AMDV021 OF 365COVER PAGE
SHEETDATE
DEPARTMENT
SIZE
PROJECT DOCUMENT NUMBER REV
REVIEWER
DESIGNER
123
7 3 2 1 6 5 4
E
A
B
C
E
D
C
B
A
7 6 5 4
D
C



7879FPGA 1/6CPU HW STRAP PINCPU1 CAVITY BOT DECOUPLING CAPS 3/3CPU1 CAVITY BOT DECOUPLING CAPS 2/3Blank<NAME_1><NAME_2>CPU0 GLUE LOGICCPU0 VSS 3/3CPU0 VSS 2/3CPU0 VSS 1/3CPU0 POWER29 120119118117116114113112111110109108107106105104103102101100999897969594939291908988878685848381
8076737271706968676665646362616059585756555453525150494847464544434241
403938373635343332313028272625242322212019181716151413121110987654321
PCIE - CPU1_EXAMAX_P2/P3_X16PCIE - CPU0_EXAMAX_P0/P1_X16PCIE - CPU0_EXAMAX_P0/P1_X16PCIE - CPU0_EXAMAX_P2/P3_X16PCIE - CPU0_EXAMAX_P2/P3_X16BlankBMC-GPU FPGA PCIE RE-DRIVER SELECTBMC-GPU FPGA PCIE - RE-DRIVER (2nd)BMC - GPU FPGA PCIE - RE-DRIVER (main)BlankDDR5 - CPU1 CHLDDR5 - CPU1 CHKDDR5 - CPU1 CHJDDR5 - CPU1 CHIDDR5 - CPU1 CHHDDR5 - CPU1 CHGDDR5 - CPU1 CHFDDR5 - CPU1 CHEDDR5 - CPU1 CHDDDR5 - CPU1 CHCDDR5 - CPU1 CHBDDR5 - CPU1 CHADDR5 - CPU0 CHLDDR5 - CPU0 CHKDDR5 - CPU0 CHJDDR5 - CPU0 CHIDDR5 - CPU0 CHHDDR5 - CPU0 CHGDDR5 - CPU0 CHFDDR5 - CPU0 CHEDDR5 - CPU0 CHDDDR5 - CPU0 CHCDDR5 - CPU0 CHBDDR5 - CPU0 CHAFPGA 6/6FPGA 5/6 (BOARD ID)FPGA 4/6FPGA 3/6FPGA 2/6
CPU1 CAVITY BOT DECOUPLING CAPS 1/3CPU1 CAVITY TOP DECOUPLING CAPSCPU0 CAVITY BOT DECOUPLING CAPS 3/3CPU0 CAVITY BOT DECOUPLING CAPS 2/3CPU0 CAVITY BOT DECOUPLING CAPS 1/3CPU0 CAVITY TOP DECOUPLING CAPSPCIE AC-COUPLE CAPS 5/5PCIE AC-COUPLE CAPS 4/5PCIE AC-COUPLE CAPS 3/5PCIE AC-COUPLE CAPS 2/5BlankCPU1 GLUE LOGICCPU1 VSS 3/3CPU1 VSS 2/3CPU1 VSS 1/3CPU1 SPI/USBCPU1 MISC 2/2CPU1 MISC 1/2CPU1 PCIE P4/P5/WAFLCPU1 PCIE P2/P3CPU1 PCIE P0/P1CPU1 PCIE G2/G3CPU1 PCIE G0/G1CPU1 DDR CHLCPU1 DDR CHKCPU1 DDR CHJCPU1 DDR CHICPU1 DDR CHHCPU1 DDR CHGCPU1 DDR CHFCPU1 DDR CHE
CPU1 DDR CHCCPU1 DDR CHBCPU0 SPI/USBCPU0 MISC 2/2CPU0 MISC 1/2CPU0 PCIE P4/P5/WAFLCPU0 PCIE P2/P3CPU0 PCIE P0/P1CPU0 PCIE G2/G3CPU0 PCIE G0/G1CPU0 DDR CHLCPU0 DDR CHKCPU0 DDR CHJCPU0 DDR CHICPU0 DDR CHHCPU0 DDR CHGCPU0 DDR CHFCPU0 DDR CHECPU0 DDR CHDCPU0 DDR CHCCPU0 DDR CHBCPU0 DDR CHABLOCK DIAGRAM - POWER SEQUENCEBLOCK DIAGRAM - CLOCKBLOCK DIAGRAM - POWERBLOCK DIAGRAM - SYSTEMTABLE OF CONTENT 3/3TABLE OF CONTENT 2/3TABLE OF CONTENT 1/3COVER PAGE
GT AMD MB FABCThu Aug 24 10:13:29 20232 OF 365V02CPU1 DDR CHDBlankBlankCPU1 DDR CHA
82CPU1 POWERBLOCK DIAGRAM - I2C/I3CPCIE AC-COUPLE CAPS 1/5115PCIE - CPU1_EXAMAX_P2/P3_X16777574CPU SPI LEVEL SHIFTCPU PWROKTABLE OF CONTENT 1/3
1
DEPARTMENT REV
7 3 2 6 5 4
C
A
B
7
E
D
6 4 5 3 2 1
E
D
C
B
A
DATE
PROJECT
SHEET
DOCUMENT NUMBERDESIGNER
SIZE
REVIEWER
C
CONTENTSPAGE(S) PAGE(S) CONTENTS PAGE(S) CONTENTS



240239238237236235234233232231230229228227226225224223222221220219218217216215214213212211210209208207206205204203202201
199198196195194193192191190189188187186185184183182181180179178177176175174173172171170169168166165164163162161
160159158157156155154153152151150149148147146145144143142141140139138137136135134133132131130129128127126125124123122121
POWER CONNECTOR/ISOLATEDBlankMB FRUPOWER MONITOR (2/4)POWER MONITOR (1/4)TEMP SENSOR - LM75USB HUB (BMC TO EXAMAX)CLK-GEN(NON SSC)BlankBlankHOLEDELTA-LBlankBlankPVDD18_S5_P1PVDD11_S3_P1 VR PHASE 1&2PVDD11_S3_P1 VR CONTROLLERPVDDIO_P1 VR PHASE 3&4PVDDIO_P1 VR PHASE 1&2BlankPVDDCR_CPU1_P1 VR PHASE 5&6PVDDCR_CPU1_P1 VR PHASE 3&4PVDDCR_CPU1_P1 VR PHASE 1&2PVDDCR_CPU1_P1/PVDDIO_P1 VR CONTROLLERPVDDCR_SOC_P1 VR PHASE 3PVDDCR_SOC_P1 VR PHASE 1&2BlankPVDDCR_CPU0_P1 VR PHASE 5&6PVDDCR_CPU0_P1 VR PHASE 3&4PVDDCR_CPU0_P1 VR PHASE 1&2PVDDCR_CPU0_P1/PVDDCR_SOC_P1 VR CONTROLLERPVDD18_S5_P0PVDD11_S3_P0 VR PHASE 1&2BlankPVDDCR_CPU1_P0 VR PHASE 5&6PVDDCR_CPU1_P0 VR PHASE 1&2
PVDDCR_CPU1_P0/PVDDIO_P0 VR CONTROLLERPVDDCR_SOC_P0 VR PHASE 3PVDDCR_SOC_P0 VR PHASE 1&2BlankPVDDCR_CPU0_P0 VR PHASE 5&6PVDDCR_CPU0_P0 VR PHASE 3&4PVDDCR_CPU0_P0 VR PHASE 1&2PVDDCR_CPU0_P0/PVDDCR_SOC_P0 VR CONTROLLERPVDD_33_S5BlankNCP3284/P3V3_AUXMPQ8633A/P5V_AUXP5V & P3V3 SWITCHBATTERYSMBUS-RETIMER EEPROM MUXSMBUS - RETIMER EEPROMSMBUS - RETIMERCLK BUFFER _ 9ZXL045 _ CPU1 RETIMERCLK BUFFER _ 9ZXL045 _ CPU0 RETIMERBlankUSB3.0 EXT HUB USB SIGNAL SELECTUSB3.0 EXT HUB 2ND(2/2)USB3.0 EXT HUB 2ND(1/2)USB3.0 EXT HUB MAIN(2/2)USB3.0 EXT HUB MAIN(1/2)BlankJTAG - TDI/TDOJTAG - BUFFERJTAG - BMC MUXBlankDISCHARGE CIRCUITBlankDEBUG JUMPERLED (2/2)LED (1/2)UART LEVEL SHIFTBlankBlankI2C MUX - APML(2/2)
I2C MUX - APML(1/2)I3C MUX - DDR5 SPDBlankBlankBlankWAKEBlankSCM_SWP12V_SCMSCM SMBUS BUSSCM CONNCPU - SATA / RAID KEYE1S_HSC_CO_LAYOUTE1S_HSCCPU0 - E1S - 0 CONNCPU1 - M.2 - 0 CONN (EMPTY)OCP3.0 NCSIV3_2_OCP3.0 HSC(3/3)V3_2_OCP3.0 HSC-CO-LAYOUT(2/3)V3_2_OCP3.0 HSC(1/3)PCIE - V3_2 OCP3.0 (3/3)PCIE - V3_2 OCP3.0 (2/3)PCIE - V3_2 OCP3.0_X16_CPU1 (1/3)SFF_OCP3.0 HSC(3/3)SFF_OCP3.0 HSC CO-LAYOUT(2/3)SFF_OCP3.0 HSC(1/3)PCIE - SFF OCP3.0 (3/3)PCIE - SFF OCP3.0 (2/3)PCIE - SFF OCP3.0_X16_CPU0 (1/3)EXAMAX_ISO (7/7)EXAMAX_ISO (6/7)EXAMAX_ISO (5/7)EXAMAX_ISO (4/7)EXAMAX_ISO (3/7)EXAMAX_ISO (2/7)EXAMAX_ISO (1/7)EXAMAX_PRESENTPCIE - CPU1_EXAMAX_P0/P1_X16PCIE - CPU1_EXAMAX_P0/P1_X16
3 OF 365V02GT AMDThu Aug 24 10:13:29 2023MB FABC197Blank200<NAME_2><NAME_1>
PVDDCR_CPU1_P0 VR PHASE 3&4PVDDIO_P0_VR PHASE 1&2PVDDIO_P0_VR PHASE 3&4PVDD11_S3_P0 VR CONTROLLERJTAG - HDT & BMC MUX167
TABLE OF CONTENT 2/3
1
DEPARTMENT REV
7 3 2 6 5 4
C
A
B
7
E
D
6 4 5 3 2 1
E
D
C
B
A
DATE
PROJECT
SHEET
DOCUMENT NUMBERDESIGNER
SIZE
REVIEWER
C
CONTENTSPAGE(S) PAGE(S) CONTENTS PAGE(S) CONTENTS



<NAME_1><NAME_2>
POWER GOOD LED'S 3/3PWRGD_ISOLATORSMBUS - PCIE1 SMBUSBlank246
4 OF 365Thu Aug 24 10:13:29 2023V02GT AMD MB FABC360359358357356355354353352351350349348347346345344343342341340339338337336335334333332331330329328327326325324323322321
320319318317316315314313312311310309308307306305304303302301300299298297296295294293292291290289288287286285284283282281
280279278277276275274273272271270269268267266265264263262261260259258257256255254253252251250249248247245244243242241
P1V8_CPU0_RT_1DBlankBOARD ID (RETIMER)POWER MONITOR (4/4)RETIMER_CPU1_P3 DECAPS(8)RETIMER_CPU1_P3(7)RETIMER_CPU1_P3 POWER(6)RETIMER_CPU1_P3(5)RETIMER_CPU1_P3(4)RETIMER_CPU1_P3(3)RETIMER_CPU1_P3(2)RETIMER_CPU1_P3(1)BLANKRETIMER_CPU1_P2(10)RETIMER_CPU1_P2(9)RETIMER_CPU1_P2 DECAPS(8)RETIMER_CPU1_P2(7)RETIMER_CPU1_P2 POWER(6)RETIMER_CPU1_P2(5)RETIMER_CPU1_P2(4)RETIMER_CPU1_P2(3)RETIMER_CPU1_P2(2)RETIMER_CPU1_P2(1)BLANKRETIMER_CPU1_P1(10)RETIMER_CPU1_P1(9)RETIMER_CPU1_P1 DECAPS(8)RETIMER_CPU1_P1(7)RETIMER_CPU1_P1 POWER(6)RETIMER_CPU1_P1(5)RETIMER_CPU1_P1(4)RETIMER_CPU1_P1(3)RETIMER_CPU1_P1(2)RETIMER_CPU1_P1(1)BLANKRETIMER_CPU1_P0(10)RETIMER_CPU1_P0 (9)RETIMER_CPU1_P0 DECAPS (8)RETIMER_CPU1_P0(7)RETIMER_CPU1_P0 POWER(6)
RETIMER_CPU1_P0(5)RETIMER_CPU1_P0(4)RETIMER_CPU1_P0(3)RETIMER_CPU1_P0(2)RETIMER_CPU1_P0(1)BLANKRETIMER_CPU0_P3(10)RETIMER_CPU0_P3(9)RETIMER_CPU0_P3 DECAPS(8)RETIMER_CPU0_P3(7)RETIMER_CPU0_P3 POWER(6)RETIMER_CPU0_P3(5)RETIMER_CPU0_P3(4)RETIMER_CPU0_P3(3)RETIMER_CPU0_P3(2)RETIMER_CPU0_P3(1)BLANKRETIMER_CPU0_P2(10)RETIMER_CPU0_P2(9)RETIMER_CPU0_P2 DECAPS(8)RETIMER_CPU0_P2(7)RETIMER_CPU0_P2 POWER(6)RETIMER_CPU0_P2(5)RETIMER_CPU0_P2(4)RETIMER_CPU0_P2(3)RETIMER_CPU0_P2(2)RETIMER_CPU0_P2(1)BLANKRETIMER_CPU0_P1(10)RETIMER_CPU0_P1(9)RETIMER_CPU0_P1 DECAPS(8)RETIMER_CPU0_P1(7)RETIMER_CPU0_P1 POWER(6)RETIMER_CPU0_P1(5)RETIMER_CPU0_P1(4)RETIMER_CPU0_P1(3)RETIMER_CPU0_P1(2)RETIMER_CPU0_P1(1)BLANKRETIMER_CPU0_P0(10)
RETIMER_CPU0_P0(9)RETIMER_CPU0_P0 DECAPS(8)RETIMER_CPU0_P0(7)RETIMER_CPU0_P0 POWER(6)RETIMER_CPU0_P0(5)RETIMER_CPU0_P0(4)RETIMER_CPU0_P0(3)RETIMER_CPU0_P0(2)RETIMER_CPU0_P0(1)POWER MONITOR (3/4)P1V2_AUXP1V8_AUXHSC Shared CircuitP12V HOTSWAP FOR MODULE(2/2)P12V HOTSWAP FOR MODULE(1/2)BlankHSC MP5990 (3/3)HSC MP5990 (2/3)HSC MP5990 (1/3)TDR_2TDR_1P12V_MEM MOS SWITCHVOLTAGE SENSOR (2/2)VOLTAGE SENSOR (1/2)POWER GOOD LED'S 2/3POWER GOOD LED'S 1/3SMBUS - PCIE2 SMBUSSMBUS - PCIE0 SMBUSSMBUS - PCIE3 SMBUSSMBUS - ISOLATEDBlankBMC - PCA9539BlankBlankPSU POWER CONNECTORSPOWER CONNECTOR/ISOLATED
TABLE OF CONTENT 3/3
1
DEPARTMENT REV
7 3 2 6 5 4
C
A
B
7
E
D
6 4 5 3 2 1
E
D
C
B
A
DATE
PROJECT
SHEET
DOCUMENT NUMBERDESIGNER
SIZE
REVIEWER
C
CONTENTSPAGE(S) PAGE(S) CONTENTS PAGE(S) CONTENTS



Thu Aug 24 10:13:29 2023<NAME_2><NAME_1>MB FABCGT AMDV025 OF 365BLOCK DIAGRAM - SYSTEM
SHEETDATE
DEPARTMENT
SIZE
PROJECT DOCUMENT NUMBER REV
REVIEWER
DESIGNER
123
7 3 2 1 6 5 4
E
A
B
C
E
D
C
B
A
7 6 5 4
D
C



Thu Aug 24 10:13:30 2023<NAME_2><NAME_1>MB FABCGT AMDV026 OF 365BLOCK DIAGRAM - POWER
SHEETDATE
DEPARTMENT
SIZE
PROJECT DOCUMENT NUMBER REV
REVIEWER
DESIGNER
123
7 3 2 1 6 5 4
E
A
B
C
E
D
C
B
A
7 6 5 4
D
C



Thu Aug 24 10:13:30 2023<NAME_2><NAME_1>MB FABCGT AMDV027 OF 365BLOCK DIAGRAM - CLOCK
SHEETDATE
DEPARTMENT
SIZE
PROJECT DOCUMENT NUMBER REV
REVIEWER
DESIGNER
123
7 3 2 1 6 5 4
E
A
B
C
E
D
C
B
A
7 6 5 4
D
C



Thu Aug 24 10:13:30 2023<NAME_2><NAME_1>MB FABCGT AMDV028 OF 365BLOCK DIAGRAM - I2C/I3C
SHEETDATE
DEPARTMENT
SIZE
PROJECT DOCUMENT NUMBER REV
REVIEWER
DESIGNER
123
7 3 2 1 6 5 4
E
A
B
C
E
D
C
B
A
7 6 5 4
D
C



Thu Aug 24 10:13:30 2023<NAME_2><NAME_1>MB FABCGT AMDV029 OF 365BLOCK DIAGRAM - POWER SEQUENCE
SHEETDATE
DEPARTMENT
SIZE
PROJECT DOCUMENT NUMBER REV
REVIEWER
DESIGNER
123
7 3 2 1 6 5 4
E
A
B
C
E
D
C
B
A
7 6 5 4
D
C



Thu Sep 14 16:11:48 2023<NAME_2><NAME_1>MB FABCGT AMDV0210 OF 36586868686868686868686868686
868686868686868686R1941 PLACE CLOSE TO DIMM < 25MM0402LF15 1%
SOCKET6096_13568-001IO
M_A_CPU0_ALERT_NTP_M_A_CPU0_SA_TEST39ATP_M_A_CPU0_SA_TEST40M_A_CPU0_ALERT_R_NM_A_CPU0_SA_CA<6:0>M_A_CPU0_CLK_DP<0>M_A_CPU0_CLK_DN<0>M_A_CPU0_SA_CS_N<0>M_A_CPU0_SA_CS_N<1>M_A_CPU0_SA_RSP<0>M_A_CPU0_SB_CS_N<0>M_A_CPU0_SA_PARM_A_CPU0_SB_CS_N<1>M_A_CPU0_SB_RSP<0>M_A_CPU0_SB_PARM_A_CPU0_RESET_N
M_A_CPU0_SA_DQS_DN<9:0>M_A_CPU0_SA_DQS_DP<9:0>M_A_CPU0_SB_DQS_DP<9:0>M_A_CPU0_SA_CB<7:0>M_A_CPU0_SB_CB<7:0>M_A_CPU0_SB_DQ<31:0>M_A_CPU0_SA_DQ<31:0>M_A_CPU0_SB_DQS_DN<9:0>M_A_CPU0_SB_CA<6:0>
CPU0 DDR CHA
SMLF
21R375
C60
BF72
BL74
BW74
DC73
CU73
CL73
CE73
BW73
DC74
CU74
CL74
CE74
BV74
DD72
CV72
CM72
CF72
BY72
DB74
CT74
CK74
CD74
DF74
DE74
DE73
DD74
DB72
DA74
DA73
CY74
CY72
CW74
CW73
CV74
CT72
CR74
CR73
CP74
CP72
CN74
CN73
CM74
CK72
CJ74
CJ73
CH74
CH72
CG74
CG73
CF74
CD72
CC74
CC73
CB74
BV72
BU74
BU73
BT74
CB72
CA74
CA73
BY74
BK74
BK72
BJ73
BJ74
BH74
BH72
BG73
BR74
BM74
BL73
BP74
BN74
BM72
BC73
AM72
AF72
Y72
P72
H72
AM74
AF74
Y74
P74
H74
AN73
AG73
AA73
R73
J73
AL74
AE74
W74
N74
G74
AJ73
AH74
AH72
AG74
AE73
AD74
AD72
AC74
AC73
AB74
AB72
AA74
W73
V74
V72
U74
U73
T74
T72
R74
N73
M74
M72
L74
L73
K74
K72
J74
G73
F74
F72
E74
AR73
AP74
AP72
AN74
AL73
AK74
AK72
AJ74
BB72
BB74
BA74
BA73
AY72
AY74
AW74
BP72
AV72
AU74
BN73
AW73
AV74
AT74
AR74
BG74
BF74
BD74
BC74
U25
5
6
2
3
4
0
1
5
6
3
4
2
0
1
7
8
9
5
6
4
2
3
0
1
9
8
7
6
5
4
2
3
1
0
7
8
9
5
6
2
3
4
0
1
9
8
7
6
5
4
3
2
1
0
7
6
5
4
3
2
1
6
7
0
5
4
3
1
2
0
29
30
31
27
28
24
26
25
23
19
20
21
22
18
15
17
16
14
10
12
11
13
9
6
7
8
5
4
1
2
3
0
29
30
31
27
28
24
25
26
23
20
22
21
18
19
15
17
16
14
10
11
12
13
9
6
7
8
5
4
1
2
3
01/40
TEST40
TEST39A
MA1_CLK_L
MA0_CLK_L
MA1_CLK_H
MAB_DQS_H9
MA0_CLK_H
MAB_PAR
MAA_PAR
MAA0_CS_L0
MAA_DATA3
MAA_DQS_H6
MAB_CA6
MAB_DATA2
MAB_DATA17
MAB_DATA28
MAB_DQS_H0
MAB_DQS_L4
MAA_CA6
MAA_DATA2
MAA_DQS_H5
MAA_DQS_L9
MAB1_RSP_L
MAB_CA5
MAB_CHECK7
MAB_DATA1
MAB_DATA16
MAB_DATA27
MAB_DQS_L3
MAA_CA5
MAA_DATA1
MAA_DQS_H4
MAA_DQS_L8
MAB0_RSP_L
MAB_CA4
MAB_CHECK6
MAB_DATA0
MAB_DATA15
MAB_DATA26
MAB_DQS_L2
MAA_CA4
MAA_DATA0
MAA_DQS_H3
MAA_DQS_L7
MAB_CA3
MAB_CHECK5
MAB_DATA14
MAB_DATA25
MAB_DQS_L1
MAA_CA3
MAA_DATA19
MAA_DQS_H2
MAA_DQS_L6
MAB_CA2
MAB_CHECK4
MAB_DATA13
MAB_DATA24
MAB_DQS_L0
MAA_CA2
MAA_DATA18
MAA_DATA29
MAA_DQS_H1
MAA_DQS_L5
MAB_CA1
MAB_CHECK3
MAB_DATA12
MAB_DATA23
MAA_CA1
MAA_DATA17
MAA_DATA28
MAA_DQS_H0
MAA_DQS_L4
MAB_CA0
MAB_CHECK2
MAB_DATA11
MAB_DATA22
MAA1_RSP_L
MAA_CA0
MAA_CHECK7
MAA_DATA16
MAA_DATA27
MAA_DQS_L3
MAB_CHECK1
MAB_DATA10
MAB_DATA21
MAA0_RSP_L
MAA_CHECK6
MAA_DATA15
MAA_DATA26
MAA_DQS_L2
MAB_CHECK0
MAB_DATA20
MAB_DATA31
MAA_CHECK5
MAA_DATA14
MAA_DATA25
MAA_DQS_L1
MAB1_CS_L1
MAB_DATA30
MAB_DQS_H8
MAA_CHECK4
MAA_DATA13
MAA_DATA24
MAA_DQS_L0
MAB0_CS_L1
MAB1_CS_L0
MAB_DATA9
MAB_DQS_H7
MAA_CHECK3
MAA_DATA9
MAA_DATA12
MAA_DATA23
MAB0_CS_L0
MAB_DATA8
MAB_DQS_H6
MAA_CHECK2
MAA_DATA8
MAA_DATA11
MAA_DATA22
MAB_DATA7
MAB_DQS_H5
MAB_DQS_L9
MAA_CHECK1
MAA_DATA7
MAA_DATA10
MAA_DATA21
MAB_DATA6
MAB_DQS_H4
MAB_DQS_L8
MAA_CHECK0
MAA_DATA6
MAA_DATA20
MAA_DATA31
MAA_DQS_H9
MAB_DATA5
MAB_DQS_H3
MAB_DQS_L7
MAA1_CS_L1
MAA_DATA5
MAA_DATA30
MAA_DQS_H8
MAB_DATA4
MAB_DATA19
MAB_DQS_H2
MAB_DQS_L6
MAA0_CS_L1
MAA1_CS_L0
MAA_DATA4
MAA_DQS_H7
MAB_DATA3
MAB_DATA18
MAB_DATA29
MAB_DQS_H1
MAB_DQS_L5
MA_RESET_L
MA_ALERT_L
CAD NOTE:
SHEETDATE
DEPARTMENT
SIZE
PROJECT DOCUMENT NUMBER REV
REVIEWER
DESIGNER
123
7 3 2 1 6 5 4
E
A
B
C
E
D
C
B
A
7 6 5 4
D
IN
OUT
OUT
IN
OUT
OUT
OUT
IN
OUTOUT
OUTOUT
OUT
OUT
BIBI
BIBI
BI
BI
BI
BI
C



Thu Sep 14 16:11:48 2023<NAME_2><NAME_1>MB FABCGT AMDV0211 OF 365
8787878787878787878787878787
87878787
8787
8787M_B_CPU0_SB_CA<6:0>M_B_CPU0_CLK_DN<0>M_B_CPU0_SA_CS_N<0>M_B_CPU0_SB_CS_N<0>M_B_CPU0_SB_RSP<0>15M_B_CPU0_ALERT_R_NM_B_CPU0_ALERT_N1%0402LF
SOCKET6096_13568-001IO
TP_M_B_CPU0_SA_TEST39BM_B_CPU0_SA_CA<6:0>M_B_CPU0_CLK_DP<0>M_B_CPU0_SA_CS_N<1>M_B_CPU0_SA_PARM_B_CPU0_SA_RSP<0>M_B_CPU0_SB_CS_N<1>M_B_CPU0_SB_PARM_B_CPU0_RESET_N
M_B_CPU0_SA_DQS_DP<9:0>M_B_CPU0_SB_DQS_DP<9:0>M_B_CPU0_SB_DQS_DN<9:0>M_B_CPU0_SA_DQS_DN<9:0>
M_B_CPU0_SB_CB<7:0>M_B_CPU0_SA_CB<7:0>
M_B_CPU0_SA_DQ<31:0>M_B_CPU0_SB_DQ<31:0>
CPU0 DDR CHBR1946 PLACE CLOSE TO CPU < 25MM
SMLF
21R376
BF62
BL64
BW64
DC62
CU62
CL62
CE62
BW62
DC64
CU64
CL64
CE64
BV63
DD62
CV62
CM62
CF62
BY62
DB63
CT63
CK63
CD63
DF62
DE64
DE62
DD63
DB62
DA64
DA62
CY63
CY62
CW64
CW62
CV63
CT62
CR64
CR62
CP63
CP62
CN64
CN62
CM63
CK62
CJ64
CJ62
CH63
CH62
CG64
CG62
CF63
CD62
CC64
CC62
CB63
BV62
BU64
BU62
BT63
CB62
CA64
CA62
BY63
BK63
BK62
BJ62
BJ64
BH63
BH62
BG62
BR64
BM63
BL62
BP63
BN64
BM62
BC62
AM62
AF62
Y62
P62
H62
AM63
AF63
Y63
P63
H63
AN62
AG62
AA62
R62
J62
AL64
AE64
W64
N64
G64
AJ62
AH63
AH62
AG64
AE62
AD63
AD62
AC64
AC62
AB63
AB62
AA64
W62
V63
V62
U64
U62
T63
T62
R64
N62
M63
M62
L64
L62
K63
K62
J64
G62
F63
F62
E64
AR62
AP63
AP62
AN64
AL62
AK63
AK62
AJ64
BB62
BB63
BA64
BA62
AY62
AY63
AW64
BP62
AV62
AU64
BN62
AW62
AV63
AU62
AT62
BG64
BF63
BD63
BC64
U25
6
5
4
3
2
1
0
6
3
5
4
2
1
0
7
8
9
9
8
5
6
5
7
6
4
3
2
4
3
0
1
1
0
2
9
8
8
9
7
6
5
6
7
3
2
4
4
5
3
0
1
2
1
0
6
7
5
4
3
2
1
0
6
5
7
3
2
4
1
0
31
30
29
28
27
25
26
24
22
21
23
19
20
18
17
16
14
15
13
12
10
9
11
8
6
7
5
4
3
0
1
2
31
28
30
29
27
26
25
24
23
22
21
19
20
18
17
16
15
14
13
12
9
10
11
8
7
6
5
3
4
0
1
2
2/40
TEST39B
MBB_DATA20
MBA_DATA24
MBB_DATA19
MB1_CLK_L
MB1_CLK_H
MB0_CLK_L
MB0_CLK_H
MBB_PAR
MBA_PAR
MBB_DQS_H9
MBA_CHECK1
MBA_DATA10
MBA_DATA21
MBB_DQS_H4
MBB_DQS_L8
MBA1_CS_L1
MBA_CHECK0
MBA_DATA20
MBA_DATA31
MBA_DQS_H9
MBB_CA6
MBB_DQS_H3
MBB_DQS_L7
MBA0_CS_L1
MBA1_CS_L0
MBA_CA6
MBA_DATA30
MBA_DQS_H8
MBB_CA5
MBB_DQS_H2
MBB_DQS_L6
MBA0_CS_L0
MBA_CA5
MBA_DQS_H7
MBB_CA4
MBB_DATA18
MBB_DATA29
MBB_DQS_H1
MBB_DQS_L5
MBA_CA4
MBA_DQS_H6
MBB1_RSP_L
MBB_CA3
MBB_DATA9
MBB_DATA17
MBB_DATA28
MBB_DQS_H0
MBB_DQS_L4
MBA_CA3
MBA_DATA9MBA_DQS_H5
MBA_DQS_L9
MBB0_RSP_L
MBB_CA2
MBB_CHECK7
MBB_DATA8
MBB_DATA16
MBB_DATA27
MBB_DQS_L3
MBA_CA2
MBA_DATA8
MBA_DQS_H4
MBA_DQS_L8
MBB_CA1
MBB_CHECK6
MBB_DATA7
MBB_DATA15
MBB_DATA26
MBB_DQS_L2
MBA_CA1
MBA_DATA7
MBA_DQS_H3
MBA_DQS_L7
MBB_CA0
MBB_CHECK5
MBB_DATA6
MBB_DATA14
MBB_DATA25
MBB_DQS_L1
MBA_CA0
MBA_DATA6
MBA_DATA19
MBA_DQS_H2
MBA_DQS_L6
MBB_CHECK4
MBB_DATA5
MBB_DATA13
MBB_DATA24
MBB_DQS_L0
MBA_DATA5
MBA_DATA18
MBA_DATA29
MBA_DQS_H1
MBA_DQS_L5
MBB_CHECK3
MBB_DATA4
MBB_DATA12
MBB_DATA23
MBA1_RSP_L
MBA_DATA4
MBA_DATA17
MBA_DATA28
MBA_DQS_H0
MBA_DQS_L4
MBB_CHECK2
MBB_DATA3
MBB_DATA11
MBB_DATA22
MBA0_RSP_L
MBA_CHECK7
MBA_DATA3
MBA_DATA16
MBA_DATA27
MBA_DQS_L3
MBB_CHECK1
MBB_DATA2
MBB_DATA10
MBB_DATA21
MBA_CHECK6
MBA_DATA2
MBA_DATA15
MBA_DATA26
MBA_DQS_L2
MBB1_CS_L1
MBB_CHECK0
MBB_DATA1
MBB_DATA31
MBA_CHECK5
MBA_DATA1
MBA_DATA14
MBA_DATA25
MBA_DQS_L1
MBB0_CS_L1
MBB1_CS_L0
MBB_DATA0
MBB_DATA30
MBB_DQS_H8
MBA_CHECK4
MBA_DATA0
MBA_DATA13
MBA_DQS_L0
MBB0_CS_L0
MBB_DQS_H7
MBA_CHECK3
MBA_DATA12
MBA_DATA23
MBB_DQS_H6
MBA_CHECK2
MBA_DATA11
MBA_DATA22
MBB_DQS_H5
MBB_DQS_L9
MB_RESET_L
MB_ALERT_L
CAD NOTE:
SHEETDATE
DEPARTMENT
SIZE
PROJECT DOCUMENT NUMBER REV
REVIEWER
DESIGNER
123
7 3 2 1 6 5 4
E
A
B
C
E
D
C
B
A
7 6 5 4
D
IN
OUT
IN
OUT
OUT
IN
OUT
OUT
OUTOUT
OUTOUT
OUT
OUT
BIBI
BIBI
BI
BI
BI
BI
C



Thu Sep 14 16:11:49 2023<NAME_2><NAME_1>MB FABCGT AMDV0212 OF 3658888888888888888888888888888888888888888
888815M_C_CPU0_ALERT_R_NM_C_CPU0_ALERT_N1%0402LF
SOCKET6096_13568-001IOM_C_CPU0_SA_CA<6:0>M_C_CPU0_SB_CA<6:0>TP_M_C_CPU0_SA_TEST39CM_C_CPU0_CLK_DP<0>M_C_CPU0_CLK_DN<0>M_C_CPU0_SA_RSP<0>M_C_CPU0_SA_CS_N<0>M_C_CPU0_SA_CS_N<1>M_C_CPU0_SA_PARM_C_CPU0_SB_CS_N<0>M_C_CPU0_SB_CS_N<1>M_C_CPU0_SB_RSP<0>M_C_CPU0_SB_PARM_C_CPU0_RESET_NM_C_CPU0_SB_DQS_DN<9:0>M_C_CPU0_SA_DQS_DN<9:0>M_C_CPU0_SA_DQS_DP<9:0>M_C_CPU0_SB_DQS_DP<9:0>M_C_CPU0_SB_CB<7:0>M_C_CPU0_SA_CB<7:0>
M_C_CPU0_SA_DQ<31:0>M_C_CPU0_SB_DQ<31:0>R1951 PLACE CLOSE TO CPU < 25MMCPU0 DDR CHC
SMLF
21R377
BF55
BL57
BW57
DC55
CU55
CL55
CE55
BW55
DC57
CU57
CL57
CE57
BV56
DD55
CV55
CM55
CF55
BY55
DB56
CT56
CK56
CD56
DF55
DE57
DE55
DD56
DB55
DA57
DA55
CY56
CY55
CW57
CW55
CV56
CT55
CR57
CR55
CP56
CP55
CN57
CN55
CM56
CK55
CJ57
CJ55
CH56
CH55
CG57
CG55
CF56
CD55
CC57
CC55
CB56
BV55
BU57
BU55
BT56
CB55
CA57
CA55
BY56
BK56
BK55
BJ55
BJ57
BH56
BH55
BG55
BR57
BM56
BL55
BP56
BN57
BM55
BC55
AM55
AF55
Y55
P55
H55
AM56
AF56
Y56
P56
H56
AN55
AG55
AA55
R55
J55
AL57
AE57
W57
N57
G57
AJ55
AH56
AH55
AG57
AE55
AD56
AD55
AC57
AC55
AB56
AB55
AA57
W55
V56
V55
U57
U55
T56
T55
R57
N55
M56
M55
L57
L55
K56
K55
J57
G55
F56
F55
E57
AR55
AP56
AP55
AN57
AL55
AK56
AK55
AJ57
BB55
BB56
BA57
BA55
AY55
AY56
AW57
BP55
AV55
AU57
BN55
AW55
AV56
AU55
AT55
BG57
BF56
BD56
BC57
U25
6
5
4
2
3
1
0
6
5
4
3
2
0
1
8
9
9
6
7
4
3
5
1
2
9
0
6
7
8
4
3
5
0
2
1
7
8
6
5
3
4
2
1
0
9
8
7
6
5
4
3
2
1
0
6
7
5
4
3
2
1
0
7
6
5
4
3
2
1
0
31
30
29
28
27
25
26
24
21
23
20
22
19
18
17
16
13
15
14
12
11
10
9
8
7
6
5
4
3
2
0
1
31
30
29
28
27
26
25
24
23
22
21
20
19
18
17
16
15
14
13
12
11
9
10
8
7
6
5
4
3
2
0
1
3/40
TEST39C
MC1_CLK_L
MC1_CLK_H
MC0_CLK_L
MC0_CLK_H
MCB_PAR
MCA_PAR
MCB_DQS_H9
MCA_CHECK4
MCA_DATA8
MCA_DATA13
MCA_DATA24
MCA_DQS_L0
MCB0_CS_L0
MCB1_CS_L0
MCB_DATA7
MCB_DQS_H7
MCA_CHECK3
MCA_DATA7
MCA_DATA12
MCA_DATA23
MCB_DATA6
MCB_DQS_H6
MCA_CHECK2
MCA_DATA6
MCA_DATA11
MCA_DATA22
MCB_CA6
MCB_DATA5
MCB_DQS_H5
MCB_DQS_L9
MCA_CA6
MCA_CHECK1
MCA_DATA5
MCA_DATA10
MCA_DATA21
MCB_CA5
MCB_DATA4
MCB_DQS_H4
MCB_DQS_L8
MCA_CA5
MCA_CHECK0
MCA_DATA4
MCA_DATA20
MCA_DATA31
MCA_DQS_H9
MCB_CA4
MCB_DATA3
MCB_DQS_H3
MCB_DQS_L7
MCA1_CS_L1
MCA_CA4
MCA_DATA3
MCA_DATA30
MCA_DQS_H8
MCB_CA3
MCB_DATA2
MCB_DATA19
MCB_DQS_H2
MCB_DQS_L6
MCA0_CS_L1
MCA1_CS_L0
MCA_CA3
MCA_DATA2
MCA_DQS_H7
MCB_CA2
MCB_DATA1
MCB_DATA18
MCB_DATA29
MCB_DQS_H1
MCB_DQS_L5
MCA0_CS_L0
MCA_CA2
MCA_DATA1
MCA_DQS_H6
MCB_CA1
MCB_DATA0
MCB_DATA17
MCB_DATA28
MCB_DQS_H0
MCB_DQS_L4
MCA_CA1
MCA_DATA0
MCA_DQS_H5
MCA_DQS_L9
MCB0_RSP_L
MCB1_RSP_L
MCB_CA0
MCB_CHECK7
MCB_DATA16
MCB_DATA27
MCB_DQS_L3
MCA_CA0
MCA_DQS_H4
MCA_DQS_L8
MCB_CHECK6
MCB_DATA15
MCB_DATA26
MCB_DQS_L2
MCA_DQS_H3
MCA_DQS_L7
MCB_CHECK5
MCB_DATA14
MCB_DATA25
MCB_DQS_L1
MCA_DATA19
MCA_DQS_H2
MCA_DQS_L6
MCB_CHECK4
MCB_DATA13
MCB_DATA24
MCB_DQS_L0
MCA_DATA18
MCA_DATA29
MCA_DQS_H1
MCA_DQS_L5
MCB_CHECK3
MCB_DATA12
MCB_DATA23
MCA_DATA17
MCA_DATA28
MCA_DQS_H0
MCA_DQS_L4
MCB_CHECK2
MCB_DATA11
MCB_DATA22
MCA1_RSP_L
MCA_CHECK7
MCA_DATA16
MCA_DATA27
MCA_DQS_L3
MCB_CHECK1
MCB_DATA10
MCB_DATA21
MCA0_RSP_L
MCA_CHECK6
MCA_DATA15
MCA_DATA26
MCA_DQS_L2
MCB_CHECK0
MCB_DATA9
MCB_DATA20
MCB_DATA31
MCA_CHECK5
MCA_DATA9
MCA_DATA14
MCA_DATA25
MCA_DQS_L1
MCB0_CS_L1
MCB1_CS_L1
MCB_DATA8
MCB_DATA30
MCB_DQS_H8
MC_RESET_L
MC_ALERT_L
CAD NOTE:
SHEETDATE
DEPARTMENT
SIZE
PROJECT DOCUMENT NUMBER REV
REVIEWER
DESIGNER
123
7 3 2 1 6 5 4
E
A
B
C
E
D
C
B
A
7 6 5 4
D
OUT
IN
OUT
IN
OUTOUT
OUT
OUTOUT
IN
OUTOUT
OUT
OUT
BIBI
BIBI
BI
BI
BI
BI
C



Thu Sep 14 16:11:49 2023<NAME_2><NAME_1>MB FABCGT AMDV0213 OF 365898989898989
8989
898989
898989898989898989898915M_D_CPU0_ALERT_R_NM_D_CPU0_ALERT_N1%0402LFM_D_CPU0_SB_CA<6:0>M_D_CPU0_SA_CA<6:0>M_D_CPU0_SB_DQS_DP<9:0>SMLF
CPU0 DDR CHDR1952 PLACE CLOSE TO CPU < 25MMM_D_CPU0_SB_DQ<31:0>M_D_CPU0_SA_DQ<31:0>
M_D_CPU0_SA_CB<7:0>M_D_CPU0_SB_CB<7:0>
M_D_CPU0_SA_DQS_DN<9:0>M_D_CPU0_SB_DQS_DN<9:0>M_D_CPU0_SA_DQS_DP<9:0>
M_D_CPU0_RESET_NM_D_CPU0_SB_PARM_D_CPU0_SB_RSP<0>M_D_CPU0_SB_CS_N<1>M_D_CPU0_SB_CS_N<0>M_D_CPU0_SA_PARM_D_CPU0_SA_RSP<0>M_D_CPU0_SA_CS_N<1>M_D_CPU0_SA_CS_N<0>M_D_CPU0_CLK_DN<0>M_D_CPU0_CLK_DP<0>TP_M_D_CPU0_SA_TEST39D
IOSOCKET6096_13568-001
21R378
BF58
BL60
BW60
DC59
CU59
CL59
CE59
BW59
DC60
CU60
CL60
CE60
BV60
DD58
CV58
CM58
CF58
BY58
DB60
CT60
CK60
CD60
DF60
DE60
DE59
DD60
DB58
DA60
DA59
CY60
CY58
CW60
CW59
CV60
CT58
CR60
CR59
CP60
CP58
CN60
CN59
CM60
CK58
CJ60
CJ59
CH60
CH58
CG60
CG59
CF60
CD58
CC60
CC59
CB60
BV58
BU60
BU59
BT60
CB58
CA60
CA59
BY60
BK60
BK58
BJ59
BJ60
BH60
BH58
BG59
BR60
BM60
BL59
BP60
BN60
BM58
BC59
AM58
AF58
Y58
P58
H58
AM60
AF60
Y60
P60
H60
AN59
AG59
AA59
R59
J59
AL60
AE60
W60
N60
G60
AJ59
AH60
AH58
AG60
AE59
AD60
AD58
AC60
AC59
AB60
AB58
AA60
W59
V60
V58
U60
U59
T60
T58
R60
N59
M60
M58
L60
L59
K60
K58
J60
G59
F60
F58
E60
AR59
AP60
AP58
AN60
AL59
AK60
AK58
AJ60
BB58
BB60
BA60
BA59
AY58
AY60
AW60
BP58
AV58
AU60
BN59
AW59
AV60
AU59
AT58
BG60
BF60
BD60
BC60
U25
0
24
27
20
2
0
1
5
3
4
6
7
9
8
10
11
14
12
13
15
16
18
17
19
21
25
23
22
26
28
30
29
2
0
31
1
5
3
4
6
7
8
9
10
11
14
12
13
15
18
17
16
21
19
20
23
24
22
25
26
27
28
30
29
2
1
0
31
4
3
5
6
7
3
2
0
1
6
4
5
7
0
1
2
3
0
1
2
3
5
4
6
7
9
8
4
5
6
7
8
1
0
2
3
9
1
2
3
4
5
6
7
8
4
5
6
7
8
9
1
9
0
2
3
4
5
6
1
0
3
2
4
5
6
4/40
TEST39D
MD1_CLK_L
MD1_CLK_H
MD0_CLK_L
MD0_CLK_H
MDB_DQS_H9
MDB_CA3
MDB_PAR
MDA_PAR
MDA1_RSP_L
MDA_DATA2
MDA_DATA17
MDA_DATA28
MDA_DQS_H0
MDA_DQS_L4
MDB_CHECK2
MDB_DATA1
MDB_DATA11
MDB_DATA22
MDA0_RSP_L
MDA_CHECK7
MDA_DATA1
MDA_DATA16
MDA_DATA27
MDA_DQS_L3
MDB_CHECK1
MDB_DATA0
MDB_DATA10
MDB_DATA21
MDA_CHECK6
MDA_DATA0
MDA_DATA15
MDA_DATA26
MDA_DQS_L2
MDB1_CS_L1
MDB_CHECK0
MDB_DATA20
MDB_DATA31
MDA_CHECK5
MDA_DATA14
MDA_DATA25
MDA_DQS_L1
MDB0_CS_L1
MDB1_CS_L0
MDB_CA6
MDB_DATA30
MDB_DQS_H8
MDA_CA6
MDA_CHECK4
MDA_DATA13
MDA_DATA24
MDA_DQS_L0
MDB0_CS_L0
MDB_CA5
MDB_DQS_H7
MDA_CA5
MDA_CHECK3
MDA_DATA12
MDA_DATA23
MDB_CA4
MDB_DQS_H6
MDA_CA4
MDA_CHECK2
MDA_DATA11
MDA_DATA22
MDB_DQS_H5
MDB_DQS_L9
MDA_CA3
MDA_CHECK1
MDA_DATA10
MDA_DATA21
MDB_CA2
MDB_DQS_H4
MDB_DQS_L8
MDA1_CS_L1
MDA_CA2
MDA_CHECK0
MDA_DATA20
MDA_DATA31
MDA_DQS_H9
MDB_CA1
MDB_DQS_H3
MDB_DQS_L7
MDA0_CS_L1
MDA1_CS_L0
MDA_CA1
MDA_DATA30
MDA_DQS_H8
MDB_CA0
MDB_DATA9
MDB_DATA19
MDB_DQS_H2
MDB_DQS_L6
MDA0_CS_L0
MDA_CA0
MDA_DATA9
MDA_DQS_H7
MDB_DATA8
MDB_DATA18
MDB_DATA29
MDB_DQS_H1
MDB_DQS_L5
MDA_DATA8
MDA_DQS_H6
MDB1_RSP_L
MDB_DATA7
MDB_DATA17
MDB_DATA28
MDB_DQS_H0
MDB_DQS_L4
MDA_DATA7
MDA_DQS_H5
MDA_DQS_L9
MDB0_RSP_L
MDB_CHECK7
MDB_DATA6
MDB_DATA16
MDB_DATA27
MDB_DQS_L3
MDA_DATA6
MDA_DQS_H4
MDA_DQS_L8
MDB_CHECK6
MDB_DATA5
MDB_DATA15
MDB_DATA26
MDB_DQS_L2
MDA_DATA5
MDA_DQS_H3
MDA_DQS_L7
MDB_CHECK5
MDB_DATA4
MDB_DATA14
MDB_DATA25
MDB_DQS_L1
MDA_DATA4
MDA_DATA19
MDA_DQS_H2
MDA_DQS_L6
MDB_CHECK4
MDB_DATA3
MDB_DATA13
MDB_DATA24
MDB_DQS_L0
MDA_DATA3
MDA_DATA18
MDA_DATA29
MDA_DQS_H1
MDA_DQS_L5
MDB_CHECK3
MDB_DATA2
MDB_DATA12
MDB_DATA23
MD_RESET_L
MD_ALERT_L
CAD NOTE:
SHEETDATE
DEPARTMENT
SIZE
PROJECT DOCUMENT NUMBER REV
REVIEWER
DESIGNER
123
7 3 2 1 6 5 4
E
A
B
C
E
D
C
B
A
7 6 5 4
D
OUT
IN
OUT
IN
OUTOUT
OUT
IN
OUTOUT
OUTOUT
OUT
OUT
BIBI
BIBI
BI
BI
BI
BI
C



Thu Sep 14 16:11:49 2023<NAME_2><NAME_1>MB FABCGT AMDV0214 OF 365TP_M_E_CPU0_SA_TEST39EM_E_CPU0_CLK_DN<0>M_E_CPU0_CLK_DP<0>M_E_CPU0_SB_PARM_E_CPU0_SA_PARM_E_CPU0_SA_RSP<0>M_E_CPU0_SB_CS_N<1>M_E_CPU0_SB_CS_N<0>M_E_CPU0_SA_CS_N<1>M_E_CPU0_SA_CS_N<0>M_E_CPU0_SB_RSP<0>M_E_CPU0_RESET_NM_E_CPU0_ALERT_R_N
SMLFIOSOCKET6096_13568-001
9090909090909090909090909090
90909090
9090
909015M_E_CPU0_ALERT_N1%0402LFM_E_CPU0_SB_CA<6:0>M_E_CPU0_SA_CA<6:0>M_E_CPU0_SA_DQS_DP<9:0>M_E_CPU0_SB_DQS_DP<9:0>M_E_CPU0_SB_DQS_DN<9:0>M_E_CPU0_SA_DQS_DN<9:0>
M_E_CPU0_SA_CB<7:0>M_E_CPU0_SB_CB<7:0>
M_E_CPU0_SA_DQ<31:0>M_E_CPU0_SB_DQ<31:0>R1953 PLACE CLOSE TO CPU < 25MMCPU0 DDR CHE
21R379
BF69
BL71
BW71
DC69
CU69
CL69
CE69
BW69
DC71
CU71
CL71
CE71
BV70
DD69
CV69
CM69
CF69
BY69
DB70
CT70
CK70
CD70
DF69
DE71
DE69
DD70
DB69
DA71
DA69
CY70
CY69
CW71
CW69
CV70
CT69
CR71
CR69
CP70
CP69
CN71
CN69
CM70
CK69
CJ71
CJ69
CH70
CH69
CG71
CG69
CF70
CD69
CC71
CC69
CB70
BV69
BU71
BU69
BT70
CB69
CA71
CA69
BY70
BK70
BK69
BJ69
BJ71
BH70
BH69
BG69
BR71
BM70
BL69
BP70
BN71
BM69
BC69
AM69
AF69
Y69
P69
H69
AM70
AF70
Y70
P70
H70
AN69
AG69
AA69
R69
J69
AL71
AE71
W71
N71
G71
AJ69
AH70
AH69
AG71
AE69
AD70
AD69
AC71
AC69
AB70
AB69
AA71
W69
V70
V69
U71
U69
T70
T69
R71
N69
M70
M69
L71
L69
K70
K69
J71
G69
F70
F69
E71
AR69
AP70
AP69
AN71
AL69
AK70
AK69
AJ71
BB69
BB70
BA71
BA69
AY69
AY70
AW71
BP69
AV69
AU71
BN69
AW69
AV70
AU69
AT69
BG71
BF70
BD70
BC71
U25
6
5
4
2
3
1
0
4
5
6
3
2
1
0
9
8
7
6
5
4
9
7
8
6
5
4
3
2
1
9
0
3
2
0
1
8
7
6
5
4
9
7
8
6
5
3
2
1
0
4
2
3
1
0
7
5
6
3
2
4
0
1
7
6
5
3
4
1
2
31
0
30
29
28
27
26
25
24
22
23
21
20
19
18
17
16
15
13
14
10
11
12
9
8
7
6
4
5
2
1
3
0
31
30
29
28
27
26
24
25
22
23
21
20
19
17
18
16
13
14
15
10
11
12
8
9
7
6
4
5
2
1
3
0
5/40
TEST39E
ME1_CLK_L
ME1_CLK_H
ME0_CLK_L
ME0_CLK_H
MEB_DQS_H9
MEB_PAR
MEA_PAR
MEA_DQS_H3
MEA_DQS_L7
MEB_CHECK5
MEB_DATA14
MEB_DATA25
MEB_DQS_L1
MEA_DATA19
MEA_DQS_H2
MEA_DQS_L6
MEB_CHECK4
MEB_DATA13
MEB_DATA24
MEB_DQS_L0
MEA_DATA18
MEA_DATA29
MEA_DQS_H1
MEA_DQS_L5
MEB_CHECK3
MEB_DATA12
MEB_DATA23
MEA_DATA17
MEA_DATA28
MEA_DQS_H0
MEA_DQS_L4
MEB_CHECK2
MEB_DATA9
MEB_DATA11
MEB_DATA22
MEA0_RSP_L
MEA1_RSP_L
MEA_CHECK7
MEA_DATA9
MEA_DATA16
MEA_DATA27
MEA_DQS_L3
MEB_CA6
MEB_CHECK1
MEB_DATA8
MEB_DATA10
MEB_DATA21
MEA_CA6
MEA_CHECK6
MEA_DATA8
MEA_DATA15
MEA_DATA26
MEA_DQS_L2
MEB_CA5
MEB_CHECK0
MEB_DATA7
MEB_DATA20
MEB_DATA31
MEA_CA5
MEA_CHECK5
MEA_DATA7
MEA_DATA14
MEA_DATA25
MEA_DQS_L1
MEB0_CS_L1
MEB1_CS_L1
MEB_CA4
MEB_DATA6
MEB_DATA30
MEB_DQS_H8
MEA_CA4
MEA_CHECK4
MEA_DATA6
MEA_DATA13
MEA_DATA24
MEA_DQS_L0
MEB0_CS_L0
MEB1_CS_L0
MEB_CA3
MEB_DATA5
MEB_DQS_H7
MEA_CA3
MEA_CHECK3
MEA_DATA5
MEA_DATA12
MEA_DATA23
MEB_CA2
MEB_DATA4
MEB_DQS_H6
MEA_CA2
MEA_CHECK2
MEA_DATA4
MEA_DATA11
MEA_DATA22
MEB_CA1
MEB_DATA3
MEB_DQS_H5
MEB_DQS_L9
MEA_CA1
MEA_CHECK1
MEA_DATA3
MEA_DATA10
MEA_DATA21
MEB_CA0
MEB_DATA2
MEB_DQS_H4
MEB_DQS_L8
MEA_CA0
MEA_CHECK0
MEA_DATA2
MEA_DATA20
MEA_DATA31
MEA_DQS_H9
MEB_DATA1
MEB_DQS_H3
MEB_DQS_L7
MEA0_CS_L1
MEA1_CS_L1
MEA_DATA1
MEA_DATA30
MEA_DQS_H8
MEB_DATA0
MEB_DATA19
MEB_DQS_H2
MEB_DQS_L6
MEA0_CS_L0
MEA1_CS_L0
MEA_DATA0
MEA_DQS_H7
MEB_DATA18
MEB_DATA29
MEB_DQS_H1
MEB_DQS_L5
MEA_DQS_H6
MEB_DATA17
MEB_DATA28
MEB_DQS_H0
MEB_DQS_L4
MEA_DQS_H5
MEA_DQS_L9
MEB0_RSP_L
MEB1_RSP_L
MEB_CHECK7
MEB_DATA16
MEB_DATA27
MEB_DQS_L3
MEA_DQS_H4
MEA_DQS_L8
MEB_CHECK6
MEB_DATA15
MEB_DATA26
MEB_DQS_L2
ME_RESET_L
ME_ALERT_L
CAD NOTE:
SHEETDATE
DEPARTMENT
SIZE
PROJECT DOCUMENT NUMBER REV
REVIEWER
DESIGNER
123
7 3 2 1 6 5 4
E
A
B
C
E
D
C
B
A
7 6 5 4
D
IN
IN
IN
OUT
OUTOUT
OUT
OUT
OUTOUT
OUTOUT
OUT
OUT
BIBI
BIBI
BI
BI
BI
BI
C



Thu Sep 14 16:11:49 2023<NAME_2><NAME_1>MB FABCGT AMDV0215 OF 3659191919191919191919191919191
91919191
9191
919115M_F_CPU0_ALERT_R_NM_F_CPU0_ALERT_N1%0402LF
SOCKET6096_13568-001IO
TP_M_F_CPU0_SA_TEST39FM_F_CPU0_SA_CA<6:0>M_F_CPU0_SB_CA<6:0>M_F_CPU0_CLK_DP<0>M_F_CPU0_CLK_DN<0>M_F_CPU0_SA_CS_N<0>M_F_CPU0_SA_CS_N<1>M_F_CPU0_SB_RSP<0>M_F_CPU0_SA_RSP<0>M_F_CPU0_SA_PARM_F_CPU0_SB_CS_N<0>M_F_CPU0_SB_CS_N<1>M_F_CPU0_SB_PARM_F_CPU0_RESET_N
M_F_CPU0_SA_DQS_DP<9:0>M_F_CPU0_SB_DQS_DP<9:0>M_F_CPU0_SB_DQS_DN<9:0>M_F_CPU0_SA_DQS_DN<9:0>
M_F_CPU0_SB_CB<7:0>M_F_CPU0_SA_CB<7:0>
M_F_CPU0_SA_DQ<31:0>M_F_CPU0_SB_DQ<31:0>R1954 PLACE CLOSE TO CPU < 25MMCPU0 DDR CHF
SMLF
21R380
BF65
BL67
BW67
DC66
CU66
CL66
CE66
BW66
DC67
CU67
CL67
CE67
BV67
DD65
CV65
CM65
CF65
BY65
DB67
CT67
CK67
CD67
DF67
DE67
DE66
DD67
DB65
DA67
DA66
CY67
CY65
CW67
CW66
CV67
CT65
CR67
CR66
CP67
CP65
CN67
CN66
CM67
CK65
CJ67
CJ66
CH67
CH65
CG67
CG66
CF67
CD65
CC67
CC66
CB67
BV65
BU67
BU66
BT67
CB65
CA67
CA66
BY67
BK67
BK65
BJ66
BJ67
BH67
BH65
BG66
BR67
BM67
BL66
BP67
BN67
BM65
BC66
AM65
AF65
Y65
P65
H65
AM67
AF67
Y67
P67
H67
AN66
AG66
AA66
R66
J66
AL67
AE67
W67
N67
G67
AJ66
AH67
AH65
AG67
AE66
AD67
AD65
AC67
AC66
AB67
AB65
AA67
W66
V67
V65
U67
U66
T67
T65
R67
N66
M67
M65
L67
L66
K67
K65
J67
G66
F67
F65
E67
AR66
AP67
AP65
AN67
AL66
AK67
AK65
AJ67
BB65
BB67
BA67
BA66
AY65
AY67
AW67
BP65
AV65
AU67
BN66
AW66
AV67
AU66
AT65
BG67
BF67
BD67
BC67
U25
5
6
4
3
2
1
0
6
5
4
3
2
1
0
8
9
9
7
6
5
4
3
8
7
6
5
4
2
1
0
9
3
2
1
0
9
7
8
6
5
4
3
8
7
6
5
4
2
1
0
3
2
1
0
6
7
3
4
5
1
2
0
7
4
5
6
3
2
0
1
31
30
27
28
29
26
25
23
24
21
22
18
19
20
17
16
15
14
11
12
13
9
10
7
8
5
6
2
3
4
0
1
30
31
27
28
29
26
25
24
23
21
22
18
19
20
16
17
14
15
11
12
13
10
9
7
8
5
6
2
3
4
1
0
6/40
TEST39F
MF1_CLK_L
MF1_CLK_H
MF0_CLK_L
MF0_CLK_H
MFB_DQS_H9
MFB_PAR
MFA_PAR
MFA0_CS_L0
MFA_DATA7
MFA_DQS_H7
MFB_DATA6
MFB_DATA18
MFB_DATA29
MFB_DQS_H1
MFB_DQS_L5
MFA_DATA6
MFA_DQS_H6
MFB1_RSP_L
MFB_DATA5
MFB_DATA17
MFB_DATA28
MFB_DQS_H0
MFB_DQS_L4
MFA_DATA5
MFA_DQS_H5
MFA_DQS_L9
MFB0_RSP_L
MFB_CHECK7
MFB_DATA4
MFB_DATA16
MFB_DATA27
MFB_DQS_L3
MFA_DATA4
MFA_DQS_H4
MFA_DQS_L8
MFB_CHECK6
MFB_DATA3
MFB_DATA15
MFB_DATA26
MFB_DQS_L2
MFA_DATA3
MFA_DQS_H3
MFA_DQS_L7
MFB_CHECK5
MFB_DATA2
MFB_DATA14
MFB_DATA25
MFB_DQS_L1
MFA_DATA2
MFA_DATA19
MFA_DQS_H2
MFA_DQS_L6
MFB_CA6
MFB_CHECK4
MFB_DATA1
MFB_DATA13
MFB_DATA24
MFB_DQS_L0
MFA_CA6
MFA_DATA1
MFA_DATA18
MFA_DATA29
MFA_DQS_H1
MFA_DQS_L5
MFB_CA5
MFB_CHECK3
MFB_DATA0
MFB_DATA12
MFB_DATA23
MFA1_RSP_L
MFA_CA5
MFA_DATA0
MFA_DATA17
MFA_DATA28
MFA_DQS_H0
MFA_DQS_L4
MFB_CA4
MFB_CHECK2
MFB_DATA11
MFB_DATA22
MFA0_RSP_L
MFA_CA4
MFA_CHECK7
MFA_DATA16
MFA_DATA27
MFA_DQS_L3
MFB_CA3
MFB_CHECK1
MFB_DATA10
MFB_DATA21
MFA_CA3
MFA_CHECK6
MFA_DATA15
MFA_DATA26
MFA_DQS_L2
MFB1_CS_L1
MFB_CA2
MFB_CHECK0
MFB_DATA20
MFB_DATA31
MFA_CA2
MFA_CHECK5
MFA_DATA14
MFA_DATA25
MFA_DQS_L1
MFB0_CS_L1
MFB1_CS_L0
MFB_CA1
MFB_DATA30
MFB_DQS_H8
MFA_CA1
MFA_CHECK4
MFA_DATA13
MFA_DATA24
MFA_DQS_L0
MFB0_CS_L0
MFB_CA0
MFB_DQS_H7
MFA_CA0
MFA_CHECK3
MFA_DATA12
MFA_DATA23
MFB_DQS_H6
MFA_CHECK2
MFA_DATA11
MFA_DATA22
MFB_DQS_H5
MFB_DQS_L9
MFA_CHECK1
MFA_DATA10
MFA_DATA21
MFB_DATA9
MFB_DQS_H4
MFB_DQS_L8
MFA1_CS_L1
MFA_CHECK0
MFA_DATA9
MFA_DATA20
MFA_DATA31
MFA_DQS_H9
MFB_DATA8
MFB_DQS_H3
MFB_DQS_L7
MFA0_CS_L1
MFA1_CS_L0
MFA_DATA8
MFA_DATA30
MFA_DQS_H8
MFB_DATA7
MFB_DATA19
MFB_DQS_H2
MFB_DQS_L6
MF_RESET_L
MF_ALERT_L
CAD NOTE:
SHEETDATE
DEPARTMENT
SIZE
PROJECT DOCUMENT NUMBER REV
REVIEWER
DESIGNER
123
7 3 2 1 6 5 4
E
A
B
C
E
D
C
B
A
7 6 5 4
D
OUT
IN
OUT
OUTOUT
OUT
IN
IN
OUTOUT
OUTOUT
OUT
OUT
BIBI
BIBI
BI
BI
BI
BI
C



Thu Sep 14 16:11:50 2023<NAME_2><NAME_1>MB FABCGT AMDV0216 OF 3659292929292929292929292929292
92929292
9292
929215M_G_CPU0_ALERT_R_NM_G_CPU0_ALERT_N1%0402LF
SOCKET6096_13568-001IO
TP_M_G_CPU0_SA_TEST39GM_G_CPU0_SA_CA<6:0>M_G_CPU0_SB_CA<6:0>M_G_CPU0_CLK_DN<0>M_G_CPU0_CLK_DP<0>M_G_CPU0_SA_CS_N<1>M_G_CPU0_SA_CS_N<0>M_G_CPU0_SA_PARM_G_CPU0_SA_RSP<0>M_G_CPU0_SB_RSP<0>M_G_CPU0_SB_CS_N<0>M_G_CPU0_SB_CS_N<1>M_G_CPU0_SB_PARM_G_CPU0_RESET_N
M_G_CPU0_SA_DQS_DP<9:0>M_G_CPU0_SB_DQS_DP<9:0>M_G_CPU0_SB_DQS_DN<9:0>M_G_CPU0_SA_DQS_DN<9:0>
M_G_CPU0_SA_CB<7:0>M_G_CPU0_SB_CB<7:0>
M_G_CPU0_SA_DQ<31:0>M_G_CPU0_SB_DQ<31:0>
CPU0 DDR CHGR1955 PLACE CLOSE TO CPU < 25MM
SMLF
21R381
BF4
BL3
BW2
DC3
CU3
CL3
CE3
BW3
DC2
CU2
CL2
CE2
BV2
DD4
CV4
CM4
CF4
BY4
DB2
CT2
CK2
CD2
DF2
DE2
DE3
DD2
DB4
DA2
DA3
CY2
CY4
CW2
CW3
CV2
CT4
CR2
CR3
CP2
CP4
CN2
CN3
CM2
CK4
CJ2
CJ3
CH2
CH4
CG2
CG3
CF2
CD4
CC2
CC3
CB2
BV4
BU2
BU3
BT2
CB4
CA2
CA3
BY2
BK2
BK4
BJ3
BJ2
BH2
BH4
BG3
BR2
BM2
BL2
BP2
BN2
BM4
BC3
AM4
AF4
Y4
P4
H4
AM2
AF2
Y2
P2
H2
AN3
AG3
AA3
R3
J3
AL2
AE2
W2
N2
G2
AJ3
AH2
AH4
AG2
AE3
AD2
AD4
AC2
AC3
AB2
AB4
AA2
W3
V2
V4
U2
U3
T2
T4
R2
N3
M2
M4
L2
L3
K2
K4
J2
G3
F2
F4
E2
AR3
AP2
AP4
AN2
AL3
AK2
AK4
AJ2
BB4
BB2
BA2
BA3
AY4
AY2
AW2
BP4
AW3
AV2
BN3
AV4
AU2
AT2
AR2
BG2
BF2
BD2
BC2
U25
6
5
4
3
2
1
0
6
5
4
3
2
1
0
9
8
6
7
5
4
9
8
7
5
6
4
3
2
1
0
9
3
2
1
0
8
7
6
5
4
9
8
7
5
6
3
2
1
0
4
3
2
1
0
7
6
5
4
3
2
1
0
6
7
5
3
4
2
1
31
0
30
29
28
27
26
25
24
23
22
21
20
19
18
17
15
16
14
13
12
10
11
9
8
6
7
5
4
3
2
1
31
0
30
29
28
26
27
25
24
22
23
21
20
19
18
17
16
14
15
13
12
10
11
9
8
6
7
5
4
3
2
1
0
7/40
TEST39G
MG1_CLK_L
MG1_CLK_H
MG0_CLK_L
MG0_CLK_H
MGA_PAR
MGB_DQS_H9
MGB_PAR
MGA_CHECK1
MGA_DATA0
MGA_DATA10
MGA_DATA21
MGB_DATA0
MGB_DQS_H4
MGB_DQS_L8
MGA_CHECK0
MGA_DATA20
MGA_DATA31
MGA_DQS_H9
MGB_DQS_H3
MGB_DQS_L7
MGA0_CS_L1
MGA1_CS_L1
MGA_DATA30
MGA_DQS_H8
MGB_DATA19
MGB_DQS_H2
MGB_DQS_L6
MGA0_CS_L0
MGA1_CS_L0
MGA_DQS_H7
MGB_DATA18
MGB_DATA29
MGB_DQS_H1
MGB_DQS_L5
MGA_DQS_H6
MGB_DATA17
MGB_DATA28
MGB_DQS_H0
MGB_DQS_L4
MGA_DQS_H5
MGA_DQS_L9
MGB0_RSP_L
MGB1_RSP_L
MGB_CHECK7
MGB_DATA16
MGB_DATA27
MGB_DQS_L3
MGA_DQS_H4
MGA_DQS_L8
MGB_CA6
MGB_CHECK6
MGB_DATA15
MGB_DATA26
MGB_DQS_L2
MGA_CA6
MGA_DQS_H3
MGA_DQS_L7
MGB_CA5
MGB_CHECK5
MGB_DATA14
MGB_DATA25
MGB_DQS_L1
MGA_CA5
MGA_DATA9
MGA_DATA19
MGA_DQS_H2
MGA_DQS_L6
MGB_CA4
MGB_CHECK4
MGB_DATA9
MGB_DATA13
MGB_DATA24
MGB_DQS_L0
MGA_CA4
MGA_DATA8
MGA_DATA18
MGA_DATA29
MGA_DQS_H1
MGA_DQS_L5
MGB_CA3
MGB_CHECK3
MGB_DATA8
MGB_DATA12
MGB_DATA23
MGA_CA3
MGA_DATA7
MGA_DATA17
MGA_DATA28
MGA_DQS_H0
MGA_DQS_L4
MGB_CA2
MGB_CHECK2
MGB_DATA7
MGB_DATA11
MGB_DATA22
MGA0_RSP_L
MGA1_RSP_L
MGA_CA2
MGA_CHECK7
MGA_DATA6
MGA_DATA16
MGA_DATA27
MGA_DQS_L3
MGB_CA1
MGB_CHECK1
MGB_DATA6
MGB_DATA10
MGB_DATA21
MGA_CA1
MGA_CHECK6
MGA_DATA5
MGA_DATA15
MGA_DATA26
MGA_DQS_L2
MGB_CA0
MGB_CHECK0
MGB_DATA5
MGB_DATA20
MGB_DATA31
MGA_CA0
MGA_CHECK5
MGA_DATA4
MGA_DATA14
MGA_DATA25
MGA_DQS_L1
MGB0_CS_L1
MGB1_CS_L1
MGB_DATA4
MGB_DATA30
MGB_DQS_H8
MGA_CHECK4
MGA_DATA3
MGA_DATA13
MGA_DATA24
MGA_DQS_L0
MGB0_CS_L0
MGB1_CS_L0
MGB_DATA3
MGB_DQS_H7
MGA_CHECK3
MGA_DATA2
MGA_DATA12
MGA_DATA23
MGB_DATA2
MGB_DQS_H6
MGA_CHECK2
MGA_DATA1
MGA_DATA11
MGA_DATA22
MGB_DATA1
MGB_DQS_H5
MGB_DQS_L9
MG_RESET_L
MG_ALERT_L
CAD NOTE:
SHEETDATE
DEPARTMENT
SIZE
PROJECT DOCUMENT NUMBER REV
REVIEWER
DESIGNER
123
7 3 2 1 6 5 4
E
A
B
C
E
D
C
B
A
7 6 5 4
D
IN
OUT
OUT
OUTOUT
IN
IN
OUT
OUTOUT
OUTOUT
OUT
OUT
BIBI
BIBI
BI
BI
BI
BI
C



Thu Sep 14 16:11:50 2023<NAME_2><NAME_1>MB FABCGT AMDV0217 OF 3659393939393939393939393939393
93939393
9393
939315M_H_CPU0_ALERT_R_NM_H_CPU0_ALERT_N1%0402LF
SOCKET6096_13568-001IO
TP_M_H_CPU0_SA_TEST39HM_H_CPU0_SA_CA<6:0>M_H_CPU0_SB_CA<6:0>M_H_CPU0_CLK_DP<0>M_H_CPU0_CLK_DN<0>M_H_CPU0_SA_CS_N<0>M_H_CPU0_SA_CS_N<1>M_H_CPU0_SA_RSP<0>M_H_CPU0_SA_PARM_H_CPU0_SB_CS_N<1>M_H_CPU0_SB_CS_N<0>M_H_CPU0_SB_RSP<0>M_H_CPU0_SB_PARM_H_CPU0_RESET_N
M_H_CPU0_SA_DQS_DP<9:0>M_H_CPU0_SB_DQS_DP<9:0>M_H_CPU0_SB_DQS_DN<9:0>M_H_CPU0_SA_DQS_DN<9:0>
M_H_CPU0_SB_CB<7:0>M_H_CPU0_SA_CB<7:0>
M_H_CPU0_SA_DQ<31:0>M_H_CPU0_SB_DQ<31:0>R1947 PLACE CLOSE TO CPU < 25MMCPU0 DDR CHH
SMLF
21R382
BF14
BL14
BW12
DC14
CU14
CL14
CE14
BW14
DC12
CU12
CL12
CE12
BV13
DD14
CV14
CM14
CF14
BY14
DB13
CT13
CK13
CD13
DF14
DE12
DE14
DD13
DB14
DA12
DA14
CY13
CY14
CW12
CW14
CV13
CT14
CR12
CR14
CP13
CP14
CN12
CN14
CM13
CK14
CJ12
CJ14
CH13
CH14
CG12
CG14
CF13
CD14
CC12
CC14
CB13
BV14
BU12
BU14
BT13
CB14
CA12
CA14
BY13
BK13
BK14
BJ14
BJ12
BH13
BH14
BG14
BR12
BM13
BL12
BP13
BN12
BM14
BC14
AM14
AF14
Y14
P14
H14
AM13
AF13
Y13
P13
H13
AN14
AG14
AA14
R14
J14
AL12
AE12
W12
N12
G12
AJ14
AH13
AH14
AG12
AE14
AD13
AD14
AC12
AC14
AB13
AB14
AA12
W14
V13
V14
U12
U14
T13
T14
R12
N14
M13
M14
L12
L14
K13
K14
J12
G14
F13
F14
E12
AR14
AP13
AP14
AN12
AL14
AK13
AK14
AJ12
BB14
BB13
BA12
BA14
AY14
AY13
AW12
BP14
AW14
AV13
BN14
AV14
AU12
AU14
AT14
BG12
BF13
BD13
BC12
U25
5
6
4
3
1
0
2
6
5
4
3
2
1
0
9
8
9
7
6
5
4
3
8
7
6
5
4
2
1
0
9
3
2
1
0
9
7
8
6
5
4
8
7
6
3
5
4
2
1
0
3
1
2
0
6
7
5
4
3
2
7
0
1
4
5
6
2
3
31
30
1
0
26
25
29
28
27
24
21
23
22
17
16
20
19
18
11
12
13
14
15
10
7
8
9
5
6
4
3
2
30
31
1
0
26
25
29
28
27
21
22
23
24
16
17
20
19
18
11
12
13
15
14
9
7
8
10
5
6
4
3
2
1
0
8/40
TEST39H
MH1_CLK_L
MH1_CLK_H
MH0_CLK_L
MH0_CLK_H
MHB_PAR
MHA_PAR
MHB_DQS_H9
MHA_CHECK5
MHA_DATA14
MHA_DATA25
MHA_DQS_L1
MHB0_CS_L1
MHB1_CS_L0
MHB_DATA30
MHB_DQS_H8
MHA_CHECK4
MHA_DATA13
MHA_DATA24
MHA_DQS_L0
MHB0_CS_L0
MHB_DQS_H7
MHA_CHECK3
MHA_DATA9
MHA_DATA12
MHA_DATA23
MHB_DATA9
MHB_DQS_H6
MHA_CHECK2
MHA_DATA8
MHA_DATA11
MHA_DATA22
MHB_DATA8
MHB_DQS_H5
MHB_DQS_L9
MHA_CHECK1
MHA_DATA7
MHA_DATA10
MHA_DATA21
MHB_DATA7
MHB_DQS_H4
MHB_DQS_L8
MHA1_CS_L1
MHA_CHECK0
MHA_DATA6
MHA_DATA20
MHA_DATA31
MHA_DQS_H9
MHB_DATA6
MHB_DQS_H3
MHB_DQS_L7
MHA0_CS_L1
MHA1_CS_L0
MHA_DATA5
MHA_DATA30
MHA_DQS_H8
MHB_DATA5
MHB_DATA19
MHB_DQS_H2
MHB_DQS_L6
MHA0_CS_L0
MHA_DATA4
MHA_DQS_H7
MHB_CA6
MHB_DATA4
MHB_DATA18
MHB_DATA29
MHB_DQS_H1
MHB_DQS_L5
MHA_CA6
MHA_DATA3
MHA_DQS_H6
MHB1_RSP_L
MHB_CA5
MHB_DATA3
MHB_DATA17
MHB_DATA28
MHB_DQS_H0
MHB_DQS_L4
MHA_CA5
MHA_DATA2
MHA_DQS_H5
MHA_DQS_L9
MHB0_RSP_L
MHB_CA4
MHB_CHECK7
MHB_DATA2
MHB_DATA16
MHB_DATA27
MHB_DQS_L3
MHA_CA4
MHA_DATA1
MHA_DQS_H4
MHA_DQS_L8
MHB_CA3
MHB_CHECK6
MHB_DATA1
MHB_DATA15
MHB_DATA26
MHB_DQS_L2
MHA_CA3
MHA_DATA0
MHA_DQS_H3
MHA_DQS_L7
MHB_CA2
MHB_CHECK5
MHB_DATA0
MHB_DATA14
MHB_DATA25
MHB_DQS_L1
MHA_CA2
MHA_DATA19
MHA_DQS_H2
MHA_DQS_L6
MHB_CA1
MHB_CHECK4
MHB_DATA13
MHB_DATA24
MHB_DQS_L0
MHA_CA1
MHA_DATA18
MHA_DATA29
MHA_DQS_H1
MHA_DQS_L5
MHB_CA0
MHB_CHECK3
MHB_DATA12
MHB_DATA23
MHA1_RSP_L
MHA_CA0
MHA_DATA17
MHA_DATA28
MHA_DQS_H0
MHA_DQS_L4
MHB_CHECK2
MHB_DATA11
MHB_DATA22
MHA0_RSP_L
MHA_CHECK7
MHA_DATA16
MHA_DATA27
MHA_DQS_L3
MHB_CHECK1
MHB_DATA10
MHB_DATA21
MHA_CHECK6
MHA_DATA15
MHA_DATA26
MHA_DQS_L2
MHB1_CS_L1
MHB_CHECK0
MHB_DATA20
MHB_DATA31
MH_RESET_L
MH_ALERT_L
CAD NOTE:
SHEETDATE
DEPARTMENT
SIZE
PROJECT DOCUMENT NUMBER REV
REVIEWER
DESIGNER
123
7 3 2 1 6 5 4
E
A
B
C
E
D
C
B
A
7 6 5 4
D
OUT
IN
OUT
IN
OUTOUT
OUT
IN
OUTOUT
OUTOUT
OUT
OUT
BIBI
BIBI
BI
BI
BI
BI
C



Thu Sep 14 16:11:50 2023<NAME_2><NAME_1>MB FABCGT AMDV0218 OF 3659494949494949494949494949494
94949494
9494
949415M_I_CPU0_ALERT_R_NM_I_CPU0_ALERT_N1%0402LF
SOCKET6096_13568-001IO
TP_M_I_CPU0_SA_TEST39IM_I_CPU0_SA_CA<6:0>M_I_CPU0_SB_CA<6:0>M_I_CPU0_CLK_DP<0>M_I_CPU0_CLK_DN<0>M_I_CPU0_SA_CS_N<0>M_I_CPU0_SA_CS_N<1>M_I_CPU0_SA_RSP<0>M_I_CPU0_SA_PARM_I_CPU0_SB_CS_N<0>M_I_CPU0_SB_CS_N<1>M_I_CPU0_SB_RSP<0>M_I_CPU0_SB_PARM_I_CPU0_RESET_N
M_I_CPU0_SA_DQS_DP<9:0>M_I_CPU0_SB_DQS_DP<9:0>M_I_CPU0_SB_DQS_DN<9:0>M_I_CPU0_SA_DQS_DN<9:0>
M_I_CPU0_SB_CB<7:0>M_I_CPU0_SA_CB<7:0>
M_I_CPU0_SA_DQ<31:0>M_I_CPU0_SB_DQ<31:0>R1948 PLACE CLOSE TO CPU < 25MMCPU0 DDR CHI
SMLF
21R383
BF21
BL21
BW19
DC21
CU21
CL21
CE21
BW21
DC19
CU19
CL19
CE19
BV20
DD21
CV21
CM21
CF21
BY21
DB20
CT20
CK20
CD20
DF21
DE19
DE21
DD20
DB21
DA19
DA21
CY20
CY21
CW19
CW21
CV20
CT21
CR19
CR21
CP20
CP21
CN19
CN21
CM20
CK21
CJ19
CJ21
CH20
CH21
CG19
CG21
CF20
CD21
CC19
CC21
CB20
BV21
BU19
BU21
BT20
CB21
CA19
CA21
BY20
BK20
BK21
BJ21
BJ19
BH20
BH21
BG21
BR19
BM20
BL19
BP20
BN19
BM21
BC21
AM21
AF21
Y21
P21
H21
AM20
AF20
Y20
P20
H20
AN21
AG21
AA21
R21
J21
AL19
AE19
W19
N19
G19
AJ21
AH20
AH21
AG19
AE21
AD20
AD21
AC19
AC21
AB20
AB21
AA19
W21
V20
V21
U19
U21
T20
T21
R19
N21
M20
M21
L19
L21
K20
K21
J19
G21
F20
F21
E19
AR21
AP20
AP21
AN19
AL21
AK20
AK21
AJ19
BB21
BB20
BA19
BA21
AY21
AY20
AW19
BP21
AW21
AV20
BN21
AV21
AU19
AU21
AT21
BG19
BF20
BD20
BC19
U25
5
6
4
3
2
0
1
5
6
3
4
2
1
0
9
8
9
7
6
4
5
3
2
1
9
0
8
7
6
5
4
3
2
1
0
9
8
7
6
5
3
4
2
1
0
8
7
6
5
4
3
2
1
0
6
7
5
4
3
1
2
7
0
4
5
6
2
3
0
1
31
30
27
28
29
26
25
24
23
21
22
20
19
18
17
16
14
15
13
12
11
10
9
8
7
6
5
3
2
4
1
0
31
30
27
28
29
25
26
24
23
21
22
18
19
20
17
16
15
14
11
12
13
9
10
7
8
5
6
2
3
4
1
0
9/40
TEST39I
MIA_DATA5
MIA_DATA17
MIA_DATA28
MIA_DQS_H0
MIA_DQS_L4
MIB_CHECK2
MIB_DATA5
MIB_DATA11
MIB_DATA22
MI_ALERT_L
MIA0_RSP_L
MIA1_RSP_L
MIA_CHECK7
MIA_DATA4
MIA_DATA16
MIA_DATA27
MIA_DQS_L3
MIB_CHECK1
MIB_DATA4
MIB_DATA10
MIB_DATA21
MIB_PAR
MIA_CHECK6
MIA_DATA3
MIA_DATA15
MIA_DATA26
MIA_DQS_L2
MIA_PAR
MIB1_CS_L1
MIB_CHECK0
MIB_DATA3
MIB_DATA20
MIB_DATA31
MIB_DQS_H9
MIA_CHECK5
MIA_DATA2
MIA_DATA14
MIA_DATA25
MIA_DQS_L1
MIB0_CS_L1
MIB1_CS_L0
MIB_DATA2
MIB_DATA30
MIB_DQS_H8
MIA_CHECK4
MIA_DATA1
MIA_DATA13
MIA_DATA24
MIA_DQS_L0
MIB0_CS_L0
MIB_DATA1
MIB_DQS_H7
MIA_CHECK3
MIA_DATA0
MIA_DATA12
MIA_DATA23
MIB_DATA0
MIB_DQS_H6
MI_RESET_L
MI0_CLK_L
MI1_CLK_L
MIA_CHECK2
MIA_DATA11
MIA_DATA22
MIB_DQS_H5
MIB_DQS_L9
MIA_CHECK1
MIA_DATA10
MIA_DATA21
MIB_DQS_H4
MIB_DQS_L8
MIA_CHECK0
MIA_DATA20
MIA_DATA31
MIA_DQS_H9
MIB_CA6
MIB_DQS_H3
MIB_DQS_L7
MIA0_CS_L1
MIA1_CS_L1
MIA_CA6
MIA_DATA30
MIA_DQS_H8
MIB_CA5
MIB_DATA19
MIB_DQS_H2
MIB_DQS_L6
MI0_CLK_H
MI1_CLK_H
MIA0_CS_L0
MIA1_CS_L0
MIA_CA5
MIA_DQS_H7
MIB_CA4
MIB_DATA18
MIB_DATA29
MIB_DQS_H1
MIB_DQS_L5
MIA_CA4
MIA_DQS_H6
MIB1_RSP_L
MIB_CA3
MIB_DATA17
MIB_DATA28
MIB_DQS_H0
MIB_DQS_L4
MIA_CA3
MIA_DQS_H5
MIA_DQS_L9
MIB0_RSP_L
MIB_CA2
MIB_CHECK7
MIB_DATA16
MIB_DATA27
MIB_DQS_L3
MIA_CA2
MIA_DATA9
MIA_DQS_H4
MIA_DQS_L8
MIB_CA1
MIB_CHECK6
MIB_DATA9
MIB_DATA15
MIB_DATA26
MIB_DQS_L2
MIA_CA1
MIA_DATA8
MIA_DQS_H3
MIA_DQS_L7
MIB_CA0
MIB_CHECK5
MIB_DATA8
MIB_DATA14
MIB_DATA25
MIB_DQS_L1
MIA_CA0
MIA_DATA7
MIA_DATA19
MIA_DQS_H2
MIA_DQS_L6
MIB_CHECK4
MIB_DATA7
MIB_DATA13
MIB_DATA24
MIB_DQS_L0
MIA_DATA6
MIA_DATA18
MIA_DATA29
MIA_DQS_H1
MIA_DQS_L5
MIB_CHECK3
MIB_DATA6
MIB_DATA12
MIB_DATA23
CAD NOTE:
SHEETDATE
DEPARTMENT
SIZE
PROJECT DOCUMENT NUMBER REV
REVIEWER
DESIGNER
123
7 3 2 1 6 5 4
E
A
B
C
E
D
C
B
A
7 6 5 4
D
OUT
IN
OUT
IN
OUTOUT
OUT
IN
OUTOUT
OUTOUT
OUT
OUT
BIBI
BIBI
BI
BI
BI
BI
C



Thu Sep 14 16:11:50 2023<NAME_2><NAME_1>MB FABCGT AMDV0219 OF 3659595959595959595959595959595
95959595
9595
959515M_J_CPU0_ALERT_R_NM_J_CPU0_ALERT_N1%0402LF
SOCKET6096_13568-001IO
TP_M_J_CPU0_SA_TEST39JM_J_CPU0_SA_CA<6:0>M_J_CPU0_SB_CA<6:0>M_J_CPU0_CLK_DP<0>M_J_CPU0_CLK_DN<0>M_J_CPU0_SA_CS_N<0>M_J_CPU0_SA_PARM_J_CPU0_SA_CS_N<1>M_J_CPU0_SA_RSP<0>M_J_CPU0_SB_CS_N<0>M_J_CPU0_SB_CS_N<1>M_J_CPU0_SB_RSP<0>M_J_CPU0_SB_PARM_J_CPU0_RESET_N
M_J_CPU0_SA_DQS_DP<9:0>M_J_CPU0_SB_DQS_DP<9:0>M_J_CPU0_SB_DQS_DN<9:0>M_J_CPU0_SA_DQS_DN<9:0>
M_J_CPU0_SB_CB<7:0>M_J_CPU0_SA_CB<7:0>
M_J_CPU0_SA_DQ<31:0>M_J_CPU0_SB_DQ<31:0>R1949 PLACE CLOSE TO CPU < 25MMCPU0 DDR CHJ
SMLF
21R384
BF18
BL17
BW16
DC17
CU17
CL17
CE17
BW17
DC16
CU16
CL16
CE16
BV16
DD18
CV18
CM18
CF18
BY18
DB16
CT16
CK16
CD16
DF16
DE16
DE17
DD16
DB18
DA16
DA17
CY16
CY18
CW16
CW17
CV16
CT18
CR16
CR17
CP16
CP18
CN16
CN17
CM16
CK18
CJ16
CJ17
CH16
CH18
CG16
CG17
CF16
CD18
CC16
CC17
CB16
BV18
BU16
BU17
BT16
CB18
CA16
CA17
BY16
BK16
BK18
BJ17
BJ16
BH16
BH18
BG17
BR16
BM16
BL16
BP16
BN16
BM18
BC17
AM18
AF18
Y18
P18
H18
AM16
AF16
Y16
P16
H16
AN17
AG17
AA17
R17
J17
AL16
AE16
W16
N16
G16
AJ17
AH16
AH18
AG16
AE17
AD16
AD18
AC16
AC17
AB16
AB18
AA16
W17
V16
V18
U16
U17
T16
T18
R16
N17
M16
M18
L16
L17
K16
K18
J16
G17
F16
F18
E16
AR17
AP16
AP18
AN16
AL17
AK16
AK18
AJ16
BB18
BB16
BA16
BA17
AY18
AY16
AW16
BP18
AW17
AV16
BN17
AV18
AU16
AU17
AT18
BG16
BF16
BD16
BC16
U25
3
4
6
5
6
0
2
1
5
4
1
2
3
9
0
9
6
7
8
4
5
8
7
6
3
5
4
2
1
9
0
3
2
1
9
0
7
6
8
4
5
8
7
6
5
4
1
2
3
0
3
2
0
1
7
6
5
4
2
1
3
0
7
5
6
4
3
2
1
0
31
30
29
28
27
26
25
24
21
22
23
19
20
18
16
17
14
15
12
13
11
10
9
8
5
6
7
4
3
2
1
0
30
31
29
28
25
26
27
24
23
21
22
20
19
17
16
18
15
14
13
12
11
10
9
8
7
5
6
4
3
1
0
2
10/40
TEST39J
MJB_DATA7
MJB_DATA6
MJB_DATA5
MJB_DQS_H5
MJB_DQS_L4
MJB_DQS_L0
MJA_DATA31
MJB_DATA0
MJB_DATA3
MJB_DATA4
MJA_DQS_H4
MJA_DQS_H8
MJA_DQS_L4
MJA_DQS_L5
MJA_DQS_L7
MJA_DATA22
MJA_CA5
MJA_CA6
MJ0_CLK_H
MJ0_CLK_L
MJ1_CLK_H
MJ1_CLK_L
MJA0_CS_L0
MJA0_CS_L1
MJA0_RSP_L
MJA1_CS_L0
MJA1_CS_L1
MJA1_RSP_L
MJA_CA0
MJA_CA1
MJA_CA2
MJA_CA3
MJA_CA4
MJA_CHECK0
MJA_CHECK1
MJA_CHECK2
MJA_CHECK3
MJA_CHECK4
MJA_CHECK5
MJA_CHECK6
MJA_CHECK7
MJA_DATA0
MJA_DATA1
MJA_DATA2
MJA_DATA3
MJA_DATA4
MJA_DATA5
MJA_DATA6
MJA_DATA7
MJA_DATA8
MJA_DATA9
MJA_DATA10
MJA_DATA11
MJA_DATA12
MJA_DATA13
MJA_DATA14
MJA_DATA15
MJA_DATA16
MJA_DATA17
MJA_DATA18
MJA_DATA19
MJA_DATA20
MJA_DATA21
MJA_DATA23
MJA_DATA24
MJA_DATA25
MJA_DATA26
MJA_DATA27
MJA_DATA28
MJA_DATA29
MJA_DATA30
MJA_DQS_H0
MJA_DQS_H1
MJA_DQS_H2
MJA_DQS_H3
MJA_DQS_H5
MJA_DQS_H6
MJA_DQS_H7
MJA_DQS_H9
MJA_DQS_L0
MJA_DQS_L1
MJA_DQS_L2
MJA_DQS_L3
MJA_DQS_L6
MJA_DQS_L8
MJA_DQS_L9
MJA_PAR
MJB0_CS_L0
MJB0_CS_L1
MJB0_RSP_L
MJB1_CS_L0
MJB1_CS_L1
MJB1_RSP_L
MJB_CA0
MJB_CA1
MJB_CA2
MJB_CA3
MJB_CA4
MJB_CA5
MJB_CA6
MJB_CHECK0
MJB_CHECK1
MJB_CHECK2
MJB_CHECK3
MJB_CHECK4
MJB_CHECK5
MJB_CHECK6
MJB_CHECK7
MJB_DATA1
MJB_DATA2
MJB_DATA8
MJB_DATA9
MJB_DATA10
MJB_DATA11
MJB_DATA12
MJB_DATA13
MJB_DATA14
MJB_DATA15
MJB_DATA16
MJB_DATA17
MJB_DATA18
MJB_DATA19
MJB_DATA20
MJB_DATA21
MJB_DATA22
MJB_DATA23
MJB_DATA24
MJB_DATA25
MJB_DATA26
MJB_DATA27
MJB_DATA28
MJB_DATA29
MJB_DATA30
MJB_DATA31
MJB_DQS_H0
MJB_DQS_H1
MJB_DQS_H2
MJB_DQS_H3
MJB_DQS_H4
MJB_DQS_H6
MJB_DQS_H7
MJB_DQS_H8
MJB_DQS_H9
MJB_DQS_L1
MJB_DQS_L2
MJB_DQS_L3
MJB_DQS_L5
MJB_DQS_L6
MJB_DQS_L7
MJB_DQS_L8
MJB_DQS_L9
MJB_PAR
MJ_ALERT_L
MJ_RESET_L
CAD NOTE:
SHEETDATE
DEPARTMENT
SIZE
PROJECT DOCUMENT NUMBER REV
REVIEWER
DESIGNER
123
7 3 2 1 6 5 4
E
A
B
C
E
D
C
B
A
7 6 5 4
D
OUT
IN
OUT
IN
OUTOUT
IN
OUT
OUT
OUT
OUTOUT
OUT
OUT
BIBI
BIBI
BI
BI
BI
BI
C



Thu Sep 14 16:11:51 2023<NAME_2><NAME_1>MB FABCGT AMDV0220 OF 3659696969696969696969696969696
96969696
9696
969615M_K_CPU0_ALERT_R_NM_K_CPU0_ALERT_N1%0402LF
SOCKET6096_13568-001IO
TP_M_K_CPU0_SA_TEST39KM_K_CPU0_SA_CA<6:0>M_K_CPU0_SB_CA<6:0>M_K_CPU0_CLK_DP<0>M_K_CPU0_CLK_DN<0>M_K_CPU0_SA_CS_N<0>M_K_CPU0_SA_RSP<0>M_K_CPU0_SA_CS_N<1>M_K_CPU0_SA_PARM_K_CPU0_SB_CS_N<0>M_K_CPU0_SB_CS_N<1>M_K_CPU0_SB_RSP<0>M_K_CPU0_SB_PARM_K_CPU0_RESET_N
M_K_CPU0_SA_DQS_DP<9:0>M_K_CPU0_SB_DQS_DP<9:0>M_K_CPU0_SB_DQS_DN<9:0>M_K_CPU0_SA_DQS_DN<9:0>
M_K_CPU0_SB_CB<7:0>M_K_CPU0_SA_CB<7:0>
M_K_CPU0_SA_DQ<31:0>M_K_CPU0_SB_DQ<31:0>
CPU0 DDR CHKR1950 PLACE CLOSE TO CPU < 25MM
SMLF
21R385
BF7
BL7
BW5
DC7
CU7
CL7
CE7
BW7
DC5
CU5
CL5
CE5
BV6
DD7
CV7
CM7
CF7
BY7
DB6
CT6
CK6
CD6
DF7
DE5
DE7
DD6
DB7
DA5
DA7
CY6
CY7
CW5
CW7
CV6
CT7
CR5
CR7
CP6
CP7
CN5
CN7
CM6
CK7
CJ5
CJ7
CH6
CH7
CG5
CG7
CF6
CD7
CC5
CC7
CB6
BV7
BU5
BU7
BT6
CB7
CA5
CA7
BY6
BK6
BK7
BJ7
BJ5
BH6
BH7
BG7
BR5
BM6
BL5
BP6
BN5
BM7
BC7
AM7
AF7
Y7
P7
H7
AM6
AF6
Y6
P6
H6
AN7
AG7
AA7
R7
J7
AL5
AE5
W5
N5
G5
AJ7
AH6
AH7
AG5
AE7
AD6
AD7
AC5
AC7
AB6
AB7
AA5
W7
V6
V7
U5
U7
T6
T7
R5
N7
M6
M7
L5
L7
K6
K7
J5
G7
F6
F7
E5
AR7
AP6
AP7
AN5
AL7
AK6
AK7
AJ5
BB7
BB6
BA5
BA7
AY7
AY6
AW5
BP7
AW7
AV6
BN7
AV7
AU5
AU7
AT7
BG5
BF6
BD6
BC5
U25
5
6
4
3
2
1
0
5
6
4
3
2
1
0
9
8
9
7
5
6
4
3
2
1
0
9
8
8
6
7
4
5
3
2
1
9
0
7
6
4
5
3
2
1
0
8
6
7
4
5
3
2
1
0
5
6
7
4
3
0
1
2
7
5
4
6
3
2
1
0
31
30
29
27
28
26
25
24
23
22
20
21
18
19
17
16
13
15
14
11
12
8
9
10
7
4
6
5
3
2
0
1
30
31
29
27
28
26
24
25
23
21
22
20
18
19
16
17
14
15
12
11
13
8
9
10
7
4
6
5
3
2
1
0
36/40
TEST39K
MKA0_CS_L0
MKA_CA0
MKA_DQS_H7
MKB_DATA9
MKB_DATA18
MKB_DATA29
MKB_DQS_H1
MKB_DQS_L5
MKA_DATA9
MKA_DQS_H6
MKB1_RSP_L
MKB_DATA8
MKB_DATA17
MKB_DATA28
MKB_DQS_H0
MKB_DQS_L4
MKA_DATA8
MKA_DQS_H5
MKA_DQS_L9
MKB0_RSP_L
MKB_CHECK7
MKB_DATA7
MKB_DATA16
MKB_DATA27
MKB_DQS_L3
MKA_DATA7
MKA_DQS_H4
MKA_DQS_L8
MKB_CHECK6
MKB_DATA6
MKB_DATA15
MKB_DATA26
MKB_DQS_L2
MKB_PAR
MKA_DATA6MKA_DQS_H3
MKA_DQS_L7
MKA_PAR
MKB_CHECK5
MKB_DATA5
MKB_DATA14
MKB_DATA25
MKB_DQS_L1
MKA_DATA5
MKA_DATA19
MKA_DQS_H2
MKA_DQS_L6
MKB_CHECK4
MKB_DATA4
MKB_DATA13
MKB_DATA24
MKB_DQS_L0
MKA_DATA4
MKA_DATA18
MKA_DATA29
MKA_DQS_H1
MKA_DQS_L5
MKB_CHECK3
MKB_DATA3
MKB_DATA12
MKB_DATA23
MKA1_RSP_L
MKA_DATA3
MKA_DATA17
MKA_DATA28
MKA_DQS_H0
MKA_DQS_L4
MKB_CHECK2
MKB_DATA2
MKB_DATA11
MKB_DATA22
MK_ALERT_L
MKA0_RSP_L
MKA_CHECK7
MKA_DATA2
MKA_DATA16
MKA_DATA27
MKA_DQS_L3
MKB_CHECK1
MKB_DATA1
MKB_DATA10
MKB_DATA21
MKA_CHECK6
MKA_DATA1
MKA_DATA15
MKA_DATA26
MKA_DQS_L2
MKB1_CS_L1
MKB_CHECK0
MKB_DATA0
MKB_DATA20
MKB_DATA31
MKB_DQS_H9
MK1_CLK_L
MKA_CHECK5
MKA_DATA0
MKA_DATA14
MKA_DATA25
MKA_DQS_L1
MKB0_CS_L1
MKB1_CS_L0
MKB_CA6
MKB_DATA30
MKB_DQS_H8
MK0_CLK_L
MKA_CA6
MKA_CHECK4
MKA_DATA13
MKA_DATA24
MKA_DQS_L0
MKB0_CS_L0
MKB_CA5
MKB_DQS_H7
MKA_CA5
MKA_CHECK3
MKA_DATA12
MKA_DATA23
MKB_CA4
MKB_DQS_H6
MK_RESET_L
MKA_CA4
MKA_CHECK2
MKA_DATA11
MKA_DATA22
MKB_CA3
MKB_DQS_H5
MKB_DQS_L9
MK1_CLK_H
MKA_CA3
MKA_CHECK1
MKA_DATA10
MKA_DATA21
MKB_CA2
MKB_DQS_H4
MKB_DQS_L8
MK0_CLK_H
MKA1_CS_L1
MKA_CA2
MKA_CHECK0
MKA_DATA20
MKA_DATA31
MKA_DQS_H9
MKB_CA1
MKB_DQS_H3
MKB_DQS_L7
MKA0_CS_L1
MKA1_CS_L0
MKA_CA1
MKA_DATA30
MKA_DQS_H8
MKB_CA0
MKB_DATA19
MKB_DQS_H2
MKB_DQS_L6
CAD NOTE:
SHEETDATE
DEPARTMENT
SIZE
PROJECT DOCUMENT NUMBER REV
REVIEWER
DESIGNER
123
7 3 2 1 6 5 4
E
A
B
C
E
D
C
B
A
7 6 5 4
D
OUT
IN
OUT
IN
OUTOUT
OUT
OUT
IN
OUT
OUTOUT
OUT
OUT
BIBI
BIBI
BI
BI
BI
BI
C



Thu Sep 14 16:11:51 2023<NAME_2><NAME_1>MB FABCGT AMDV0221 OF 3659797979797979797979797979797
97979797
9797
979715M_L_CPU0_ALERT_R_NM_L_CPU0_ALERT_N1%0402LFR1982 PLACE CLOSE TO CPU < 25MM
SOCKET6096_13568-001IO
TP_M_L_CPU0_SA_TEST39LM_L_CPU0_SA_CA<6:0>M_L_CPU0_SB_CA<6:0>M_L_CPU0_CLK_DP<0>M_L_CPU0_CLK_DN<0>M_L_CPU0_SA_CS_N<0>M_L_CPU0_SA_PARM_L_CPU0_SA_RSP<0>M_L_CPU0_SA_CS_N<1>M_L_CPU0_SB_CS_N<0>M_L_CPU0_SB_CS_N<1>M_L_CPU0_SB_RSP<0>M_L_CPU0_SB_PARM_L_CPU0_RESET_N
M_L_CPU0_SA_DQS_DP<9:0>M_L_CPU0_SB_DQS_DP<9:0>M_L_CPU0_SB_DQS_DN<9:0>M_L_CPU0_SA_DQS_DN<9:0>
M_L_CPU0_SB_CB<7:0>M_L_CPU0_SA_CB<7:0>
M_L_CPU0_SA_DQ<31:0>M_L_CPU0_SB_DQ<31:0>
CPU0 DDR CHL
SMLF
21R386
BF11
BL10
BW9
DC10
CU10
CL10
CE10
BW10
DC9
CU9
CL9
CE9
BV9
DD11
CV11
CM11
CF11
BY11
DB9
CT9
CK9
CD9
DF9
DE9
DE10
DD9
DB11
DA9
DA10
CY9
CY11
CW9
CW10
CV9
CT11
CR9
CR10
CP9
CP11
CN9
CN10
CM9
CK11
CJ9
CJ10
CH9
CH11
CG9
CG10
CF9
CD11
CC9
CC10
CB9
BV11
BU9
BU10
BT9
CB11
CA9
CA10
BY9
BK9
BK11
BJ10
BJ9
BH9
BH11
BG10
BR9
BM9
BL9
BP9
BN9
BM11
BC10
AM11
AF11
Y11
P11
H11
AM9
AF9
Y9
P9
H9
AN10
AG10
AA10
R10
J10
AL9
AE9
W9
N9
G9
AJ10
AH9
AH11
AG9
AE10
AD9
AD11
AC9
AC10
AB9
AB11
AA9
W10
V9
V11
U9
U10
T9
T11
R9
N10
M9
M11
L9
L10
K9
K11
J9
G10
F9
F11
E9
AR10
AP9
AP11
AN9
AL10
AK9
AK11
AJ9
BB11
BB9
BA9
BA10
AY11
AY9
AW9
BP11
AW10
AV9
BN10
AV11
AU9
AU10
AT11
BG9
BF9
BD9
BC9
U25
6
4
3
5
1
0
6
2
5
4
3
1
2
0
9
9
8
7
6
5
4
3
2
1
9
0
8
7
6
5
4
3
2
1
0
9
8
7
6
4
5
3
2
1
0
8
7
5
6
4
3
2
1
0
5
6
7
4
3
0
1
2
7
5
6
4
3
2
1
0
30
31
29
28
27
26
25
23
22
21
24
20
19
18
17
16
13
15
14
12
11
8
9
10
7
6
5
4
3
2
0
1
30
31
29
28
27
25
26
24
23
21
22
20
19
18
17
16
14
15
12
13
11
8
9
10
7
6
5
4
3
2
0
1
35/40
TEST39L
MLA_CA1
MLA_CHECK1
MLA_DATA4
MLA_DATA10
MLA_DATA21
MLB_CA0
MLB_DATA3
MLB_DQS_H4
MLB_DQS_L8
MLA_CA0
MLA_CHECK0
MLA_DATA3
MLA_DATA20
MLA_DATA31
MLA_DQS_H9
MLB_DATA2
MLB_DQS_H3
MLB_DQS_L7
MLA1_CS_L1
MLA_DATA2
MLA_DATA30
MLA_DQS_H8
MLB_DATA1
MLB_DATA19
MLB_DQS_H2
MLB_DQS_L6
MLA0_CS_L1
MLA1_CS_L0
MLA_DATA1
MLA_DQS_H7
MLB_DATA0
MLB_DATA18
MLB_DATA29
MLB_DQS_H1
MLB_DQS_L5
ML1_CLK_L
MLA0_CS_L0
MLA_DATA0
MLA_DQS_H6
MLB_DATA17
MLB_DATA28
MLB_DQS_H0
MLB_DQS_L4
MLB_PAR
ML0_CLK_L
MLA_DQS_H5
MLA_DQS_L9
MLA_PAR
MLB1_RSP_L
MLB_CHECK7
MLB_DATA16
MLB_DATA27
MLB_DQS_L3
MLA_DQS_H4
MLA_DQS_L8
MLB0_RSP_L
MLB_CHECK6
MLB_DATA15
MLB_DATA26
MLB_DQS_L2
MLA_DQS_H3
MLA_DQS_L7
MLB_CHECK5
MLB_DATA14
MLB_DATA25
MLB_DQS_L1
ML1_CLK_H
MLA_DATA19
MLA_DQS_H2
MLA_DQS_L6
MLB_CHECK4
MLB_DATA13
MLB_DATA24
MLB_DQS_L0
ML0_CLK_H
MLA_DATA18
MLA_DATA29
MLA_DQS_H1
MLA_DQS_L5
MLB_CHECK3
MLB_DATA12
MLB_DATA23
MLA_DATA17
MLA_DATA28
MLA_DQS_H0
MLA_DQS_L4
MLB_CHECK2
MLB_DATA11
MLB_DATA22
ML_ALERT_L
MLA1_RSP_L
MLA_CHECK7
MLA_DATA16
MLA_DATA27
MLA_DQS_L3
MLB_CA6
MLB_CHECK1
MLB_DATA9
MLB_DATA10
MLB_DATA21
MLA0_RSP_L
MLA_CA6
MLA_CHECK6
MLA_DATA9
MLA_DATA15
MLA_DATA26
MLA_DQS_L2
MLB_CA5
MLB_CHECK0
MLB_DATA8
MLB_DATA20
MLB_DATA31
MLB_DQS_H9
MLA_CA5
MLA_CHECK5
MLA_DATA8
MLA_DATA14
MLA_DATA25
MLA_DQS_L1
MLB1_CS_L1
MLB_CA4
MLB_DATA7
MLB_DATA30
MLB_DQS_H8
MLA_CA4
MLA_CHECK4
MLA_DATA7
MLA_DATA13
MLA_DATA24
MLA_DQS_L0
MLB0_CS_L1
MLB1_CS_L0
MLB_CA3
MLB_DATA6
MLB_DQS_H7
MLA_CA3
MLA_CHECK3
MLA_DATA6
MLA_DATA12
MLA_DATA23
MLB0_CS_L0
MLB_CA2
MLB_DATA5
MLB_DQS_H6
ML_RESET_L
MLA_CA2
MLA_CHECK2
MLA_DATA5
MLA_DATA11
MLA_DATA22
MLB_CA1
MLB_DATA4
MLB_DQS_H5
MLB_DQS_L9
CAD NOTE:
SHEETDATE
DEPARTMENT
SIZE
PROJECT DOCUMENT NUMBER REV
REVIEWER
DESIGNER
123
7 3 2 1 6 5 4
E
A
B
C
E
D
C
B
A
7 6 5 4
D
OUT
IN
OUT
IN
OUTOUT
OUT
IN
OUT
OUT
OUTOUT
OUT
OUT
BIBI
BIBI
BI
BI
BI
BI
C



Thu Sep 14 16:11:51 2023<NAME_2><NAME_1>MB FABCGT AMDV0222 OF 365
505050 5050505050SOCKET6096_13568-001SOCKET6096_13568-001IOIOGMI_CPU1_G3_CPU0_G1_TX_DP<15:0>GMI_CPU1_G2_CPU0_G0_TX_DP<15:0>GMI_CPU1_G2_CPU0_G0_TX_DN<15:0>GMI_CPU0_G1_CPU1_G3_TX_DN<15:0>GMI_CPU0_G1_CPU1_G3_TX_DP<15:0>GMI_CPU0_G0_CPU1_G2_TX_DP<15:0>GMI_CPU0_G0_CPU1_G2_TX_DN<15:0>GMI_CPU1_G3_CPU0_G1_TX_DN<15:0>CPU0 PCIE G0/G1
SMLFSMLF
AL52
AJ52
AN52
AL49
AJ49
AN49
AL46
AJ46
AN46
AL43
AJ43
AN43
AK40
AH40
AM40
AP40
AL53
AJ53
AN53
AL50
AJ50
AN50
AL47
AJ47
AN47
AL44
AJ44
AN44
AK41
AH41
AM41
AP41
U53
R53
W53
U50
R50
N50
W50
R47
N47
U47
R44
N44
U44
P41
T41
V41
U52
R52
W52
U49
R49
N49
W49
R46
N46
U46
R43
N43
U43
P40
T40
V40
U25
AE52
AC52
AG52
AE49
AC49
AG49
AE46
AC46
AG46
AE43
AC43
AA43
AG43
AB40
AD40
AF40
AE53
AC53
AG53
AE50
AC50
AG50
AE47
AC47
AG47
AE44
AC44
AA44
AG44
AB41
AD41
AF41
N53
J53
G53
L53
J50
G50
L50
J47
G47
L47
J44
G44
L44
H41
K41
M41
N52
J52
G52
L52
J49
G49
L49
J46
G46
L46
J43
G43
L43
H40
K40
M40
U25
6
14
15
15
13
12
14
13
12
11
10
9
11
10
8
6
7
9
8
7
5
4
6
5
4
3
1
2
3
2
0
1
0
15
14
15
12
13
14
13
12
10
11
11
10
9
7
9
8
8
6
7
4
5
6
4
5
2
3
3
2
1
0
1
0
15
14
13
15
14
12
11
13
12
11
10
9
8
10
9
7
8
7
6
5
4
3
5
3
4
2
1
0
2
1
0
14
15
13
15
14
11
12
13
12
11
9
10
10
9
8
6
7
8
7
6
3
5
4
5
4
3
1
2
2
1
0
0
12/40
G1_RXN7
G1_RXN6
G1_RXN5
G1_RXP7
G1_TXN7
G1_RXN4
G1_RXP6
G1_TXN6
G1_RXN3
G1_RXP5
G1_TXN5
G1_TXP7
G1_RXN2
G1_RXP4
G1_TXN4
G1_TXP6
G1_RXN1
G1_RXP3
G1_TXN3
G1_TXP5
G1_RXN0
G1_RXP2
G1_TXN2
G1_TXP4
G1_RXP1
G1_TXN1
G1_TXP3
G1_RXP0
G1_TXN0
G1_TXP2
G1_TXP1
G1_TXP0
G1_RXN8
G1_RXN9
G1_RXN10
G1_RXN11
G1_RXN12
G1_RXN13
G1_RXN14
G1_RXN15
G1_RXP8
G1_RXP9
G1_RXP10
G1_RXP11
G1_RXP12
G1_RXP13
G1_RXP14
G1_RXP15
G1_TXN8
G1_TXN9
G1_TXN10
G1_TXN11
G1_TXN12
G1_TXN13
G1_TXN14
G1_TXN15
G1_TXP8
G1_TXP9
G1_TXP10
G1_TXP11
G1_TXP12
G1_TXP13
G1_TXP14
G1_TXP15
11/40
G0_TXP15
G0_TXP14
G0_TXP13
G0_TXP12
G0_TXP11
G0_TXP10
G0_TXP9
G0_TXP8
G0_TXP7
G0_TXP6
G0_TXP5
G0_TXP4
G0_TXP3
G0_TXP2
G0_TXP1
G0_TXP0
G0_TXN15
G0_TXN14
G0_TXN13
G0_TXN12
G0_TXN11
G0_TXN10
G0_TXN9
G0_TXN8
G0_TXN7
G0_TXN6
G0_TXN5
G0_TXN4
G0_TXN3
G0_TXN2
G0_TXN1
G0_TXN0
G0_RXP15
G0_RXP14
G0_RXP13
G0_RXP12
G0_RXP11
G0_RXP10
G0_RXP9
G0_RXP8
G0_RXP7
G0_RXP6
G0_RXP5
G0_RXP4
G0_RXP3
G0_RXP2
G0_RXP1
G0_RXP0
G0_RXN15
G0_RXN14
G0_RXN13
G0_RXN12
G0_RXN11
G0_RXN10
G0_RXN9
G0_RXN8
G0_RXN7
G0_RXN6
G0_RXN5
G0_RXN4
G0_RXN3
G0_RXN2
G0_RXN1
G0_RXN0
SHEETDATE
DEPARTMENT
SIZE
PROJECT DOCUMENT NUMBER REV
REVIEWER
DESIGNER
123
7 3 2 1 6 5 4
E
A
B
C
E
D
C
B
A
7 6 5 4
D
ININ OUT OUT
ININ OUTOUT
C



CPU0 G3[15:0] TO OCP SLOT#0Thu Sep 14 16:11:51 2023<NAME_2><NAME_1>MB FABCGT AMDV0223 OF 36565651311314949 4949P5E_CPU0_G3_TX_DN<15:0>P5E_CPU0_G3_TX_DP<15:0>SOCKET6096_13568-001P5E_CPU0_G3_RX_DP<15:0>IOP5E_CPU0_G3_RX_DN<15:0>IOSOCKET6096_13568-001GMI_CPU1_G0_CPU0_G2_TX_DN<15:0>GMI_CPU1_G0_CPU0_G2_TX_DP<15:0> GMI_CPU0_G2_CPU1_G0_TX_DP<15:0>GMI_CPU0_G2_CPU1_G0_TX_DN<15:0>
CPU0 PCIE G2/G3
SMLFSMLF
V35
T35
P35
U32
N32
R32
U29
N29
R29
W26
N26
R26
U26
W23
R23
U23
V36
T36
P36
U33
N33
R33
U30
N30
R30
W27
N27
R27
U27
W24
R24
U24
AP36
AM36
AH36
AK36
AN33
AJ33
AL33
AN30
AJ30
AL30
AN27
AJ27
AL27
AN24
AJ24
AL24
AP35
AM35
AH35
AK35
AN32
AJ32
AL32
AN29
AJ29
AL29
AN26
AJ26
AL26
AN23
AJ23
AL23
U25
M35
K35
H35
L32
G32
J32
L29
G29
J29
L26
G26
J26
L23
G23
J23
N23
M36
K36
H36
L33
G33
J33
L30
G30
J30
L27
G27
J27
L24
G24
J24
N24
AF36
AD36
AB36
AG33
AA33
AC33
AE33
AG30
AC30
AE30
AG27
AC27
AE27
AG24
AC24
AE24
AF35
AD35
AB35
AG32
AA32
AC32
AE32
AG29
AC29
AE29
AG26
AC26
AE26
AG23
AC23
AE23
U25
1
1
3
2
7
6
5
4
3
2
12
0
1
9
11
8
7
14
13
13
4
5
11
3
14
15
12
14
15
13
12
13
10
10
6
9
8
7
5
6
4
2
3
2
0
1
15
15
14
14
12
13
13
11
10
10
11
9
9
8
8
7
0
0
6
5
4
15
15
12
14
11
10
11
12
10
9
8
7
9
8
6
4
5
7
6
5
3
2
4
2
3
1
0
1
0
15
15
13
14
13
14
12
11
10
12
11
10
9
8
8
9
7
6
5
7
6
4
5
4
3
2
3
2
1
0
1
0
14/40
G3_RXN2||SATA22_RXN
G3_TXN9||SATA31_TXN
G3_RXN12||SATA34_RXN
G3_RXN15||SATA37_RXN
G3_TXP5||SATA25_TXP
G3_RXN9||SATA31_RXN
G3_TXP2||SATA22_TXPG3_RXP2||SATA22_RXP
G3_RXP5||SATA25_RXP
G3_RXP14||SATA36_RXP
G3_TXN4||SATA24_TXN
G3_TXN7||SATA27_TXN
G3_TXN10||SATA32_TXN
G3_TXN13||SATA35_TXN
G3_RXP11||SATA33_RXP
G3_TXN1||SATA21_TXN
G3_TXP9||SATA31_TXP
G3_TXP15||SATA37_TXP
G3_RXN1||SATA21_RXN
G3_RXN4||SATA24_RXN
G3_RXN7||SATA27_RXN
G3_TXP12||SATA34_TXP
G3_RXP9||SATA31_RXP
G3_TXP7||SATA27_TXP
G3_TXN8||SATA30_TXN
G3_RXN11||SATA33_RXN
G3_RXN14||SATA36_RXN
G3_TXP1||SATA21_TXP
G3_TXP4||SATA24_TXP
G3_RXP7||SATA27_RXP
G3_RXN8||SATA30_RXN
G3_TXN12||SATA34_TXN
G3_TXN15||SATA37_TXN
G3_RXP1||SATA21_RXP
G3_RXP4||SATA24_RXP
G3_RXP10||SATA32_RXP
G3_RXP13||SATA35_RXP
G3_TXN3||SATA23_TXN
G3_TXN6||SATA26_TXNG3_RXN6||SATA26_RXN
G3_TXN0||SATA20_TXN
G3_TXP8||SATA30_TXP
G3_TXP14||SATA36_TXP
G3_RXN0||SATA20_RXN
G3_RXN3||SATA23_RXN
G3_RXP8||SATA30_RXP
G3_TXP11||SATA33_TXP
G3_RXN13||SATA35_RXN
G3_TXP6||SATA26_TXP
G3_RXN10||SATA32_RXN
G3_TXP0||SATA20_TXP
G3_TXP3||SATA23_TXPG3_RXP3||SATA23_RXP
G3_RXP6||SATA26_RXP
G3_RXP15||SATA37_RXP
G3_TXN5||SATA25_TXN
G3_TXN11||SATA33_TXN
G3_TXN14||SATA36_TXN
G3_RXP0||SATA20_RXP
G3_RXP12||SATA34_RXP
G3_TXN2||SATA22_TXN
G3_RXN5||SATA25_RXN
G3_TXP10||SATA32_TXP
G3_TXP13||SATA35_TXP
13/40
G2_TXP0
G2_RXN7
G2_RXN6
G2_RXN5
G2_RXP7
G2_TXN7
G2_RXN4
G2_RXP6
G2_TXN6
G2_RXN3
G2_RXP5
G2_TXN5
G2_TXP7
G2_RXN2
G2_RXP4
G2_TXN4
G2_TXP6
G2_RXN1
G2_RXP3
G2_TXN3
G2_TXP5
G2_RXN0
G2_RXP2
G2_TXN2
G2_TXP4
G2_RXP1
G2_TXN1
G2_TXP3
G2_RXP0
G2_TXN0
G2_TXP2
G2_TXP1
G2_RXN15
G2_RXP15
G2_RXN13
G2_RXP13
G2_RXN11
G2_RXP11
G2_RXN9
G2_RXP9
G2_RXN14
G2_RXP14
G2_RXN12
G2_RXP12
G2_RXN10
G2_RXP10
G2_RXN8
G2_RXP8
G2_TXN15
G2_TXP15
G2_TXN13
G2_TXP13
G2_TXN11
G2_TXP11
G2_TXN9
G2_TXP9
G2_TXN14
G2_TXP14
G2_TXN12
G2_TXP12
G2_TXN10
G2_TXP10
G2_TXN8
G2_TXP8
SHEETDATE
DEPARTMENT
SIZE
PROJECT DOCUMENT NUMBER REV
REVIEWER
DESIGNER
123
7 3 2 1 6 5 4
E
A
B
C
E
D
C
B
A
7 6 5 4
D
ININ OUT OUT
ININ OUT OUT
C



CPU0 P0[15:0] TO EXAMAX
CPU0 P1[15:0] TO EXAMAXThu Sep 14 16:11:52 2023<NAME_2><NAME_1>MB FABCGT AMDV0224 OF 3656363285285
6363274274
SOCKET6096_13568-001P5E_CPU0_P1_TX_DP<15:0>P5E_CPU0_P1_TX_DN<15:0>P5E_CPU0_P1_RX_DN<15:0>IOP5E_CPU0_P1_RX_DP<15:0>
P5E_CPU0_P0_TX_DN<15:0>P5E_CPU0_P0_TX_DP<15:0>P5E_CPU0_P0_RX_DN<15:0>P5E_CPU0_P0_RX_DP<15:0>SMLFIO
SMLFCPU0 PCIE P0/P1
SOCKET6096_13568-001
CV41
CY41
DB41
CW44
DC44
DA44
CW47
DC47
DA47
CW50
DC50
DA50
CW53
DC53
DA53
CU53
CV40
CY40
DB40
CW43
DC43
DA43
CW46
DC46
DA46
CW49
DC49
DA49
CW52
DC52
DA52
CU52
CD40
CF40
CH40
CC43
CJ43
CG43
CE43
CC46
CG46
CE46
CC49
CG49
CE49
CC52
CG52
CE52
CD41
CF41
CH41
CC44
CJ44
CG44
CE44
CC47
CG47
CE47
CC50
CG50
CE50
CC53
CG53
CE53
U25
CM41
CP41
CT41
CN44
CU44
CR44
CN47
CU47
CR47
CL50
CU50
CR50
CN50
CL53
CR53
CN53
CM40
CP40
CT40
CN43
CU43
CR43
CN46
CU46
CR46
CL49
CU49
CR49
CN49
CL52
CR52
CN52
BT40
BV40
CB40
BY40
BU43
CA43
BW43
BU46
CA46
BW46
BU49
CA49
BW49
BU52
CA52
BW52
BT41
BV41
CB41
BY41
BU44
CA44
BW44
BU47
CA47
BW47
BU50
CA50
BW50
BU53
CA53
BW53
U25
3
2
0
1
0
1
0
0
1
5
1
2
4
6
7
5
4
3
7
6
8
9
11
10
12
10
9
8
13
11
12
13
15
14
14
15
13
15
2
2
3
4
5
6
7
4
5
6
7
8
9
10
11
13
12
8
9
10
11
12
14
15
14
3
13
12
7
5
9
10
6
14
3
2
4
4
15
0
00
1
11
10
7
6
1
14
13
12
11
8
5
3
0
1
1
15
14
13
12
11
10
9
8
7
6
5
4
3
2
2
3
4
5
6
7
8
9
11
10
12
14
13
15 15
2
8
9
16/40
P1_RXN6
P1_RXN5
P1_RXP7
P1_TXN7
P1_RXN4
P1_RXP6
P1_TXN6
P1_RXN3
P1_RXP5
P1_TXN5
P1_TXP7
P1_RXN2
P1_RXP4
P1_TXN4
P1_TXP6
P1_RXN1
P1_RXP3
P1_TXN3
P1_TXP5
P1_RXN0
P1_RXP2
P1_TXN2
P1_TXP4
P1_RXP1
P1_TXN1
P1_TXP3
P1_RXP0
P1_TXN0
P1_TXP2
P1_TXP1
P1_TXP0
P1_RXN7
P1_TXN15
P1_TXP15
P1_TXN14
P1_TXP14
P1_TXN13
P1_TXP13
P1_TXN12
P1_TXP12
P1_TXN11
P1_TXP11
P1_TXN10
P1_TXP10
P1_TXN9
P1_TXP9
P1_TXN8
P1_TXP8
P1_RXN15
P1_RXP15
P1_RXN14
P1_RXP14
P1_RXN13
P1_RXP13
P1_RXN12
P1_RXP12
P1_RXN11
P1_RXP11
P1_RXN10
P1_RXP10
P1_RXN9
P1_RXP9
P1_RXN8
P1_RXP8
15/40
P0_RXP11||SATA13_RXP
P0_TXP12||SATA14_TXP
P0_TXP15||SATA17_TXP
P0_RXN11||SATA13_RXN
P0_RXN14||SATA16_RXN
P0_TXN15||SATA17_TXN
P0_RXP13||SATA15_RXP
P0_TXN9||SATA11_TXN
P0_TXN12||SATA14_TXN
P0_RXP10||SATA12_RXP
P0_RXN9||SATA11_RXN
P0_TXP11||SATA13_TXP
P0_TXP14||SATA16_TXP
P0_RXN10||SATA12_RXN
P0_RXN13||SATA15_RXN
P0_TXP9||SATA11_TXPP0_RXP9||SATA11_RXP
P0_TXN14||SATA16_TXN
P0_RXP12||SATA14_RXP
P0_RXP15||SATA17_RXP
P0_TXN8||SATA10_TXN
P0_TXN11||SATA13_TXN
P0_RXN8||SATA10_RXN
P0_TXP13||SATA15_TXP
P0_TXP10||SATA12_TXP
P0_RXN15||SATA17_RXN
P0_TXP8||SATA10_TXP
P0_RXN12||SATA14_RXN
P0_RXP8||SATA10_RXP
P0_RXP14||SATA16_RXP
P0_TXN10||SATA12_TXN
P0_TXN13||SATA15_TXN
P0_TXP3||SATA03_TXP
P0_TXP6||SATA06_TXP
P0_TXP0||SATA00_TXP
P0_RXP3||SATA03_RXP
P0_RXP6||SATA06_RXP
P0_TXN5||SATA05_TXN
P0_RXP0||SATA00_RXP
P0_TXN2||SATA02_TXNP0_RXN2||SATA02_RXN
P0_RXN5||SATA05_RXN
P0_TXP2||SATA02_TXP
P0_TXP5||SATA05_TXPP0_RXP5||SATA05_RXP
P0_RXP2||SATA02_RXP
P0_TXN1||SATA01_TXN
P0_TXN7||SATA07_TXN
P0_TXN4||SATA04_TXN
P0_RXN7||SATA07_RXN
P0_RXN1||SATA01_RXN
P0_RXN4||SATA04_RXN
P0_TXP7||SATA07_TXP
P0_TXP1||SATA01_TXP
P0_TXP4||SATA04_TXPP0_RXP4||SATA04_RXP
P0_RXP7||SATA07_RXP
P0_TXN6||SATA06_TXN
P0_RXP1||SATA01_RXP
P0_TXN0||SATA00_TXN
P0_TXN3||SATA03_TXNP0_RXN3||SATA03_RXN
P0_RXN6||SATA06_RXN
P0_RXN0||SATA00_RXN
SHEETDATE
DEPARTMENT
SIZE
PROJECT DOCUMENT NUMBER REV
REVIEWER
DESIGNER
123
7 3 2 1 6 5 4
E
A
B
C
E
D
C
B
A
7 6 5 4
D
OUTOUTININ
ININ OUT OUT
C



CPU0 P2[15:0] TO EXAMAXCPU0 P3[15:0] TO EXAMAXThu Sep 14 16:11:52 2023<NAME_2><NAME_1>MB FABCGT AMDV0225 OF 365
64646464307296296307P5E_CPU0_P2_TX_DP<15:0>P5E_CPU0_P2_TX_DN<15:0>P5E_CPU0_P3_TX_DP<15:0>P5E_CPU0_P3_TX_DN<15:0>P5E_CPU0_P3_RX_DP<15:0>SOCKET6096_13568-001IOSMLFSMLF
CPU0 PCIE P2/P3
IOSOCKET6096_13568-001P5E_CPU0_P2_RX_DP<15:0>P5E_CPU0_P2_RX_DN<15:0>P5E_CPU0_P3_RX_DN<15:0>
CE24
CG24
CC24
CE27
CG27
CC27
CE30
CG30
CC30
CE33
CG33
CJ33
CC33
CH36
CF36
CD36
CE23
CG23
CC23
CE26
CG26
CC26
CE29
CG29
CC29
CE32
CG32
CJ32
CC32
CH35
CF35
CD35
CU23
DA23
DC23
CW23
DA26
DC26
CW26
DA29
DC29
CW29
DA32
DC32
CW32
DB35
CY35
CV35
CU24
DA24
DC24
CW24
DA27
DC27
CW27
DA30
DC30
CW30
DA33
DC33
CW33
DB36
CY36
CV36
U25
BW24
CA24
BU24
BW27
CA27
BU27
BW30
CA30
BU30
BW33
CA33
BU33
BY36
CB36
BV36
BT36
BW23
CA23
BU23
BW26
CA26
BU26
BW29
CA29
BU29
BW32
CA32
BU32
BY35
CB35
BV35
BT35
CN23
CR23
CL23
CN26
CR26
CU26
CL26
CR29
CU29
CN29
CR32
CU32
CN32
CT35
CP35
CM35
CN24
CR24
CL24
CN27
CR27
CU27
CL27
CR30
CU30
CN30
CR33
CU33
CN33
CT36
CP36
CM36
U25
4
1
0
2
0
1
3
4
5
6
7
3
2
4
5
6
7
8
9
10
11
12
8
9
10
11
12
13
15
14
13
14
15
0
1
1
0
2
3
2
5
7
6
3
4
6
5
7
9
8
10
12
11
8
10
9
11
12
14
13
13
14
15
15
2
2
4
3
1
0
4
3
0
1
6
6
12
13
15
8
5
0
1
2
3
6
4
9
7
12
11
10
13
14
15
1
2
3
4
6
7
8
9
10
11
12
13
14
15
0
5
7
8
10
9
11
12
14
15
5
7
8
9
10
11
13
14
5
18/40
P3_TXN15
P3_TXP15
P3_TXN14
P3_TXP14
P3_TXN13
P3_TXP13
P3_TXN12
P3_TXP12
P3_TXN11
P3_TXP11
P3_TXN10
P3_TXP10
P3_TXN9
P3_TXP9
P3_TXN8
P3_TXP8
P3_TXN7
P3_TXP7
P3_TXN6
P3_TXP6
P3_TXN5
P3_TXP5
P3_TXN4
P3_TXP4
P3_TXN3
P3_TXP3
P3_TXN2
P3_TXP2
P3_TXN1
P3_TXP1
P3_TXN0
P3_TXP0
P3_RXN15
P3_RXP15
P3_RXN14
P3_RXP14
P3_RXN13
P3_RXP13
P3_RXN12
P3_RXP12
P3_RXN11
P3_RXP11
P3_RXN10
P3_RXP10
P3_RXN9
P3_RXP9
P3_RXN8
P3_RXP8
P3_RXN7
P3_RXP7
P3_RXN6
P3_RXP6
P3_RXN5
P3_RXP5
P3_RXN4
P3_RXP4
P3_RXN3
P3_RXP3
P3_RXN2
P3_RXP2
P3_RXN1
P3_RXP1
P3_RXN0
P3_RXP0
17/40
P2_RXN7
P2_RXN6
P2_RXN5
P2_RXP7
P2_TXN7
P2_RXN4
P2_RXP6
P2_TXN6
P2_RXN3
P2_RXP5
P2_TXN5
P2_TXP7
P2_RXN2
P2_RXP4
P2_TXN4
P2_TXP6
P2_RXN1
P2_RXP3
P2_TXN3
P2_TXP5
P2_RXN0
P2_RXP2
P2_TXN2
P2_TXP4
P2_RXP1
P2_TXN1
P2_TXP3
P2_RXP0
P2_TXN0
P2_TXP2
P2_TXP1
P2_TXP0
P2_TXN15
P2_TXP15
P2_TXN14
P2_TXP14
P2_TXN13
P2_TXP13
P2_TXN12
P2_TXP12
P2_TXN11
P2_TXP11
P2_TXN10
P2_TXP10
P2_TXN9
P2_TXP9
P2_TXN8
P2_TXP8
P2_RXN15
P2_RXP15
P2_RXN14
P2_RXP14
P2_RXN13
P2_RXP13
P2_RXN12
P2_RXP12
P2_RXN11
P2_RXP11
P2_RXN10
P2_RXP10
P2_RXN9
P2_RXP9
P2_RXN8
P2_RXP8
SHEETDATE
DEPARTMENT
SIZE
PROJECT DOCUMENT NUMBER REV
REVIEWER
DESIGNER
123
7 3 2 1 6 5 4
E
A
B
C
E
D
C
B
A
7 6 5 4
D
OUTOUTININ
ININ
OUTOUT
C



CPU0 P4[3:0] TO E1.SCPU0 P5[2] TO SCM CONN
Thu Sep 14 16:11:52 2023<NAME_2><NAME_1>MB FABCGT AMDV0226 OF 365
150150535315015067671451455353P2E_CPU0_P5_TX_C_DNP2E_CPU0_P5_TX_C_DPDIFF BUS_0.22UFC0201WAFL_CPU0_TX0_CPU1_RX1_DPWAFL_CPU0_TX0_CPU1_RX1_DNP2E_CPU0_P5_TX_DP6.3VP2E_CPU0_P5_RX_DNP2E_CPU0_P5_RX_DPP2E_CPU0_P5_TX_DNSMLFSOCKET6096_13568-001IOX6S20%P3E_CPU0_P4_TX_DN<3:0>
CPU0 PCIE P4/P5/WAFL
P3E_CPU0_P4_TX_DP<3:0>P3E_CPU0_P4_RX_DN<3:0>P3E_CPU0_P4_RX_DP<3:0>WAFL_CPU1_TX1_CPU0_RX0_DPWAFL_CPU1_TX1_CPU0_RX0_DN
C47
C50
C48
C51
E46
E49
E47
E50
C41
C44
C42
C45
E40
E43
E41
E44
DE44
DE47
DE50
DE53
DE43
DE46
DE49
DE52
DG45
DG48
DG51
DG54
DG44
DG47
DG50
DG53
U25
21
21
21
21
0
1
3
1
0
2
2
1
2
3
3
2
1
3
0
0
C2078
C2077
19/40
WAFL_TXP1||P5_TXP1
WAFL_TXN1||P5_TXN1
WAFL_TXP0||P5_TXP0
WAFL_TXN0||P5_TXN0
WAFL_RXP1||P5_RXP1
WAFL_RXN1||P5_RXN1
WAFL_RXP0||P5_RXP0
WAFL_RXN0||P5_RXN0
P4_RXN1
P4_RXN0
P4_RXP1
P4_TXN1
P4_RXP0
P4_TXN0
P4_TXP1
P4_TXP0
P5_TXP3
P5_TXP2
P5_TXN3
P5_TXN2
P5_RXP3
P5_RXP2
P5_RXN3
P5_RXN2
P4_TXP3
P4_TXP2
P4_TXN3
P4_TXN2
P4_RXP3
P4_RXP2
P4_RXN3
P4_RXN2
SHEETDATE
DEPARTMENT
SIZE
PROJECT DOCUMENT NUMBER REV
REVIEWER
DESIGNER
123
7 3 2 1 6 5 4
E
A
B
C
E
D
C
B
A
7 6 5 4
D ININ
OUTOUTININ
OUTOUTININ
OUTOUT
C



HIGH: VDDBT_RTC_G POWERED FROM 3.0V SOURCE
CAD NOTE: IF DEPOP R1533, PLEASE POP R536LOW: VDDBT_RTC_G POWERED FROM 1.8 OR 1.5V SOURCEXTRIG_L[7:4] OF THE ASP RESPECTIVELY)XTRIG_L[7:4] OF THE BP ARE CONNECTED TOThu Sep 14 16:11:52 2023<NAME_2><NAME_1>MB FABCGT AMDV0227 OF 365TP_CPU0_TEST5_CCD10TP_CPU0_TEST5_CCD4TP_CPU0_TEST5_CCD3TP_CPU0_TEST5_CCD1172 828282TP_CPU0_TEST6_X3D4TP_CPU0_TEST47_IOD0TP_CPU0_TEST47_CCD3P1V5_BAT
PVDD18_S5_P0PVDD18_S5_P0
PVDD18_S5_P0P3V3_AUX278254 8220020019319327822782 17219320920754 8254 8254 82278217227172272727272716476 1641642782 54 8227821722782172
2727278217227821722782278217282272727272727 82272727278227822782278227822782167278220020719319320920027 8227 8227 8227 8227 8227 8227 82173271732717327
278183818327173271732717327174200161
271741742717327
271732782278220020082 2782 27161271742782 1722782 17216781
193278127 82
1642782172
3333CHIP0402LF1/16W05%CPU0_THERMTRIP_R_N CPU1_THERMTRIP_R_NNA1/16WCPU0_RTC_LDO_SELECT10KEMPTY5%0402LF1/16WCHIP5%0402LF10K0402LFTP_CPU0_TEST47_CCD2EMPTYSVID_PVDDCR_CPU1_P0_SVD_RSVID_PVDDCR_CPU1_P0_SVC_R0SVID_PVDDCR_CPU0_P0_SVD_R SVID_PVDDCR_CPU0_P0_SVDSVID_PVDDCR_CPU0_P0_SVTOSVID_PVDDCR_CPU1_P0_SVC00 CPU0_XTRIG_L4CPU0_XTRIG_L6VSENSE_PVDDCR_SOC_P0_DPVSENSE_PVDD18_S5_P0_DPTP_VSENSE_PVDD33_S5_P0VSENSE_PVDD11_S3_P0_DPUART_CPU0_SCM_UART1_R_TXTP_CPU0_TEST41_IDOCPU1_XTRIG_L7CPU1_XTRIG_L6CPU1_XTRIG_L5CONN10_HBC1051-L300D-8HCPU0_XTRIG_L7CPU0_XTRIG_L5IOCPU0_XTRIG_R1_L7CPU0_BP2CPU0_BP1CPU0_XTRIG_R1_L6SMLFIOCPU0_XTRIG_R1_L5SMLFCPU0_BP0CPU0_BP3CPU0_XTRIG_L6UART_CPU0_UART0_RXUART_CPU0_SCM_UART1_TXUART_CPU0_SCM_UART1_RXTHLFIOCPU0_XTRIG_L4 CPU1_XTRIG_L4CPU0_XTRIG_L5CPU0_XTRIG_L7
SMLF
CPU0 MISC 1/2
APML_CPU0_ALERT_NCPU0_THERMTRIP_NCPU0_XTRIG_L7CPU0_XTRIG_L6CPU0_XTRIG_L4CPU0_XTRIG_L5CPU0_PROCHOT_NCPU0_BP3CPU0_BP2CPU0_BP0CPU0_BP1CPU0_PROCHOT_NCPU0_BP1CPU0_BP0NC_CPU0_AZ_BITCLKCPU0_BP3TP_CPU0_TEST5_CCD2TP_CPU0_TEST6_X3D3TP_CPU0_TEST6_X3D2TP_CPU0_TEST6_X3D1TP_CPU0_TEST6_X3D0TP_CPU0_TEST4_CCD11TP_CPU0_TEST4_CCD9TP_CPU0_TEST4_CCD10TP_CPU0_TEST4_CCD8TP_CPU0_TEST4_CCD6TP_CPU0_TEST5_CCD7TP_CPU0_TEST4_CCD5TP_CPU0_TEST5_CCD6TP_CPU0_TEST4_CCD4TP_CPU0_TEST4_CCD3TP_CPU0_TEST4_CCD2TP_CPU0_TEST4_CCD1TP_CPU0_TEST4_CCD0TP_CPU0_TEST6_X3D5TP_CPU0_TEST5_CCD0TP_CPU0_TEST5_CCD11TP_CPU0_TEST5_CCD9TP_CPU0_TEST4_IODCPU0_SP5R4CPU0_SP5R3CPU0_SP5R2CPU0_SP5R1CPU0_CORETYPE1CPU0_CORETYPE0PRSNT_CPU0_NCPU0_CORETYPE2TP_CPU0_TEST50_IODVSENSE_VSS_SENSE_C_P0VSENSE_PVDDCR_CPU0_P0_DPVSENSE_VSS_SENSE_A_P0VSENSE_PVDD18_S5_P0_DNVSENSE_VSS_SENSE_B_P0CPU0_SP5R4CPU0_SP5R3CPU0_SP5R1CPU0_SP5R2CPU0_CORETYPE2CPU0_CORETYPE1CPU0_CORETYPE0JTAG_CPU0_DBREQ_NJTAG_CPU0_TCKJTAG_CPU0_TMS
IO
NACHIP CHIP
EMPTYEMPTYEMPTYEMPTYEMPTYEMPTY10%10%10%10%10%10%
SOCKET6096_13568-001
0.001UF0.001UF0.001UF0.001UF0.001UF
2.2K2.2K2.2K2.2K2.2K2.2K2.2K2.2K2.2K2.2K2.2K2.2K2.2K2.2K2.2K2.2K2.2K2.2K2.2K2.2K 2.2K
50V50V50V50VC0402C0402C0402C0402C0402C0402
0402LF 0402LFNC_CPU0_AZ_RST_NNC_CPU0_AZ_SDIN0NC_CPU0_AZ_SDIN1NC_CPU0_AZ_SDIN2NC_CPU0_AZ_SDOUTNC_CPU0_AZ_SYNCTP_CPU0_TEST47_CCD1TP_CPU0_TEST47_CCD0 TP_CPU0_TEST6_CCD1CPU0_BP2FM_P0_PCC0_NFM_P0_PCC1_NJTAG_CPU0_TMSJTAG_CPU0_TCKJTAG_CPU0_TRST_NJTAG_CPU0_TDISVID_PVDDCR_CPU1_P0_SVTOSMB_APML_CPU0_SCL
JTAG_CPU0_TDOJTAG_CPU0_TDIJTAG_CPU0_TRST_N
JTAG_CPU0_DBREQ_NCPU0_SA0CPU0_SA1VSENSE_PVDDCR_CPU1_P0_DPVSENSE_PVDDIO_P0_DPNACPU0_SA1CPU0_SA0NA NANA NA
SMB_APML_CPU0_SDA
TP_CPU0_TEST5_IODNATP_CPU0_TEST47_IOD1NA0.001UF50VNA50V
0402LFTP_CPU0_TEST6_CCD0TP_CPU0_TEST5_CCD50JTAG_CPU0_R_TDOJTAG_CPU0_TDO00CPU0_XTRIG_R2_L40CPU0_XTRIG_R2_L5 CPU0_XTRIG_L50CPU0_XTRIG_R2_L7 CPU0_XTRIG_L70CPU0_XTRIG_R2_L60FM_BIOS_USB_RECOVERY_R FM_BIOS_USB_RECOVERY0
SVID_PVDDCR_CPU1_P0_SVD
0
0SVID_PVDDCR_CPU0_P0_SVC_R SVID_PVDDCR_CPU0_P0_SVC00CPU0_XTRIG_L400402LF1KCHIP1/16W1%CHIP1/16W1K1%0402LFCHIP1K1/16W1%1/16W0402LFCHIP1K1%0402LF1KCHIP1/16W1%0402LF1KCHIP1/16W1%
APML_CPU0_ALERT_N APML_CPU0_ALERT_R_NCPU0_THERMTRIP_N CPU0_THERMTRIP_R_NTP_CPU0_TEST6_IODTP_UART_CPU0_UART0_RTS_NTP_CPU0_UART0_INTRUART_CPU0_UART0_R_TX UART_CPU0_UART0_TXCPU0_XTRIG_L6TP_CPU0_TEST5_CCD8TP_CPU0_TEST4_CCD7SCONN8_G802M0083150RD3HRSCONN8_G802M0083150RD3HRTP_CPU0_TEST6_CCD3TP_CPU0_TEST6_CCD2CPU0_XTRIG_R1_L42727
R5056
R5055
TP1 TP10
21 R247
21 R489
2
1 R394
2
1R393
2
1R392
21R397
21R396
21R391
21R389
21R390
21R388
21R387
21R416
21R415
21R414
21R413
21R411
21R410
21R409
21R408
21R417
21R418
21R412
TP2 TP3 TP4 TP5 TP6 TP7 TP8 TP9
21
R1204
21 R356
21 R357
21 R157
21 R156
21 R485
21 R484
21 R481
21 R483
21PR302
21PR303
21PR60
21PR59
2
1 C207
2
1 C208
2
1
R398
2
1
R399
2
1 C209
2
1 C210
2
1
R400
2
1
R401
2
1 C211
2
1
R402
2
1 C212
2
1
R403 21R2318
2 1R405
A65
A66
C65
C66
B73
DJ3
BR54
C3
BR53
B3
DG3
C2
BP53
C74
DH3
DJ32
DH33
DJ34
DG35
DF34
DG34
DJ33
A17
A16
DJ9
B61
D7
B58
E32
CK46
CJ24
B60
W31
CJ53
AA23
CJ52
AA29
CJ29
AA47
AA49
Y46
CJ46
CJ30
AA46
AA24
Y29
CK47
CK29
Y47
AA26
CJ51
CJ25
AA53
Y30
CJ49
CJ27
AA51
AA25
AA28
CJ47
CK30
AA48
AA27
CJ50
CJ26
AA52
AA30
CJ48
CJ28
AA50
C18
C17
B17
DG73
B21
DH72
A22
DJ72
A23
DH10
DH73
C68
C19
DH71
DJ71
DJ56
DJ55
DH8
A69
DG72
C22
C16
B66
D68
B69
C70
A62
A63
C62
C63
D32
A32
A33
D33
C33
A34
C32
A68
U25
2 1R404
1111111111
R1533
87
65
43
21
87
65
43
21
109
87
65
43
21
J5
J48
J212
87
65
43
21
87
65
43
21
10
8
9
7
65
43
21
20/40
CORETYPE2
BP3
BP2
BP1
BP0
TEST41_IOD
TEST47_CCD3
TEST6_CCD0
TEST6_X3D3
TEST6_X3D2
TEST47_IOD1 TEST6_X3D1
TEST47_IOD0 TEST6_X3D0
TEST5_CCD11
TEST4_CCD11
TEST5_CCD10
TEST4_CCD9
TEST4_CCD10
TEST47_CCD2
TEST4_CCD8
TEST5_CCD9
TEST47_CCD1
TEST4_CCD7
TEST50_IOD
TEST5_CCD8
TEST47_CCD0
TEST4_CCD6
TEST5_CCD7
TEST4_CCD5
TEST5_CCD6
TEST4_CCD4
TEST5_CCD5
TEST6_IOD
TEST4_CCD3
TEST5_CCD4
TEST5_IOD
TEST4_CCD2
TEST4_IOD
TEST5_CCD3
TEST4_CCD1
TEST5_CCD2
TEST6_CCD3
TEST4_CCD0
TEST5_CCD1
TEST6_CCD2
TEST6_X3D5
TEST5_CCD0
TEST6_CCD1
TEST6_X3D4
VDDCR_CPU0_SENSE
VDDCR_CPU1_SENSE
VDDCR_SOC_SENSE
VDD_33_S5_SENSE
VDD_18_S5_SENSE
VDD_11_S3_SENSE
VDDIO_SENSE
VSS_SENSE_D
VSS_SENSE_C
VSS_SENSE_B
VSS_SENSE_A
UART1_TXD||AGPIO142
UART1_RXD||AGPIO141
RTC_LDO_SELECT
TCK
SP5R1
AZ_SDIN1||SW_MCLK
AZ_SDIN0||SW_MDATA3
AZ_RST_L||SW_MDATA1
AZ_SDOUT||SW_MDATA2
AZ_SDIN2||SW_MDATA0
UART0_CTS_L||UART2_TXD||AGPIO135
UART0_TXD||AGPIO138
UART0_INTR||AGPIO139
UART0_RTS_L||UART2_RXD||AGPIO137
UART0_RXD||AGPIO136
SVC1
SVT1
SVC0
SVD1
SVT0
SVD0 AZ_SYNC
AZ_BITCLK
PCC1_L
PCC0_L
SP5R4
SP5R3
SP5R2
CORETYPE1
CORETYPE0
SA1
XTRIG_L7
XTRIG_L6
XTRIG_L5
XTRIG_L4
TRST_L
TMS
THERMTRIP_L
TDO
TDI
SID
SIC
SA0
PROCHOT_L
DBREQ_L
CPU_PRESENT_L
ALERT_L
21
2
1
2
1
SHEETDATE
DEPARTMENT
SIZE
PROJECT DOCUMENT NUMBER REV
REVIEWER
DESIGNER
123
7 3 2 1 6 5 4
E
A
B
C
E
D
C
B
A
7 6 5 4
D
ININ
OUTOUT
OUTOUT
OUTOUTOUTOUT
OUTOUT
OUTOUT
OUT
ININ
OUT
OUT
ININ
OUT
OUT
OUT
OUT
OUT
OUT
OUT
OUT
IN
IN
BI
BI
BI
BI
BI
BI
BI
BI
IN OUT
OUT
OUT
OUTOUTOUT
IN
BIBIBI
BI
OUTOUTOUTOUT
OUTOUT
OUTOUT
OUT
OUTOUT
OUTOUT
OUT
OUTOUTOUTOUT
BIBI
OUTIN
INOUT
BIBI
IN
OUTOUTOUTOUT
OUTOUT
OUTOUTOUT
OUTOUT
OUT
OUT IN
IN
INININ
C



Thu Sep 14 16:12:37 2023<NAME_2><NAME_1>MB FABCGT AMDV0228 OF 365EMPTYCPU0 MISC 2/2
FM_BIOS_POST_CMPLT_R_NPVDD18_S5_P0PVDD11_S3_P0
PVDD18_S5_P0PVDD11_S3_P0PVDD18_S5_P01650402LF10M0402LF0.1P50VNPO3.9PC0402NPO50V0.1P3.9PC0402CHIP1%XTAL_CPU0_X48M_X2_R1/16W4.7KCHIPCHIPCPU0_FORCE_SELFREFRESH1512815928159 18214512212218213184131281592828288185288178852881288128818128255 8484161843416681167288228166768484842881288128812828 13113113115013113115076 5528812881
82288228
288128818381832881288115555288185288178 85
82288228288128
282828812881255
2828822815928
555515134348181 5581161288228281668128288128 15928 15984288228822882167288128812881
288128 15928 159131145333333SMB_CPU_5_SCL SMB_CPU_5_R_SCLI3C_1_SPD_DDRGL_CPU0_R_SCLI3C_1_SPD_DDRGL_CPU0_R_SDASMB_CPU0_3_R_SCLSMB_CPU0_3_R_SDA0 CHIP8.2PF0.1PNP0C040250V8.2PF0.1PNP0C040250V1%1/16W0402LF5%1/16WCLK_100M_CPU0_CLK13_DPCLK_100M_CPU0_CLK12_DPCLK_100M_CPU0_CLK11_DNCLK_100M_CPU0_CLK11_DP0402LF5%1/16WCLK_100M_CPU0_CLK13_DN1/16W5%0402LF0402LF0402LF0402LFCLK_100M_CPU0_CLK11_R_DNCLK_100M_CPU0_CLK11_R_DPCLK_100M_CPU0_CLK05_R_DNCLK_100M_CPU0_CLK05_R_DPCLK_100M_CPU0_CLK04_R_DPCLK_100M_CPU0_CLK13_R_DNCLK_100M_CPU0_CLK13_R_DPCLK_100M_CPU0_CLK12_R_DN01/16W5%CLK_100M_CPU0_CLK05_DP1/16WCLK_100M_CPU0_CLK12_R_DP0402LF1/16WFAB_REV_ID005%1/16W000402LF1/16WCLK_100M_CPU0_CLK04_DN00I3C_0_SPD_DDRAF_CPU0_R_SDAMISC49.9XTAL_CPU0_X48M_X2XTAL_CPU0_X48M_X1SMLF48MHZEMPTYRST_CPU0_RESETL_NPWRGD_CPU0_PWROKCPU0_FORCE_SELFREFRESH4.7K4.7KEMPTY4.7KEMPTY4.7KCHIPCPU0_NV_SAVE_NCPU0_SMERR_NRST_CPU0_RSMRST_N4.7K4.7KEMPTY4.7K4.7KEMPTY1KSMLF32.768KHZFAB_REV_ID2FAB_REV_ID1SMB_CPU0_SEC_SCLFM_BOARD_SKU_ID0FM_BIOS_POST_CMPLT_NBIOS_DEBUG_MODEIRQ_SMI_ACTIVE_NBOOT_RDY_HCPU0_ROM_TYPE_SELECTFM_BOARD_SKU_ID3FM_BOARD_SKU_ID2FM_BOARD_SKU_ID4SMB_CPU0_2_R_SCL50V5%CPU0_PWR_BTN_NRST_CPU0_SYS_NCPU0_PWR_GOODXTAL_CPU0_X48M_X1XTAL_CPU0_X48M_X2000402LFCLK_100M_CPU0_CLK04_DPCLK_100M_CPU0_CLK03_DPCLK_100M_CPU0_CLK03_DNCLK_100M_CPU0_CLK01_DPCLK_100M_CPU0_CLK02_DNCLK_100M_CPU0_CLK02_DPCLK_100M_CPU0_CLK01_DNCLK_100M_CPU0_CLK01_R_DN0402LF5%1/16W5%CLK_CPU0_RTCCLKCPU0_PWR_BTN_NRST_CPU0_SYS_N
IRQ_BMC_SMI_NIRQ_TPM_SPI_R_N
CPU0_SMERR_NXTAL_CPU0_X32K_X1RST_CPU0_PERST1_NRST_CPU0_PERST0_NCPU0_FORCE_SELFREFRESHCPU0_NV_SAVE_NIRQ_WAKE_NRST_CPU0_RESETL_NPWRGD_CPU0_PWROKTHLFIO2.2K2.2KRST_SYS PU BY STRAP PIN5%5%01/16W5%01/16W1/16W5%0CHIP1/16W5%1/16W0CHIP00402LF 1/16W05%00IOSOCKET6096_13568-0010402LF
IRQ_SMI_ACTIVE_NFM_SMM_CRASHDUMPCPU0_PWR_GD_OUTCPU0_PWR_GOOD
5%CONN6_HBC1031-L200D-8HXTAL_CPU0_X32K_X2XTAL_CPU0_X32K_X1CPU0_NMI_SYNC_FLOOD_NRST_CPU0_RSMRST_N1000PFX7RXTAL_CPU0_X32K_X2
SMLF
ICFM_INT_CPU0_HP_UBM_NI3C_0_SPD_DDRAF_CPU0_R_SCL
EMPTY4.7KEMPTY4.7KCPU0_SLP_S3_N4.7KEMPTY4.7K 4.7KEMPTY4.7KCHIPCHIP4.7K
4.7K4.7K4.7K4.7K0CLK_100M_REF_OUT_DN CLK_100M_REF_IN_DN0CLK_100M_REF_OUT_DP CLK_100M_REF_IN_DP
00BOOT_RDY_R_H0SMB_CPU_5_R_SDASMB_CPU_5_SDA0SMB_CPU0_4_R_SDASMB_CPU0_4_SDA0SMB_CPU0_4_R_SCLSMB_CPU0_4_SCLFM_PASSWORD_CLEAR_R_N0SMB_CPU0_2_SCLSMB_CPU0_2_R_SDASMB_CPU0_2_SDA0SMB_CPU0_3_SCL0SMB_CPU0_3_SDAEMPTY1K1%1KEMPTY1%1KEMPTY1%1KEMPTY1%
FM_CPU0_SLP_S5_NCPU0_SLP_S5_NFM_CPU0_SLP_S3_NCPU0_SLP_S3_NCPU0_PWR_GD_OUT CPU1_PWR_GD_INSMB_CPU0_SEC_SDA20M0402LF
0402LFCLK_100M_CPU0_CLK02_R_DNCLK_100M_CPU0_CLK02_R_DP330402LFCLK_100M_CPU0_CLK01_R_DP0402LF0402LFCLK_100M_CPU0_CLK03_R_DPCLK_100M_CPU0_CLK03_R_DN4.7K2.2KCPU0_SLP_S5_N4.7KEMPTY4.7K4.7KEMPTYFM_INT_CPU0_HP_UBM_NBOOT_RDY_HCPU0_NMI_SYNC_FLOOD_N4.7KCPU0_SPD_HOST_CTRL_N2.2K1KI3C_0_SPD_DDRAF_CPU0_R_SCLI3C_1_SPD_DDRGL_CPU0_R_SDAFM_BOARD_SKU_ID1IRQ_TPM_SPI_R_NIRQ_BMC_SMI_NFM_SMM_CRASHDUMPFM_PASSWORD_CLEAR_NCPU0_SPD_HOST_CTRL_N0RST_CPU0_SYS_NCPU0_PWR_BTN_N0402
1/16W5%2.2KCHIPI3C_1_SPD_DDRGL_CPU0_R_SCLI3C_0_SPD_DDRAF_CPU0_R_SDACLK_100M_CPU0_CLK05_DN1/16W5%CLK_100M_CPU0_CLK12_DN5%CLK_100M_CPU0_CLK04_R_DN282828
21R6084
21R6083
21R6082
21R6081
2 1 R30
2 1 R29
2 1 R28
2 1 R27
2
1 C5023
DJ16
DJ17
DJ13
DJ14
DJ10
DH6
DJ11
DG4
DJ5
B15
D15
D14
B14
DH9
DG10
B67
A19
A20
D69
DH36
DJ8
DH7
DG36
D18
B64
DJ31
B4
A4
B72
C72
A5
C7
B71
A71
DJ20
DJ21
DH12
DG12
DJ51
DJ50
DJ48
DJ47
DJ53
DJ54
DJ45
DJ44
DJ41
DJ42
B9
C9
B12
C12
A10
A11
B6
C6
A8
A7DJ35
B63
B16
A13
C14
A14
DH15
DH16
DG32
DG31
DF31
DE30
DH30
DJ29
DG11
DE32
DF33
DH4
DE40
DF40
DF36
DE36
U25
21R434
21 R249
21
R432
31
42
Y2
2 1R1205
2 1 R430
2 1 R431
2 1 R213
2 1R940
2 1R939
21R938
R445 R447R446
R5029R5028R5027
21R442
21R441
21R448
21R449
21R450
21R451
21R452
21R207
R444R288R276
R5026R440R287
R581
R582
2
1
R424
2
1
R422
6 5
4 3
2 1
J6
2
1 R423
2
1 R421
21R436
21R435
21
Y3
21 R248
2 1 R212
21R443
2
1 R425
2
1 R420
2121212121212121212121212121
R8305
R8306
21R438
R4304
R4303
R9276
R9275
R4536
R4535
R8565
R8563
R9274
R9273
R2659
R8564
R8566
R2660
C215
21
21
21 R433
R5102
6 5
4 3
2 1
21/40
AGPIO7
NMI_SYNC_FLOOD_L
SEC_SCL||AGPIO262
SEC_SDA||AGPIO263
AGPIO257||SGPIO1_CLK||CLK_REQ01_L
PWROK||SVI_RST_L
AGPIO6||DEVSLP1||SATA_ZP1_L
AGPIO5||DEVSLP0||SATA_ZP0_L
GENINT_L||PM_INTR_L||UBM_CPRSNT_CHANGE_DET_L||AGPIO89
AGPIO22
AGPIO88
AGPIO21
AGPIO87
AGPIO109
AGPIO107
AGPIO106
AGPIO105
AGPIO104
RESET_L
REFCLK100SSC_N||GPP_CLK10N
REFCLK100SSC_P||GPP_CLK10P
SMERR_L||AGPIO24
I2C5_SDA||BMC_SDA||SMBUS1_SDA||AGPIO20
I2C5_SCL||BMC_SCL||SMBUS1_SCL||AGPIO19
I2C4_SDA||HP_SDA||UBM_SDA||AGPIO14
I2C4_SCL||HP_SCL||UBM_SCL||AGPIO13
I3C3_SCL||I2C3_SCL||SPD3_SCL||AGPIO151
I3C1_SDA||I2C1_SDA||SPD1_SDA||AGPIO148
AGPIO116||CLK_REQ12_L
PWRGD_OUT||AGPIO12
AGPIO259||SGPIO3_CLK
I3C0_SCL||I2C0_SCL||SPD0_SCL||SMBUS0_SCL||AGPIO145
I3C2_SCL||I2C2_SCL||SPD2_SCL||AGPIO149
I3C1_SCL||I2C1_SCL||SPD1_SCL||AGPIO147
I3C0_SDA||I2C0_SDA||SPD0_SDA||SMBUS0_SDA||AGPIO146
AGPIO115||CLK_REQ11_L
PCIE_RST0_L||AGPIO266
AGPIO256||SGPIO0_CLK
AGPIO258||SGPIO2_CLK||CLK_REQ02_L
I3C3_SDA||I2C3_SDA||SPD3_SDA||AGPIO152
SGPIO_DATAOUT||AGPIO260
I3C2_SDA||I2C2_SDA||SPD2_SDA||AGPIO150
SGPIO_LOAD||AGPIO261
PCIE_RST1_L||AGPIO26
AGPIO3||SPD_HOST_CTRL_L
AGPIO4||SATA_ACT_L
GPP_CLK11P
GPP_CLK01P
GPP_CLK12P
GPP_CLK02P
GPP_CLK11N
GPP_CLK13P
GPP_CLK01N
GPP_CLK03P
GPP_CLK12N
GPP_CLK14P
GPP_CLK02N
GPP_CLK04P
GPP_CLK13N
GPP_CLK15P
GPP_CLK03N
GPP_CLK05P
GPP_CLK14N
GPP_CLK04N
GPP_CLK15N
GPP_CLK05N
RTCCLK
FORCE_SELFREFRESH
NV_SAVE_L
PWR_BTN_L||AGPIO0
X48M_X2
X48M_X1
X32K_X2
X32K_X1
WAKE_L||AGPIO2
SYS_RESET_L||AGPIO1
SLP_S5_L
SLP_S3_L
RSMRST_L
PWR_GOOD
21
X2
G2G1
X1
2
1
2
1 2
1C216
2
1
2
1
2
1
21 21
21 21
21 21
21
21
21 21
21
21
21
21
DESIGN NOTE:
R6502
SHEETDATE
DEPARTMENT
SIZE
PROJECT DOCUMENT NUMBER REV
REVIEWER
DESIGNER
123
7 3 2 1 6 5 4
E
A
B
C
E
D
C
B
A
7 6 5 4
D
IN
OUTIN
OUT
IN
ININ
OUTBI
BI
OUT
OUT
OUTOUTIN
IN
OUTOUTOUTOUT
OUTOUTOUT
OUTOUT
OUTOUT
OUT
BIININ
ININ
IN
OUTOUT
OUT
OUT
OUT
OUT
OUTOUT
IN
OUTOUT
OUTOUT
OUT
OUT
OUT
OUTOUT
OUT
OUTOUT
OUT
BI
BI
OUT
IN
OUT
OUT
OUT
OUT
OUT
BI
IN
ININ
OUTOUT
IN
IN
IN IN
IN
OUT
IN
ININ
IN
OUT
OUTBI
OUT
BI
OUTOUT
OUTOUT
OUT
OUT
IN
OUT
OUTOUT
OUT
OUT
OUT
C214C213
C



PU AT DC-SCM SIDETBCTO SCM USB CONNTO SCM BMCTO OCP V3_2TBCFROM DC-SCMTO DC-SCMTO OCP SFFCAD NOTE: R462 R1592 CO-LAYCAD NOTE: R472 R1593 CO-LAY
Thu Sep 14 16:11:53 2023<NAME_2><NAME_1>MB FABCGT AMDV0229 OF 365GNDP1V8_AUXPVDD18_S5_P0PVDD18_S5_P0PVDD18_S5_P07681150298115076772915329811502981150291532981150298115029811502981150298115029811508183 29298115029811507777 2918077 1501371371311311801801801801501807777772981150818376770CLK_ESPI_CPU0_CLK1 CLK_ESPI_CPU0_R_CLK10RST_ESPI_CPU0_RSTOUT_NPD_ESPI_CPU0_CLK233SPI_CPU0_TPM_CS_NCPU0_ESPI0_ALERT_NESPI_CPU0_R_ALERT_NESPI_CPU0_R_D2ESPI_CPU0_R_D333EMPTY33ESPI_CPU0_ALERT_P0_NRST_ESPI_CPU0_RSTOUT_NESPI_CPU0_CS1_N5%1/16W0402LFESPI_CPU0_ALERT_P0_NESPI_CPU0_D3ESPI_CPU0_D2ESPI_CPU0_D1ESPI_CPU0_D030K30KCHIPCHIPESPI_CPU0_D3ESPI_CPU0_D233ESPI_CPU0_R_D1SCM_USB_OC_N SCM_USB_OC_BU_R_N SCM_USB_OC_BUF_N25V0.1UF10%0402X7R010K1/16WCHIP5%0402LFSN74LVC1G07DBVRSMLFIC33ESPI_CPU0_D03333ESPI_CPU0_R_D0ESPI_CPU0_D130KEMPTYCHIP30K30KCHIP
SPI_CPU0_CS1_N33EMPTYSMLF
CPU0 SPI/USB
SPI_CPU0_D1SCM_USB_OC_BUF_NSOCKET6096_13568-001USB2_CPU0_P0_DPIO49.91/16W4.7KEMPTY5%0402LF4.7KEMPTYRST_ESPI_CPU0_R_RSTOUT_N3333SPI_CPU0_R_CS0_N333333SPI_CPU0_D3SPI_CPU0_R_TPM_CS_NUSB2_CPU0_P1_DPUSB2_CPU0_P10_DPUSB2_CPU0_P10_DNUSB2_CPU0_P11_DPUSB2_CPU0_P11_DNUSB3_CPU0_BMC_TX_DNUSB3_CPU0_BMC_TX_DPUSB3_CPU0_BMC_RX_HUB_C_DPUSB3_CPU0_BMC_RX_HUB_C_DNUSB2_CPU0_P1_DNUSB2_CPU0_P0_DNSPI_CPU0_D0SPI_CPU0_D2SPI_CPU0_R_D3SPI_CPU0_CS0_NESPI_CPU0_CS1_NRST_CPU0_KBRST_R_N33SPI_CPU0_R_D0SPI_CPU0_R_D1SPI_CPU0_R_D2SPI_CPU0_R_CS1_NNC_CPU0_SPI_CS2_NSPI_CPU0_R_CLKSPI_CPU0_CLK33CPU0_ESPI_CS0_NESPI_CPU0_R_CS1_N
R473
R472
R1593
R1592
R462
21 R475
21 R467
21 R466
21 R465
21 R464
21 R461
21 R460
21 R459
21 R458
21 R1506
21 R1505
21 R1504
21 R1503
2
1
R454
2
1
C30
21
R589
4
5
13
2
U3
21 R474
21 R471
21 R468
21 R469
21 R470
DG58
DH58
DJ62
DH62
DH40
DH60
DJ60
DH69
DJ69
DJ65
DH65
DG40
DJ67
DH67
E30
E29
C29
C28
E24
A28
A29
C25
C26
E27
E26
E23
A26
A25
DH27
DG26
DF30
DE27
DJ26
DJ23
DG28
DF27
DG23
DJ27
DG25
DF25
DE24
DH24
DF24
DG29
DJ28
DG22
DF28
DJ22
DJ25
U25
2
1
R455
2
1
R457
NC
Y
GND
A
VCC
22/40
ESPI_RSTOUT_L||AGPIO23
ESPI_CLK1||SPI_CLK1||AGPIO75
ESPI_CLK2||AGPIO74
ESPI0_ALERT_L||AGPIO108
AGPIO76||SPI_TPM_CS_L
ESPI_CLK0||SPI_CLK0||AGPIO117
ESPI1_ALERT_L||AGPIO110
ESPI_RSTIN_L||KBRST_L||AGPIO129
USB01_OC_L||AGPIO265
SPI_CS1_L||AGPIO119
SPI_CS2_L||AGPIO126
ESPI0_DAT0||SPI0_DAT0||AGPIO120
ESPI0_DAT1||SPI0_DAT1||AGPIO121
ESPI0_DAT2||SPI0_DAT2||AGPIO122
ESPI0_DAT3||SPI0_DAT3||AGPIO123
ESPI1_DAT2||SPI1_DAT2||AGPIO133
ESPI1_DAT3||SPI1_DAT3||AGPIO134
ESPI_CS1_L||AGPIO125
ESPI1_DAT0||SPI1_DAT0||AGPIO131
ESPI1_DAT1||SPI1_DAT1||AGPIO132
SPI_CS0_L||AGPIO118
USB00_OC_L||AGPIO264
ESPI_CS0_L||AGPIO124
USB11_OC_L||AGPIO17
USB10_OC_L||AGPIO16
USB11_TXP
USB11_TXN
USB11_RXP
USB11_RXN
USB11_DP
USB11_DN
USB10_TXP
USB10_TXN
USB10_RXP
USB10_RXN
USB10_DP
USB10_DN
USB01_TXP
USB01_TXN
USB01_RXP
USB01_RXN
USB01_DP
USB01_DN
USB00_TXP
USB00_TXN
USB00_RXP
USB00_RXN
USB00_DP
USB00_DN
21
21
21
21 21
SHEETDATE
DEPARTMENT
SIZE
PROJECT DOCUMENT NUMBER REV
REVIEWER
DESIGNER
123
7 3 2 1 6 5 4
E
A
B
C
E
D
C
B
A
7 6 5 4
D
OUT
BIBI
ININ
OUTOUT
OUT
OUT
OUTOUT
OUT
OUT
OUTIN
IN
BIBI
BIBI
BIBI
OUT
OUTINOUT
BI
BIBI
BI
BIBI
BIBI
IN
OUT
OUTOUT
OUT
OUT
C



Thu Sep 14 16:11:53 2023<NAME_2><NAME_1>MB FABCGT AMDV0230 OF 365
PVDDCR_SOC_P0 PVDDCR_SOC_P0
PVDD_33_S5PVDD18_S5_P0
PVDD11_S3_P0PVDDCR_CPU0_P0PVDDCR_CPU1_P0PVDDCR_CPU1_P0PVDDCR_CPU0_P0
P1V5_BAT
PVDDIO_P0SOCKET6096_13568-001SOCKET6096_13568-001SOCKET6096_13568-001SOCKET6096_13568-001SOCKET6096_13568-001IOIOIO IOIO
CPU0 POWER
SMLFSMLFSMLFSMLFSMLF
Y19
Y12
Y5
V22
U18
U11
U4
P22
P19
P12
P5
L18
L11
L4
K22
H19
H12
H5
E11
E4
C4
BM5
BJ48
BJ11
BJ4
BH48
BH25
BH23
BG48
BG28
BG26
BG24
BG22
BF48
BF27
BF25
BF23
BD48
BD28
BD26
BD24
BD22
BD19
BD12
BD5
BC48
BC27
BC25
BC23
BB49
BB28
BB26
BB24
BB22
BA48
BA27
BA25
BA23
BA18
BA11
BA4
B5
AY49
AY28
AY26
AY24
AY22
AW48
AW27
AW25
AW23
AV47
AV45
AV43
AV41
AV39
AV36
AV34
AV32
AV30
AV28
AV26
AV24
AV22
AV19
AV12
AV5
AU40
AU35
AU31
AU27
AU23
AT22
AR18
AR11
AR4
AM22
AM19
AM12
AM5
AJ18
AJ11
AJ4
AH22
AF19
AF12
AF5
AD22
AC18
AC11
AC4
AA22
U25
DH57
DH56
DH54
DH53
DH51
DH50
DH48
DH47
DH45
DH44
DH42
DH41
DH35
DH34
DH32
DH31
DH29
DH28
DH26
DH25
DH23
DH22
DH20
DH19
DG57
DG19
DE54
DE51
DE48
DE45
DE42
DE41
DE35
DE34
DE31
DE28
DE25
DE22
DD54
DD51
DD48
DD45
DD42
DD34
DD31
DD28
DD25
DD22
DC41
DC40
DC36
DC35
DB53
DB52
DB50
DB49
DB47
DB46
DB44
DB43
DB33
DB32
DB30
DB29
DB27
DB26
DB24
DB23
DA41
DA40
DA36
DA35
CV53
CV52
CV50
CV49
CV47
CV46
CV44
CV43
CV33
CV32
CV30
CV29
CV27
CV26
CV24
CV23
CU41
CU40
CU36
CU35
CP53
CP52
CP50
CP49
CP47
CP46
CP44
CP43
CP33
CP32
CP30
CP29
CP27
CP26
CP24
CP23
CN41
CN40
CN36
CN35
CL47
CL46
CL44
CL43
CL33
CL32
CL30
CL29
CK41
CK40
CK36
CK35
CH53
CH52
CH50
CH49
CH47
CH46
CH44
CH43
CH33
CH32
CH30
CH29
CH27
CH26
CH24
CH23
CG41
CG40
CG36
CG35
CD53
CD52
CD50
CD49
CD47
CD46
CD44
CD43
CD33
CD32
CD30
CD29
CD27
CD26
CD24
CD23
CC41
CC40
CC36
CC35
BY53
BY52
BY50
BY49
BY47
BY46
BY44
BY43
BY33
BY32
BY30
BY29
BY27
BY26
BY24
BY23
BW41
BW40
BW36
BW35
BT53
BT52
BT50
BT49
BT47
BT46
BT44
BT43
BT33
BT32
BT30
BT29
BT27
BT26
BT24
BT23
BR52
BR50
BR48
BR46
BR44
BR42
BR40
BR35
BR33
BR31
BR29
BR27
BR25
BR23
BP49
BP47
BP45
BP43
BP41
BP39
BP36
BP34
BP32
BP30
BP28
BP26
BP24
BN50
BN46
BN42
BN35
BN31
BN27
U25
Y41
Y40
Y36
Y35
W47
W46
W44
W43
W33
W32
W30
W29
U41
U40
U36
U35
T53
T52
T50
T49
T47
T46
T44
T43
T33
T32
T30
T29
T27
T26
T24
T23
N41
N40
N36
N35
M53
M52
M50
M49
M47
M46
M44
M43
M33
M32
M30
M29
M27
M26
M24
M23
J41
J40
J36
J35
H53
H52
H50
H49
H47
H46
H44
H43
H33
H32
H30
H29
H27
H26
H24
H23
G41
G40
G36
G35
F54
F51
F48
F45
F42
F34
F31
F28
F25
F22
E54
E51
E48
E45
E42
E35
E34
E31
E28
E25
E22
D56
D55
C20
B57
B56
B54
B53
B51
B50
B48
B47
B45
B44
B42
B41
B35
B34
B32
B31
B29
B28
B26
B25
B23
B22
B20
B19
AU48
AU46
AU44
AU42
AU33
AU29
AU25
AT49
AT47
AT45
AT43
AT41
AT39
AT36
AT34
AT32
AT30
AT28
AT26
AT24
AR50
AR48
AR46
AR44
AR42
AR40
AR35
AR33
AR31
AR29
AR27
AR25
AR23
AP53
AP52
AP50
AP49
AP47
AP46
AP44
AP43
AP33
AP32
AP30
AP29
AP27
AP26
AP24
AP23
AL41
AL40
AL36
AL35
AK53
AK52
AK50
AK49
AK47
AK46
AK44
AK43
AK33
AK32
AK30
AK29
AK27
AK26
AK24
AK23
AG41
AG40
AG36
AG35
AF53
AF52
AF50
AF49
AF47
AF46
AF44
AF43
AF33
AF32
AF30
AF29
AF27
AF26
AF24
AF23
AC41
AC40
AC36
AC35
AB53
AB52
AB50
AB49
AB47
AB46
AB44
AB43
AB33
AB32
AB30
AB29
AB27
AB26
AB24
AB23
U25
DJ57
B36
D23
DG42
DH14
C59
C23
DF41
DH13
C58
E36
E33
DJ4
DH21
DH17
DG17
D72
D65
D62
D58
D36
D34
D22
D11
D8
D4
C54
C53
C35
C34
C31
BD72
BD69
BD65
BD62
BD58
BD55
BD21
BD18
BD14
BD11
BD7
BD4
B40
A60
A59
A57
A56
A55
A54
A51
A50
A48
A45
A42
A41
A35
A31
U25
Y71
Y64
Y57
V54
U72
U65
U58
P71
P64
P57
P54
L72
L65
L58
K54
H71
H64
H57
DG71
DG64
DE72
DE65
DE58
DB71
DB64
DB57
CY54
CW72
CW65
CW58
CT71
CT64
CT57
CT54
CN72
CN65
CN58
CM54
CK71
CK64
CK57
CJ54
CG72
CG65
CG58
CF54
CD71
CD64
CD57
CB54
CA72
CA65
CA58
BV71
BV64
BV57
BV54
BR72
BR65
BR58
BN54
BM71
BM64
BM57
BM53
BM51
BL54
BL52
BL50
BK53
BK51
BJ72
BJ65
BJ58
BJ54
BJ52
BJ50
BH53
BH51
BG54
BG52
BG50
BF71
BF64
BF57
BF53
BF51
BD54
BD52
BD50
BA72
BA65
BA58
AV71
AV64
AV57
BH27
AR72
AR65
AR58
AM71
AM64
AM57
AM54
AJ72
AJ65
AJ58
AH54
AF71
AF64
AF57
AD54
AC72
AC65
AC58
AA54
BN23
BP51
BN52
BC54
BC52
BB53
BB51
BA54
BA52
BA50
AY53
AY51
AW54
AW52
AW50
AV53
AV51
AV49
AU54
AU52
AU50
AT53
AT51
AR54
AR52
DG5
DE18
DE11
DE4
DB19
DB12
DB5
CY22
CW18
CW11
CW4
CT22
CT19
CT12
CT5
CN18
CN11
CN4
CM22
CK19
CK12
CK5
CJ22
CG18
CG11
CG4
CF22
CD19
CD12
CD5
CB22
CA18
CA11
CA4
BV22
BV19
BV12
BV5
BR18
BR11
BR4
BP22
BN48
BN44
BN40
BN33
BN29
BN25
BM49
BM47
BM45
BM43
BM41
BM39
BM36
BM34
BM32
BM30
BM28
BM26
BM24
BM22
BM19
BM12
BL48
BL27
BL25
BL23
BK49
BK28
BK26
BK24
BK22
BJ27
BJ25
BJ23
BJ18
U25
26/40
VDDCR_SOC_BG22
VDDCR_SOC_BG24
VDDCR_SOC_BG26
VDDCR_SOC_BG28
VDDCR_SOC_BG48
VDDCR_SOC_BH23
VDDCR_SOC_BH25
VDDCR_SOC_BH48
VDDCR_SOC_BJ4
VDDCR_SOC_BJ11
VDDCR_SOC_BJ48
VDDCR_SOC_BM5
VDDCR_SOC_BF48
VDDCR_SOC_BF27
VDDCR_SOC_BF25
VDDCR_SOC_BF23
VDDCR_SOC_BD48
VDDCR_SOC_BD28
VDDCR_SOC_BD26
VDDCR_SOC_BD24
VDDCR_SOC_BD22
VDDCR_SOC_BD19
VDDCR_SOC_BD12
VDDCR_SOC_BD5
VDDCR_SOC_BC48
VDDCR_SOC_BC27
VDDCR_SOC_BC25
VDDCR_SOC_BC23
VDDCR_SOC_BB49
VDDCR_SOC_BB28
VDDCR_SOC_BB26
VDDCR_SOC_BB24
VDDCR_SOC_BB22
VDDCR_SOC_BA48
VDDCR_SOC_BA27
VDDCR_SOC_BA25
VDDCR_SOC_BA23
VDDCR_SOC_BA18
VDDCR_SOC_BA11
VDDCR_SOC_BA4
VDDCR_SOC_AY49
VDDCR_SOC_AY28
VDDCR_SOC_AY26
VDDCR_SOC_AY24
VDDCR_SOC_AY22
VDDCR_SOC_AW48
VDDCR_SOC_AW27
VDDCR_SOC_AW25
VDDCR_SOC_AW23
VDDCR_SOC_AV47
VDDCR_SOC_AV45
VDDCR_SOC_AV43
VDDCR_SOC_AV41
VDDCR_SOC_AV39
VDDCR_SOC_AV36
VDDCR_SOC_AV34
VDDCR_SOC_AV32
VDDCR_SOC_AV30
VDDCR_SOC_AV28
VDDCR_SOC_AV26
VDDCR_SOC_AV24
VDDCR_SOC_AV22
VDDCR_SOC_AV19
VDDCR_SOC_AV12
VDDCR_SOC_AV5
VDDCR_SOC_AU40
VDDCR_SOC_AU35
VDDCR_SOC_AU31
VDDCR_SOC_AU27
VDDCR_SOC_AU23
VDDCR_SOC_AT22
VDDCR_SOC_AR18
VDDCR_SOC_AR11
VDDCR_SOC_AR4
VDDCR_SOC_AM22
VDDCR_SOC_AM19
VDDCR_SOC_AM12
VDDCR_SOC_AM5
VDDCR_SOC_AJ18
VDDCR_SOC_AJ11
VDDCR_SOC_AJ4
VDDCR_SOC_AH22
VDDCR_SOC_AF19
VDDCR_SOC_AF12
VDDCR_SOC_AF5
VDDCR_SOC_AD22
VDDCR_SOC_AC18
VDDCR_SOC_AC11
VDDCR_SOC_AC4
VDDCR_SOC_AA22
VDDCR_SOC_Y19
VDDCR_SOC_Y12
VDDCR_SOC_Y5
VDDCR_SOC_V22
VDDCR_SOC_U18
VDDCR_SOC_U11
VDDCR_SOC_U4
VDDCR_SOC_P22
VDDCR_SOC_P19
VDDCR_SOC_P12
VDDCR_SOC_P5
VDDCR_SOC_L18
VDDCR_SOC_L11
VDDCR_SOC_L4
VDDCR_SOC_K22
VDDCR_SOC_H19
VDDCR_SOC_H12
VDDCR_SOC_H5
VDDCR_SOC_E11
VDDCR_SOC_E4
VDDCR_SOC_C4
VDDCR_SOC_B5
25/40
VDDCR_CPU1_BN46
VDDCR_CPU1_BN35
VDDCR_CPU1_BN27
VDDCR_CPU1_BP32
VDDCR_CPU1_BP28
VDDCR_CPU1_BP24
VDDCR_CPU1_DH51
VDDCR_CPU1_DH50
VDDCR_CPU1_DH48
VDDCR_CPU1_DH47
VDDCR_CPU1_DH45
VDDCR_CPU1_DH57
VDDCR_CPU1_DH56
VDDCR_CPU1_DH54
VDDCR_CPU1_DH53
VDDCR_CPU1_DH44
VDDCR_CPU1_DH42
VDDCR_CPU1_DH41
VDDCR_CPU1_DH35
VDDCR_CPU1_DH34
VDDCR_CPU1_DH32
VDDCR_CPU1_DH31
VDDCR_CPU1_DH29
VDDCR_CPU1_DH28
VDDCR_CPU1_DH26
VDDCR_CPU1_DH25
VDDCR_CPU1_DH23
VDDCR_CPU1_DH22
VDDCR_CPU1_DH20
VDDCR_CPU1_DH19
VDDCR_CPU1_DG57
VDDCR_CPU1_DG19
VDDCR_CPU1_DE54
VDDCR_CPU1_DE51
VDDCR_CPU1_DE48
VDDCR_CPU1_DE45
VDDCR_CPU1_DE42
VDDCR_CPU1_DE41
VDDCR_CPU1_DE35
VDDCR_CPU1_DE34
VDDCR_CPU1_DE31
VDDCR_CPU1_DE28
VDDCR_CPU1_DE25
VDDCR_CPU1_DE22
VDDCR_CPU1_DD54
VDDCR_CPU1_DD51
VDDCR_CPU1_DD48
VDDCR_CPU1_DD45
VDDCR_CPU1_DD42
VDDCR_CPU1_DD34
VDDCR_CPU1_DD31
VDDCR_CPU1_DD28
VDDCR_CPU1_DD25
VDDCR_CPU1_DD22
VDDCR_CPU1_DC41
VDDCR_CPU1_DC40
VDDCR_CPU1_DC36
VDDCR_CPU1_DC35
VDDCR_CPU1_DB53
VDDCR_CPU1_DB52
VDDCR_CPU1_DB50
VDDCR_CPU1_DB49
VDDCR_CPU1_DB47
VDDCR_CPU1_DB46
VDDCR_CPU1_DB44
VDDCR_CPU1_DB43
VDDCR_CPU1_DB33
VDDCR_CPU1_DB32
VDDCR_CPU1_DB30
VDDCR_CPU1_DB29
VDDCR_CPU1_DB27
VDDCR_CPU1_DB26
VDDCR_CPU1_DB24
VDDCR_CPU1_DB23
VDDCR_CPU1_DA41
VDDCR_CPU1_DA40
VDDCR_CPU1_DA36
VDDCR_CPU1_DA35
VDDCR_CPU1_CV53
VDDCR_CPU1_CV52
VDDCR_CPU1_CV50
VDDCR_CPU1_CV49
VDDCR_CPU1_CV47
VDDCR_CPU1_CV46
VDDCR_CPU1_CV44
VDDCR_CPU1_CV43
VDDCR_CPU1_CV33
VDDCR_CPU1_CV32
VDDCR_CPU1_CV30
VDDCR_CPU1_CV29
VDDCR_CPU1_CV27
VDDCR_CPU1_CV26
VDDCR_CPU1_CV24
VDDCR_CPU1_CV23
VDDCR_CPU1_CU41
VDDCR_CPU1_CU40
VDDCR_CPU1_CU36
VDDCR_CPU1_CU35
VDDCR_CPU1_CP53
VDDCR_CPU1_CP52
VDDCR_CPU1_CP50
VDDCR_CPU1_CP49
VDDCR_CPU1_CP47
VDDCR_CPU1_CP46
VDDCR_CPU1_CP44
VDDCR_CPU1_CP43
VDDCR_CPU1_CP33
VDDCR_CPU1_CP32
VDDCR_CPU1_CP30
VDDCR_CPU1_CP29
VDDCR_CPU1_CP27
VDDCR_CPU1_CP26
VDDCR_CPU1_CP24
VDDCR_CPU1_CP23
VDDCR_CPU1_CN41
VDDCR_CPU1_CN40
VDDCR_CPU1_CN36
VDDCR_CPU1_CN35
VDDCR_CPU1_CL47
VDDCR_CPU1_CL46
VDDCR_CPU1_CL44
VDDCR_CPU1_CL43
VDDCR_CPU1_CL33
VDDCR_CPU1_CL32
VDDCR_CPU1_CL30
VDDCR_CPU1_CL29
VDDCR_CPU1_CK41
VDDCR_CPU1_CK40
VDDCR_CPU1_CK36
VDDCR_CPU1_CK35
VDDCR_CPU1_CH53
VDDCR_CPU1_CH52
VDDCR_CPU1_CH50
VDDCR_CPU1_CH49
VDDCR_CPU1_CH47
VDDCR_CPU1_CH46
VDDCR_CPU1_CH44
VDDCR_CPU1_CH43
VDDCR_CPU1_CH33
VDDCR_CPU1_CH32
VDDCR_CPU1_CH30
VDDCR_CPU1_CH29
VDDCR_CPU1_CH27
VDDCR_CPU1_CH26
VDDCR_CPU1_CH24
VDDCR_CPU1_CH23
VDDCR_CPU1_CG41
VDDCR_CPU1_CG40
VDDCR_CPU1_CG36
VDDCR_CPU1_CG35
VDDCR_CPU1_CD53
VDDCR_CPU1_CD52
VDDCR_CPU1_CD50
VDDCR_CPU1_CD49
VDDCR_CPU1_CD47
VDDCR_CPU1_CD46
VDDCR_CPU1_CD44
VDDCR_CPU1_CD43
VDDCR_CPU1_CD33
VDDCR_CPU1_CD32
VDDCR_CPU1_CD30
VDDCR_CPU1_CD29
VDDCR_CPU1_CD27
VDDCR_CPU1_CD26
VDDCR_CPU1_CD24
VDDCR_CPU1_CD23
VDDCR_CPU1_CC41
VDDCR_CPU1_CC40
VDDCR_CPU1_CC36
VDDCR_CPU1_CC35
VDDCR_CPU1_BY53
VDDCR_CPU1_BY52
VDDCR_CPU1_BY50
VDDCR_CPU1_BY49
VDDCR_CPU1_BY47
VDDCR_CPU1_BY46
VDDCR_CPU1_BY44
VDDCR_CPU1_BY43
VDDCR_CPU1_BY33
VDDCR_CPU1_BY32
VDDCR_CPU1_BY30
VDDCR_CPU1_BY29
VDDCR_CPU1_BY27
VDDCR_CPU1_BY26
VDDCR_CPU1_BY24
VDDCR_CPU1_BY23
VDDCR_CPU1_BW41
VDDCR_CPU1_BW40
VDDCR_CPU1_BW36
VDDCR_CPU1_BW35
VDDCR_CPU1_BT53
VDDCR_CPU1_BT52
VDDCR_CPU1_BT50
VDDCR_CPU1_BT49
VDDCR_CPU1_BT47
VDDCR_CPU1_BT46
VDDCR_CPU1_BT44
VDDCR_CPU1_BT43
VDDCR_CPU1_BT33
VDDCR_CPU1_BT32
VDDCR_CPU1_BT30
VDDCR_CPU1_BT29
VDDCR_CPU1_BT27
VDDCR_CPU1_BT26
VDDCR_CPU1_BT24
VDDCR_CPU1_BT23
VDDCR_CPU1_BR52
VDDCR_CPU1_BR50
VDDCR_CPU1_BR48
VDDCR_CPU1_BR46
VDDCR_CPU1_BR44
VDDCR_CPU1_BR42
VDDCR_CPU1_BR40
VDDCR_CPU1_BR35
VDDCR_CPU1_BR33
VDDCR_CPU1_BR31
VDDCR_CPU1_BR29
VDDCR_CPU1_BR27
VDDCR_CPU1_BR25
VDDCR_CPU1_BR23
VDDCR_CPU1_BP49
VDDCR_CPU1_BP47
VDDCR_CPU1_BP45
VDDCR_CPU1_BP43
VDDCR_CPU1_BP41
VDDCR_CPU1_BP39
VDDCR_CPU1_BP36
VDDCR_CPU1_BP34
VDDCR_CPU1_BP30
VDDCR_CPU1_BP26
VDDCR_CPU1_BN50
VDDCR_CPU1_BN42
VDDCR_CPU1_BN31
24/40
VDDCR_CPU0_AU33
VDDCR_CPU0_AU25
VDDCR_CPU0_AU48
VDDCR_CPU0_AU44
VDDCR_CPU0_AU29
VDDCR_CPU0_AT49
VDDCR_CPU0_AU46
VDDCR_CPU0_AU42
VDDCR_CPU0_Y35
VDDCR_CPU0_Y36
VDDCR_CPU0_Y40
VDDCR_CPU0_Y41
VDDCR_CPU0_AB23
VDDCR_CPU0_AB24
VDDCR_CPU0_AB26
VDDCR_CPU0_AB27
VDDCR_CPU0_AB29
VDDCR_CPU0_AB30
VDDCR_CPU0_AB32
VDDCR_CPU0_AB33
VDDCR_CPU0_AB43
VDDCR_CPU0_AB44
VDDCR_CPU0_AB46
VDDCR_CPU0_AB47
VDDCR_CPU0_AB49
VDDCR_CPU0_AB50
VDDCR_CPU0_AB52
VDDCR_CPU0_AB53
VDDCR_CPU0_AC35
VDDCR_CPU0_AC36
VDDCR_CPU0_AC40
VDDCR_CPU0_AC41
VDDCR_CPU0_AF23
VDDCR_CPU0_AF24
VDDCR_CPU0_AF26
VDDCR_CPU0_AF27
VDDCR_CPU0_AF29
VDDCR_CPU0_AF30
VDDCR_CPU0_AF32
VDDCR_CPU0_AF33
VDDCR_CPU0_AF43
VDDCR_CPU0_AF44
VDDCR_CPU0_AF46
VDDCR_CPU0_AF47
VDDCR_CPU0_AF49
VDDCR_CPU0_AF50
VDDCR_CPU0_AF52
VDDCR_CPU0_AF53
VDDCR_CPU0_AG35
VDDCR_CPU0_AG36
VDDCR_CPU0_AG40
VDDCR_CPU0_AG41
VDDCR_CPU0_AK23
VDDCR_CPU0_AK24
VDDCR_CPU0_AK26
VDDCR_CPU0_AK27
VDDCR_CPU0_AK29
VDDCR_CPU0_AK30
VDDCR_CPU0_AK32
VDDCR_CPU0_AK33
VDDCR_CPU0_AK43
VDDCR_CPU0_AK44
VDDCR_CPU0_AK46
VDDCR_CPU0_AK47
VDDCR_CPU0_AK49
VDDCR_CPU0_AK50
VDDCR_CPU0_AK52
VDDCR_CPU0_AK53
VDDCR_CPU0_AL35
VDDCR_CPU0_AL36
VDDCR_CPU0_AL40
VDDCR_CPU0_AL41
VDDCR_CPU0_AP23
VDDCR_CPU0_AP24
VDDCR_CPU0_AP26
VDDCR_CPU0_AP27
VDDCR_CPU0_AP29
VDDCR_CPU0_AP30
VDDCR_CPU0_AP32
VDDCR_CPU0_AP33
VDDCR_CPU0_AP43
VDDCR_CPU0_AP44
VDDCR_CPU0_AP46
VDDCR_CPU0_AP47
VDDCR_CPU0_AP49
VDDCR_CPU0_AP50
VDDCR_CPU0_AP52
VDDCR_CPU0_AP53
VDDCR_CPU0_AR23
VDDCR_CPU0_AR25
VDDCR_CPU0_AR27
VDDCR_CPU0_AR29
VDDCR_CPU0_AR31
VDDCR_CPU0_AR33
VDDCR_CPU0_AR35
VDDCR_CPU0_AR40
VDDCR_CPU0_AR42
VDDCR_CPU0_AR44
VDDCR_CPU0_AR46
VDDCR_CPU0_AR48
VDDCR_CPU0_AR50
VDDCR_CPU0_AT24
VDDCR_CPU0_AT26
VDDCR_CPU0_AT28
VDDCR_CPU0_AT30
VDDCR_CPU0_AT32
VDDCR_CPU0_AT34
VDDCR_CPU0_AT36
VDDCR_CPU0_AT39
VDDCR_CPU0_AT41
VDDCR_CPU0_AT43
VDDCR_CPU0_AT45
VDDCR_CPU0_AT47
VDDCR_CPU0_B19
VDDCR_CPU0_B20
VDDCR_CPU0_B22
VDDCR_CPU0_B23
VDDCR_CPU0_B25
VDDCR_CPU0_B26
VDDCR_CPU0_B28
VDDCR_CPU0_B29
VDDCR_CPU0_B31
VDDCR_CPU0_B32
VDDCR_CPU0_B34
VDDCR_CPU0_B35
VDDCR_CPU0_B41
VDDCR_CPU0_B42
VDDCR_CPU0_B44
VDDCR_CPU0_B45
VDDCR_CPU0_B47
VDDCR_CPU0_B48
VDDCR_CPU0_B50
VDDCR_CPU0_B51
VDDCR_CPU0_B53
VDDCR_CPU0_B54
VDDCR_CPU0_B56
VDDCR_CPU0_B57
VDDCR_CPU0_C20
VDDCR_CPU0_D55
VDDCR_CPU0_D56
VDDCR_CPU0_E22
VDDCR_CPU0_E25
VDDCR_CPU0_E28
VDDCR_CPU0_E31
VDDCR_CPU0_E34
VDDCR_CPU0_E35
VDDCR_CPU0_E42
VDDCR_CPU0_E45
VDDCR_CPU0_E48
VDDCR_CPU0_E51
VDDCR_CPU0_E54
VDDCR_CPU0_F22
VDDCR_CPU0_F25
VDDCR_CPU0_F28
VDDCR_CPU0_F31
VDDCR_CPU0_F34
VDDCR_CPU0_F42
VDDCR_CPU0_F45
VDDCR_CPU0_F48
VDDCR_CPU0_F51
VDDCR_CPU0_F54
VDDCR_CPU0_G35
VDDCR_CPU0_G36
VDDCR_CPU0_G40
VDDCR_CPU0_G41
VDDCR_CPU0_H23
VDDCR_CPU0_H24
VDDCR_CPU0_H26
VDDCR_CPU0_H27
VDDCR_CPU0_H29
VDDCR_CPU0_H30
VDDCR_CPU0_H32
VDDCR_CPU0_H33
VDDCR_CPU0_H43
VDDCR_CPU0_H44
VDDCR_CPU0_H46
VDDCR_CPU0_H47
VDDCR_CPU0_H49
VDDCR_CPU0_H50
VDDCR_CPU0_H52
VDDCR_CPU0_H53
VDDCR_CPU0_J35
VDDCR_CPU0_J36
VDDCR_CPU0_J40
VDDCR_CPU0_J41
VDDCR_CPU0_M23
VDDCR_CPU0_M24
VDDCR_CPU0_M26
VDDCR_CPU0_M27
VDDCR_CPU0_M29
VDDCR_CPU0_M30
VDDCR_CPU0_M32
VDDCR_CPU0_M33
VDDCR_CPU0_M43
VDDCR_CPU0_M44
VDDCR_CPU0_M46
VDDCR_CPU0_M47
VDDCR_CPU0_M49
VDDCR_CPU0_M50
VDDCR_CPU0_M52
VDDCR_CPU0_M53
VDDCR_CPU0_N35
VDDCR_CPU0_N36
VDDCR_CPU0_N40
VDDCR_CPU0_N41
VDDCR_CPU0_T23
VDDCR_CPU0_T24
VDDCR_CPU0_T26
VDDCR_CPU0_T27
VDDCR_CPU0_T29
VDDCR_CPU0_T30
VDDCR_CPU0_T32
VDDCR_CPU0_T33
VDDCR_CPU0_T43
VDDCR_CPU0_T44
VDDCR_CPU0_T46
VDDCR_CPU0_T47
VDDCR_CPU0_T49
VDDCR_CPU0_T50
VDDCR_CPU0_T52
VDDCR_CPU0_T53
VDDCR_CPU0_U35
VDDCR_CPU0_U36
VDDCR_CPU0_U40
VDDCR_CPU0_U41
VDDCR_CPU0_W29
VDDCR_CPU0_W30
VDDCR_CPU0_W32
VDDCR_CPU0_W33
VDDCR_CPU0_W43
VDDCR_CPU0_W44
VDDCR_CPU0_W46
VDDCR_CPU0_W47
23/40
TEST6_X3D6
TEST4_CCD15
TEST4_CCD12
TEST5_CCD12
TEST5_CCD15
TEST4_CCD14
TEST5_CCD14
TEST4_CCD13
TEST5_CCD13
TEST6_X3D7
RSVD_A60
RSVD_BD7
RSVD_D36
RSVD_BD58
RSVD_BD55
RSVD_A54
RSVD_A51
RSVD_A50
RSVD_A48
RSVD_C53
RSVD_A45
RSVD_C35
RSVD_D65
RSVD_A42
RSVD_C34
RSVD_D62
RSVD_BD21
RSVD_A41
RSVD_C31
RSVD_D58
RSVD_BD18
RSVD_DJ4
RSVD_A35
RSVD_B40
RSVD_BD14
RSVD_DH21
RSVD_A31
RSVD_D34
RSVD_BD11
RSVD_DH17
RSVD_A59
RSVD_D22
RSVD_DG17
RSVD_A57
RSVD_D11
RSVD_BD4
RSVD_BD72
RSVD_A56
RSVD_D8
RSVD_E36
RSVD_BD69
RSVD_A55
RSVD_D4
RSVD_E33
RSVD_BD65
RSVD_C54
RSVD_D72
RSVD_BD62
27/40
VDD_11_S3_CT19
VDD_11_S3_CT22
VDD_11_S3_CW4
VDD_11_S3_CW11
VDD_11_S3_CW18
VDD_11_S3_CY22
VDD_11_S3_DB5
VDD_11_S3_DB12
VDD_11_S3_DB19
VDD_11_S3_DE4
VDD_11_S3_DE11
VDD_11_S3_DE18
VDD_11_S3_DG5
VDDIO_CT64
VDDIO_CT71
VDDIO_CW58
VDDIO_CW65
VDDIO_CW72
VDDIO_CY54
VDDIO_DB57
VDDIO_DB64
VDDIO_DB71
VDDIO_DE58
VDDIO_DE65
VDDIO_DE72
VDDIO_DG64
VDDIO_DG71
VDDBT_RTC_G
VDDIO_AUDIO
VDD_33_S5_BP51
VDD_33_S5_BN52
VDD_11_S3_CT12
VDD_18_S5_BB53
VDD_18_S5_BB51
VDD_18_S5_BA54
VDD_18_S5_BA52
VDD_18_S5_BA50
VDD_18_S5_AY53
VDD_18_S5_AY51
VDD_18_S5_AW54
VDD_18_S5_AW52
VDD_18_S5_BC54
VDD_18_S5_BC52
VDD_18_S5_AW50
VDD_18_S5_AV53
VDD_18_S5_AV51
VDD_18_S5_AV49
VDD_18_S5_AU52
VDD_18_S5_AU50
VDD_18_S5_AT53
VDD_18_S5_AT51
VDD_18_S5_AR54
VDD_18_S5_AR52
VDD_18_S5_AU54
VDD_11_S3_CT5
VDD_11_S3_CN18
VDD_11_S3_CN11
VDD_11_S3_CN4
VDD_11_S3_CM22
VDD_11_S3_CK19
VDD_11_S3_CK12
VDD_11_S3_CK5
VDD_11_S3_CJ22
VDD_11_S3_CG18
VDD_11_S3_CG11
VDD_11_S3_CG4
VDD_11_S3_CF22
VDD_11_S3_CD19
VDD_11_S3_CD12
VDD_11_S3_CD5
VDD_11_S3_CB22
VDD_11_S3_CA18
VDD_11_S3_CA11
VDD_11_S3_CA4
VDD_11_S3_BV22
VDD_11_S3_BV19
VDD_11_S3_BV12
VDD_11_S3_BV5
VDD_11_S3_BR18
VDD_11_S3_BR11
VDD_11_S3_BR4
VDD_11_S3_BP22
VDD_11_S3_BN48
VDD_11_S3_BN44
VDD_11_S3_BN40
VDD_11_S3_BN33
VDD_11_S3_BN29
VDD_11_S3_BN25
VDD_11_S3_BM49
VDD_11_S3_BM47
VDD_11_S3_BM45
VDD_11_S3_BM43
VDD_11_S3_BM41
VDD_11_S3_BM39
VDD_11_S3_BM36
VDD_11_S3_BM34
VDD_11_S3_BM32
VDD_11_S3_BM30
VDD_11_S3_BM28
VDD_11_S3_BM26
VDD_11_S3_BM24
VDD_11_S3_BM22
VDD_11_S3_BM19
VDD_11_S3_BM12
VDD_11_S3_BL48
VDD_11_S3_BL27
VDD_11_S3_BL25
VDD_11_S3_BL23
VDD_11_S3_BK49
VDD_11_S3_BK28
VDD_11_S3_BK26
VDD_11_S3_BK24
VDD_11_S3_BK22
VDD_11_S3_BJ27
VDD_11_S3_BJ25
VDD_11_S3_BJ23
VDD_11_S3_BJ18
VDDIO_CT57
VDDIO_CT54
VDDIO_CN72
VDDIO_CN65
VDDIO_CN58
VDDIO_CM54
VDDIO_CK71
VDDIO_CK64
VDDIO_CK57
VDDIO_CJ54
VDDIO_CG72
VDDIO_CG65
VDDIO_CG58
VDDIO_CF54
VDDIO_CD71
VDDIO_CD64
VDDIO_CD57
VDDIO_CB54
VDDIO_CA72
VDDIO_CA65
VDDIO_CA58
VDDIO_BV71
VDDIO_BV64
VDDIO_BV57
VDDIO_BV54
VDDIO_BR72
VDDIO_BR65
VDDIO_BR58
VDDIO_BN54
VDDIO_BM71
VDDIO_BM64
VDDIO_BM57
VDDIO_BM53
VDDIO_BM51
VDDIO_BL54
VDDIO_BL52
VDDIO_BL50
VDDIO_BK53
VDDIO_BK51
VDDIO_BJ72
VDDIO_BJ65
VDDIO_BJ58
VDDIO_BJ54
VDDIO_BJ52
VDDIO_BJ50
VDDIO_BH53
VDDIO_BH51
VDDIO_BG54
VDDIO_BG52
VDDIO_BG50
VDDIO_BF71
VDDIO_BF64
VDDIO_BF57
VDDIO_BF53
VDDIO_BF51
VDDIO_BD54
VDDIO_BD52
VDDIO_BD50
VDDIO_BA72
VDDIO_BA65
VDDIO_BA58
VDDIO_AV71
VDDIO_AV64
VDDIO_AV57
VDDIO_AR72
VDDIO_AR65
VDDIO_AR58
VDDIO_AM71
VDDIO_AM64
VDDIO_AM57
VDDIO_AM54
VDDIO_AJ72
VDDIO_AJ65
VDDIO_AJ58
VDDIO_AH54
VDDIO_AF71
VDDIO_AF64
VDDIO_AF57
VDDIO_AD54
VDDIO_AC72
VDDIO_AC65
VDDIO_AC58
VDDIO_AA54
VDDIO_Y71
VDDIO_Y64
VDDIO_Y57
VDDIO_V54
VDDIO_U72
VDDIO_U65
VDDIO_U58
VDDIO_P71
VDDIO_P64
VDDIO_P57
VDDIO_P54
VDDIO_L72
VDDIO_L65
VDDIO_L58
VDDIO_K54
VDDIO_H71
VDDIO_H64
VDDIO_H57
SHEETDATE
DEPARTMENT
SIZE
PROJECT DOCUMENT NUMBER REV
REVIEWER
DESIGNER
123
7 3 2 1 6 5 4
E
A
B
C
E
D
C
B
A
7 6 5 4
D
C



Thu Sep 14 16:11:54 2023<NAME_2><NAME_1>MB FABCGT AMDV0231 OF 365
SOCKET6096_13568-001SOCKET6096_13568-001SOCKET6096_13568-001SOCKET6096_13568-001SOCKET6096_13568-001SOCKET6096_13568-001IOIOIOIOIOIO
CPU0 VSS 1/3
SMLFSMLFSMLFSMLFSMLFSMLF
BL24
BL22
BL20
BL18
BL15
BL13
BL11
BL8
BL6
BL4
BL1
BK73
BK71
BK68
BK66
BK64
BK61
BK59
BK57
BK54
BK52
BK50
BK48
BK27
BK25
BK23
BK19
BK17
BK15
BK12
BK10
BK8
BK5
BK3
BJ75
BJ70
BJ68
BJ63
BJ61
BJ56
BJ53
BJ51
BJ49
BJ28
BJ26
BJ24
BJ22
BJ20
BJ15
BJ13
BJ8
BJ6
BJ1
BH73
BH71
BH68
BH66
BH64
BH61
BH59
BH57
BH54
BH52
BH50
BH49
BH28
BH26
BH24
BH22
BH19
BH17
BH15
BH12
BH10
BH8
BH5
BH3
BG75
BG72
BG70
BG68
BG65
BG63
BG61
BG58
BG56
BG53
BG51
BG49
BG27
BG25
BG23
BG20
BG18
BG15
BG13
BG11
BG8
BG6
BG4
BG1
BF73
BF68
BF66
BF61
BF59
BF54
BF52
BF50
BF49
BF28
BF26
BF24
BF22
BF19
BF17
BF15
BF12
BF10
BF8
BF5
BF3
BD73
BD71
BD68
BD66
BD64
BD61
BD59
BD57
BD53
BD51
BD49
BD27
BD25
BD23
BD17
BD15
BD10
BD8
BD3
BC75
BC72
BC70
BC68
BC65
BC63
BC61
BC58
BC56
BC53
BC51
BC50
BC49
BC28
BC26
BC24
BC22
BC20
BC18
BC15
BC13
BC11
BC8
BC6
BC4
BC1
BB73
BB71
BB68
BB66
BB64
BB61
BB59
BB57
BB54
BB52
BB50
BB48
BB27
BB25
BB23
BB19
BB17
BB15
BB12
BB10
BB8
BB5
BB3
BA75
BA70
BA68
BA63
BA61
BA56
BA53
BA51
BA49
BA28
BA26
BA24
BA22
BA20
BA15
BA13
BA8
BA6
BA1
AY73
AY71
AY68
AY66
AY64
AY61
AY59
AY57
AY54
AY52
AY50
AY48
AY27
AY25
AY23
AY19
AY17
AY15
AY12
AY10
AY8
AY5
AY3
AW75
AW72
AW70
AW68
AW65
AW63
U25
AW61
AW58
AW56
AW53
AW51
AW49
AW28
AW26
AW24
AW22
AW20
AW18
AW15
AW13
AW11
AW8
AW6
AW4
AW1
AV73
AV68
AV66
AV61
AV59
AV54
AV52
AV50
AV48
AV46
AV44
AV42
AV40
AV37
AV35
AV33
AV31
AV29
AV27
AV25
AV23
AV17
AV15
AV10
AV8
AV3
AU75
AU73
AU72
AU70
AU68
AU65
AU63
AU61
AU58
AU56
AU53
AU51
AU49
AU47
AU45
AU43
AU41
AU36
AU34
AU32
AU30
AU28
AU26
AU24
AU22
AU20
AU18
AU15
AU13
AU11
AU8
AU6
AU4
AU3
AU1
AT73
AT72
AT71
AT70
AT68
AT67
AT66
AT64
AT63
AT61
AT60
AT59
AT57
AT56
AT54
AT52
AT50
AT48
AT46
AT44
AT42
AT40
AT37
AT35
AT33
AT31
AT29
AT27
AT25
AT23
AT20
AT19
AT17
AT16
AT15
AT13
AT12
AT10
AT9
AT8
AT6
AT5
AT4
AT3
AR75
AR71
AR70
AR68
AR67
AR64
AR63
AR61
AR60
AR57
AR56
AR53
AR51
AR49
AR47
AR45
AR43
AR41
AR36
AR34
AR32
AR30
AR28
AR26
AR24
AR22
AR20
AR19
AR16
AR15
AR13
AR12
AR9
AR8
AR6
AR5
AR1
AP73
AP71
AP68
AP66
AP64
AP61
AP59
AP57
AP54
AP51
AP48
AP45
AP42
AP39
AP37
AP34
AP31
AP28
AP25
AP22
AP19
AP17
AP15
AP12
AP10
AP8
AP5
AP3
AN75
AN72
AN70
AN68
AN65
AN63
AN61
AN58
AN56
AN54
AN51
AN48
AN45
AN42
AN41
AN40
AN36
AN35
AN34
AN31
AN28
AN25
AN22
AN18
AN15
AN13
AN11
AN8
AN6
AN4
AN1
AM73
AM68
AM66
AM61
AM59
AM53
AM52
AM51
AM50
AM49
AM48
AM47
AM46
AM45
AM44
AM43
AM42
U25
AM39
AM34
AM33
AM32
AM31
AM30
AM29
AM28
AM27
AM26
AM25
AM24
AM23
AM17
AM15
AM10
AM8
AM3
AL75
AL72
AL70
AL68
AL65
AL63
AL61
AL58
AL56
AL54
AL51
AL48
AL45
AL42
AL34
AL31
AL28
AL25
AL22
AL20
AL18
AL15
AL13
AL11
AL8
AL6
AL4
AL1
AK73
AK71
AK68
AK66
AK64
AK61
AK59
AK57
AK54
AK51
AK48
AK45
AK42
AK39
AK37
AK34
AK31
AK28
AK25
AK22
AK19
AK17
AK15
AK12
AK10
AK8
AK5
AK3
AJ75
AJ70
AJ68
AJ63
AJ61
AJ56
AJ54
AJ51
AJ48
AJ45
AJ42
AJ41
AJ40
AJ36
AJ35
AJ34
AJ31
AJ28
AJ25
AJ22
AJ20
AJ15
AJ8
AJ6
AJ1
AH73
AH71
AH68
AH66
AH64
AH61
AH59
AH57
AH53
AH52
AH51
AH50
AH49
AH48
AH47
AH46
AH45
AH44
AH43
AH42
AH39
AH37
AH34
AH32
AH31
AH30
AH29
AH28
AH27
AH26
AH25
AH24
AH23
AH19
AH17
AH15
AH12
AH10
AH8
AH5
AH3
AG75
AG72
AG70
AG68
AG65
AG63
AG61
AG58
AG56
AG54
AG51
AG48
AG45
AG42
AG34
AG31
AG28
AG25
AG22
AG20
AG18
AG15
AG13
AG11
AG8
AG6
AG4
AG1
AF73
AF68
AF66
AF61
AF59
AF54
AF51
AF48
AF45
AF42
AF39
AF37
AF34
AF31
AF28
AF25
AF22
AF17
AF15
AF10
AF8
AF3
AE75
AE72
AE70
AE68
AE65
AE63
AE61
AE58
AE56
AE54
AE51
AE48
AE45
AE42
AE41
AE40
AE36
AE35
AE34
AE31
AE28
AE25
AE22
AE20
AE18
AE15
AE13
AE11
AE8
AE6
AE1
AD73
AD71
AD68
AD66
AD64
AD61
AD59
AD57
AD53
AD52
AD51
AD50
AD49
U25
Y73
Y68
Y66
Y61
Y59
Y54
Y53
Y52
Y51
Y50
Y49
Y48
Y45
Y44
Y43
Y42
Y39
Y37
Y34
Y33
Y32
Y31
Y28
Y27
Y26
Y25
Y24
Y23
Y22
Y17
Y15
Y10
Y8
Y3
W75
W72
W70
W68
W65
W63
W61
W58
W56
W54
W51
W48
W45
W42
W41
W40
W36
W35
W34
W28
W25
W22
W20
W18
W15
W13
W11
W8
W6
W4
W1
V73
V71
V66
V64
V61
V59
V57
V53
V52
V51
V50
V49
V48
V47
V46
V45
V44
V43
V42
V39
V37
V34
V33
V32
V31
V30
V29
V28
V26
V25
V24
V23
V19
V17
V15
V12
V10
V8
V5
V3
U75
U70
U68
U63
U61
U56
U54
U51
U48
U45
U42
U34
U31
U28
U25
U22
U20
U15
U13
U8
U6
U1
T73
T71
T68
T66
AD48
AD47
AD46
AD45
AD44
AD43
AD42
AD39
AD37
AD34
AD33
AD32
AD30
AD29
AD28
AD27
AD26
AD25
AD24
AD23
AD19
AD17
AD15
AD12
AD10
AD8
AD5
AD3
AC75
AC70
AC68
AC63
AC61
AC56
AC54
AC51
AC48
AC45
AC42
AC34
AC31
AC28
AC25
AC22
AC20
AC15
AC13
AC8
AC6
AC1
AB73
AB71
AB68
AB66
AB64
AB61
AB59
AB57
AB54
AB51
AB48
AB45
AB42
AB39
AB37
AB34
AB31
AB28
AB25
AB22
AB19
AB17
AB15
AB12
AB10
AB8
AB5
AB3
AA75
AA70
AA68
AA65
AA63
AA61
AA58
AA56
AA45
AA41
AA40
AA36
AA35
AA34
AA31
AA20
AA18
AA15
AA13
AA11
AA8
AA6
AA4
AA1
U25
T64
T61
T59
T57
T54
T51
T48
T45
T42
T39
T37
T34
T31
T28
T25
T22
T19
T17
T15
T12
T10
T8
T5
T3
R75
R72
R70
R68
R65
R63
R61
R58
R56
R54
R51
R48
R45
R42
R41
R40
R36
R35
R34
R31
R28
R25
R22
R20
R18
R15
R13
R11
R8
R6
R4
R1
P73
P66
P61
P59
P53
P52
P51
P50
P49
P48
P47
P46
P45
P44
P43
P42
P39
P37
P34
P33
P32
P31
P30
P29
P28
P27
P26
P24
P23
P17
P15
P10
P8
P3
N75
N72
N70
N68
N65
N63
N61
N58
N56
N54
N51
N48
N45
N42
N34
N31
N28
N25
N22
N20
N18
N15
N13
N11
N8
N6
N4
N1
M73
M71
M68
M66
M64
M61
M59
M57
M54
M51
M48
M45
M42
M39
M37
M34
M31
M28
M25
M22
M19
M17
M15
M12
M10
M8
M5
M3
L75
L70
L68
L63
L61
L56
L54
L51
L48
L45
L42
L41
L40
L36
L35
L34
L31
L28
L25
L22
L20
L15
L13
L8
L6
L1
K73
K71
K68
K66
K64
K61
K57
K53
K52
K51
K50
K49
K48
K47
K46
K45
K44
K43
K42
K39
K37
K34
K33
K32
K31
K30
K29
K28
K27
K26
K25
K24
K19
K17
K15
K12
K10
K8
K5
K3
J75
J72
J70
J68
J65
J63
J61
J58
J56
J54
J51
J48
J45
J42
J34
J31
J28
J25
J22
J20
J18
J15
U25
J13
J11
J8
J6
J4
J1
H73
H68
H66
H61
H59
H54
H51
H48
H45
H42
H39
H37
H34
H31
H28
H25
H22
H17
H15
H10
H8
H3
G75
G72
G70
G68
G65
G63
G61
G58
G56
G54
G51
G48
G45
G42
G34
G31
G28
G25
G22
G20
G18
G15
G13
G11
G8
G6
G4
G1
F73
F71
F68
F66
F64
F61
F59
F57
F53
F52
F50
F49
F47
F46
F44
F43
F41
F40
F39
F37
F36
F35
F33
F32
F30
F29
F27
F26
F24
F23
F19
F17
F15
F12
F10
F8
F5
F3
E75
E73
E72
E70
E69
E68
E66
E65
E63
E62
E61
E59
E58
E56
E55
E53
E52
E21
E20
E18
E17
E15
E14
E13
E10
E8
E7
E6
E3
E1
D74
D73
D71
D70
D67
D66
D64
D63
D61
D60
D59
D57
D54
D53
D52
D51
D50
D49
D48
D47
D46
D45
D44
D43
D42
D41
D40
D39
D37
D35
D31
D30
D29
D28
D27
D26
D25
D24
D21
D20
D19
D17
D16
D13
D12
D10
D9
D6
D5
D3
D2
C75
C73
C71
C69
C67
C64
C61
C57
C56
C55
C52
C49
C46
C43
C40
C36
C30
C27
C24
C21
C15
C13
C11
C10
C8
C5
C1
B70
B68
B65
B62
B59
B55
B52
B49
B46
B43
B39
B37
B33
B30
B27
B24
B18
B13
B11
B10
B8
B7
A73
A72
A67
A61
A53
A49
A47
A44
A43
A27
A21
A15
A9
A3
U25
33/40
VSS_BL24
VSS_BL22
VSS_BL20
VSS_BL18
VSS_BL15
VSS_BL13
VSS_BL11
VSS_BL8
VSS_BL6
VSS_BL4
VSS_BL1
VSS_BK73
VSS_BK71
VSS_BK68
VSS_BK66
VSS_BK64
VSS_BK61
VSS_BK59
VSS_BK57
VSS_BK54
VSS_BK52
VSS_BK50
VSS_BK48
VSS_BK27
VSS_BK25
VSS_BK23
VSS_BK19
VSS_BK17
VSS_BK15
VSS_BK12
VSS_BK10
VSS_BK8
VSS_BK5
VSS_BK3
VSS_BJ75
VSS_BJ70
VSS_BJ68
VSS_BJ63
VSS_BJ61
VSS_BJ56
VSS_BJ53
VSS_BJ51
VSS_BJ49
VSS_BJ28
VSS_BJ26
VSS_BJ24
VSS_BJ22
VSS_BJ20
VSS_BJ15
VSS_BJ13
VSS_BJ8
VSS_BJ6
VSS_BJ1
VSS_BH73
VSS_BH71
VSS_BH68
VSS_BH66
VSS_BH64
VSS_BH61
VSS_BH59
VSS_BH57
VSS_BH54
VSS_BH52
VSS_BH50
VSS_BH49
VSS_BH28
VSS_BH26
VSS_BH24
VSS_BH22
VSS_BH19
VSS_BH17
VSS_BH15
VSS_BH12
VSS_BH10
VSS_BH8
VSS_BH5
VSS_BH3
VSS_BG75
VSS_BG72
VSS_BG70
VSS_BG68
VSS_BG65
VSS_BG63
VSS_BG61
VSS_BG58
VSS_BG56
VSS_BG53
VSS_BG51
VSS_BG49
VSS_BG27
VSS_BG25
VSS_BG23
VSS_BG20
VSS_BG18
VSS_BG15
VSS_BG13
VSS_BG11
VSS_BG8
VSS_BG6
VSS_BG4
VSS_BG1
VSS_BF73
VSS_BF68
VSS_BF66
VSS_BF61
VSS_BF59
VSS_BF54
VSS_BF52
VSS_BF50
VSS_BF49
VSS_BF28
VSS_BF26
VSS_BF24
VSS_BF22
VSS_BF19
VSS_BF17
VSS_BF15
VSS_BF12
VSS_BF10
VSS_BF8
VSS_BF5
VSS_BF3
VSS_BD73
VSS_BD71
VSS_BD68
VSS_BD66
VSS_BD64
VSS_BD61
VSS_BD59
VSS_BD57
VSS_BD53
VSS_BD51
VSS_BD49
VSS_BD27
VSS_BD25
VSS_BD23
VSS_BD17
VSS_BD15
VSS_BD10
VSS_BD8
VSS_BD3
VSS_BC75
VSS_BC72
VSS_BC70
VSS_BC68
VSS_BC65
VSS_BC63
VSS_BC61
VSS_BC58
VSS_BC56
VSS_BC53
VSS_BC51
VSS_BC50
VSS_BC49
VSS_BC28
VSS_BC26
VSS_BC24
VSS_BC22
VSS_BC20
VSS_BC18
VSS_BC15
VSS_BC13
VSS_BC11
VSS_BC8
VSS_BC6
VSS_BC4
VSS_BC1
VSS_BB73
VSS_BB71
VSS_BB68
VSS_BB66
VSS_BB64
VSS_BB61
VSS_BB59
VSS_BB57
VSS_BB54
VSS_BB52
VSS_BB50
VSS_BB48
VSS_BB27
VSS_BB25
VSS_BB23
VSS_BB19
VSS_BB17
VSS_BB15
VSS_BB12
VSS_BB10
VSS_BB8
VSS_BB5
VSS_BB3
VSS_BA75
VSS_BA70
VSS_BA68
VSS_BA63
VSS_BA61
VSS_BA56
VSS_BA53
VSS_BA51
VSS_BA49
VSS_BA28
VSS_BA26
VSS_BA24
VSS_BA22
VSS_BA20
VSS_BA15
VSS_BA13
VSS_BA8
VSS_BA6
VSS_BA1
VSS_AY73
VSS_AY71
VSS_AY68
VSS_AY66
VSS_AY64
VSS_AY61
VSS_AY59
VSS_AY57
VSS_AY54
VSS_AY52
VSS_AY50
VSS_AY48
VSS_AY27
VSS_AY25
VSS_AY23
VSS_AY19
VSS_AY17
VSS_AY15
VSS_AY12
VSS_AY10
VSS_AY8
VSS_AY5
VSS_AY3
VSS_AW75
VSS_AW72
VSS_AW70
VSS_AW68
VSS_AW65
VSS_AW63
32/40
VSS_AW61
VSS_AW58
VSS_AW56
VSS_AW53
VSS_AW51
VSS_AW49
VSS_AW28
VSS_AW26
VSS_AW24
VSS_AW22
VSS_AW20
VSS_AW18
VSS_AW15
VSS_AW13
VSS_AW11
VSS_AW8
VSS_AW6
VSS_AW4
VSS_AW1
VSS_AV73
VSS_AV68
VSS_AV66
VSS_AV61
VSS_AV59
VSS_AV54
VSS_AV52
VSS_AV50
VSS_AV48
VSS_AV46
VSS_AV44
VSS_AV42
VSS_AV40
VSS_AV37
VSS_AV35
VSS_AV33
VSS_AV31
VSS_AV29
VSS_AV27
VSS_AV25
VSS_AV23
VSS_AV17
VSS_AV15
VSS_AV10
VSS_AV8
VSS_AV3
VSS_AU75
VSS_AU73
VSS_AU72
VSS_AU70
VSS_AU68
VSS_AU65
VSS_AU63
VSS_AU61
VSS_AU58
VSS_AU56
VSS_AU53
VSS_AU51
VSS_AU49
VSS_AU47
VSS_AU45
VSS_AU43
VSS_AU41
VSS_AU36
VSS_AU34
VSS_AU32
VSS_AU30
VSS_AU28
VSS_AU26
VSS_AU24
VSS_AU22
VSS_AU20
VSS_AU18
VSS_AU15
VSS_AU13
VSS_AU11
VSS_AU8
VSS_AU6
VSS_AU4
VSS_AU3
VSS_AU1
VSS_AT73
VSS_AT72
VSS_AT71
VSS_AT70
VSS_AT68
VSS_AT67
VSS_AT66
VSS_AT64
VSS_AT63
VSS_AT61
VSS_AT60
VSS_AT59
VSS_AT57
VSS_AT56
VSS_AT54
VSS_AT52
VSS_AT50
VSS_AT48
VSS_AT46
VSS_AT44
VSS_AT42
VSS_AT40
VSS_AT37
VSS_AT35
VSS_AT33
VSS_AT31
VSS_AT29
VSS_AT27
VSS_AT25
VSS_AT23
VSS_AT20
VSS_AT19
VSS_AT17
VSS_AT16
VSS_AT15
VSS_AT13
VSS_AT12
VSS_AT10
VSS_AT9
VSS_AT8
VSS_AT6
VSS_AT5
VSS_AT4
VSS_AT3
VSS_AR75
VSS_AR71
VSS_AR70
VSS_AR68
VSS_AR67
VSS_AR64
VSS_AR63
VSS_AR61
VSS_AR60
VSS_AR57
VSS_AR56
VSS_AR53
VSS_AR51
VSS_AR49
VSS_AR47
VSS_AR45
VSS_AR43
VSS_AR41
VSS_AR36
VSS_AR34
VSS_AR32
VSS_AR30
VSS_AR28
VSS_AR26
VSS_AR24
VSS_AR22
VSS_AR20
VSS_AR19
VSS_AR16
VSS_AR15
VSS_AR13
VSS_AR12
VSS_AR9
VSS_AR8
VSS_AR6
VSS_AR5
VSS_AR1
VSS_AP73
VSS_AP71
VSS_AP68
VSS_AP66
VSS_AP64
VSS_AP61
VSS_AP59
VSS_AP57
VSS_AP54
VSS_AP51
VSS_AP48
VSS_AP45
VSS_AP42
VSS_AP39
VSS_AP37
VSS_AP34
VSS_AP31
VSS_AP28
VSS_AP25
VSS_AP22
VSS_AP19
VSS_AP17
VSS_AP15
VSS_AP12
VSS_AP10
VSS_AP8
VSS_AP5
VSS_AP3
VSS_AN75
VSS_AN72
VSS_AN70
VSS_AN68
VSS_AN65
VSS_AN63
VSS_AN61
VSS_AN58
VSS_AN56
VSS_AN54
VSS_AN51
VSS_AN48
VSS_AN45
VSS_AN42
VSS_AN41
VSS_AN40
VSS_AN36
VSS_AN35
VSS_AN34
VSS_AN31
VSS_AN28
VSS_AN25
VSS_AN22
VSS_AN18
VSS_AN15
VSS_AN13
VSS_AN11
VSS_AN8
VSS_AN6
VSS_AN4
VSS_AN1
VSS_AM73
VSS_AM68
VSS_AM66
VSS_AM61
VSS_AM59
VSS_AM53
VSS_AM52
VSS_AM51
VSS_AM50
VSS_AM49
VSS_AM48
VSS_AM47
VSS_AM46
VSS_AM45
VSS_AM44
VSS_AM43
VSS_AM42
31/40
VSS_AK8
VSS_AK5
VSS_AK3
VSS_AJ75
VSS_AJ70
VSS_AJ68
VSS_AJ63
VSS_AJ61
VSS_AJ56
VSS_AJ54
VSS_AJ51
VSS_AJ48
VSS_AJ45
VSS_AJ42
VSS_AJ41
VSS_AJ40
VSS_AJ36
VSS_AJ35
VSS_AJ34
VSS_AJ31
VSS_AJ28
VSS_AJ25
VSS_AJ22
VSS_AJ20
VSS_AJ15
VSS_AJ8
VSS_AJ6
VSS_AJ1
VSS_AH73
VSS_AH71
VSS_AH68
VSS_AH66
VSS_AH64
VSS_AH61
VSS_AH59
VSS_AH57
VSS_AH53
VSS_AH52
VSS_AH51
VSS_AH50
VSS_AH49
VSS_AH48
VSS_AH47
VSS_AH46
VSS_AH45
VSS_AH44
VSS_AH43
VSS_AH42
VSS_AH39
VSS_AH37
VSS_AH34
VSS_AH32
VSS_AH31
VSS_AH30
VSS_AH29
VSS_AH28
VSS_AH27
VSS_AH26
VSS_AH25
VSS_AH24
VSS_AH23
VSS_AH19
VSS_AH17
VSS_AH15
VSS_AH12
VSS_AH10
VSS_AH8
VSS_AH5
VSS_AH3
VSS_AG75
VSS_AG72
VSS_AG70
VSS_AG68
VSS_AG65
VSS_AG63
VSS_AG61
VSS_AG58
VSS_AG56
VSS_AG54
VSS_AG51
VSS_AG48
VSS_AG45
VSS_AG42
VSS_AG34
VSS_AG31
VSS_AG28
VSS_AG25
VSS_AG22
VSS_AG20
VSS_AG18
VSS_AG15
VSS_AG13
VSS_AG11
VSS_AG8
VSS_AG6
VSS_AG4
VSS_AG1
VSS_AF73
VSS_AF68
VSS_AF66
VSS_AF61
VSS_AF59
VSS_AF54
VSS_AF51
VSS_AF48
VSS_AF45
VSS_AF42
VSS_AF39
VSS_AF37
VSS_AF34
VSS_AF31
VSS_AF28
VSS_AF25
VSS_AF22
VSS_AF17
VSS_AF15
VSS_AF10
VSS_AF8
VSS_AF3
VSS_AE75
VSS_AE72
VSS_AE70
VSS_AE68
VSS_AE65
VSS_AE63
VSS_AE61
VSS_AE58
VSS_AE56
VSS_AE54
VSS_AE51
VSS_AE48
VSS_AE45
VSS_AE42
VSS_AE41
VSS_AE40
VSS_AE36
VSS_AE35
VSS_AE34
VSS_AE31
VSS_AE28
VSS_AE25
VSS_AE22
VSS_AE20
VSS_AE18
VSS_AE15
VSS_AE13
VSS_AE11
VSS_AE8
VSS_AE6
VSS_AE1
VSS_AD73
VSS_AD71
VSS_AD68
VSS_AD66
VSS_AD64
VSS_AD61
VSS_AD59
VSS_AD57
VSS_AD53
VSS_AD52
VSS_AD51
VSS_AD50
VSS_AD49
VSS_AM39
VSS_AM34
VSS_AM33
VSS_AM32
VSS_AM31
VSS_AM30
VSS_AM29
VSS_AM28
VSS_AM27
VSS_AM26
VSS_AM25
VSS_AM24
VSS_AM23
VSS_AM17
VSS_AM15
VSS_AM10
VSS_AM8
VSS_AM3
VSS_AL75
VSS_AL72
VSS_AL70
VSS_AL68
VSS_AL65
VSS_AL63
VSS_AL61
VSS_AL58
VSS_AL56
VSS_AL54
VSS_AL51
VSS_AL48
VSS_AL45
VSS_AL42
VSS_AL34
VSS_AL31
VSS_AL28
VSS_AL25
VSS_AL22
VSS_AL20
VSS_AL18
VSS_AL15
VSS_AL13
VSS_AL11
VSS_AL8
VSS_AL6
VSS_AL4
VSS_AL1
VSS_AK73
VSS_AK71
VSS_AK68
VSS_AK66
VSS_AK64
VSS_AK61
VSS_AK59
VSS_AK57
VSS_AK54
VSS_AK51
VSS_AK48
VSS_AK45
VSS_AK42
VSS_AK39
VSS_AK37
VSS_AK34
VSS_AK31
VSS_AK28
VSS_AK25
VSS_AK22
VSS_AK19
VSS_AK17
VSS_AK15
VSS_AK12
VSS_AK10
30/40
VSS_AB66
VSS_AB64
VSS_AB61
VSS_AB59
VSS_AB57
VSS_AB54
VSS_AB51
VSS_AB48
VSS_AB45
VSS_AB42
VSS_AB39
VSS_AB37
VSS_AB34
VSS_AB31
VSS_AB28
VSS_AB25
VSS_AB22
VSS_AB19
VSS_AB17
VSS_AB15
VSS_AB12
VSS_AB10
VSS_AB8
VSS_AB5
VSS_AB3
VSS_AA75
VSS_AA70
VSS_AA68
VSS_AA65
VSS_AA63
VSS_AA61
VSS_AA58
VSS_AA56
VSS_AA45
VSS_AA41
VSS_AA40
VSS_AA36
VSS_AA35
VSS_AA34
VSS_AA31
VSS_AA20
VSS_AA18
VSS_AA15
VSS_AA13
VSS_AA11
VSS_AA8
VSS_AA6
VSS_AA4
VSS_AA1
VSS_Y73
VSS_Y68
VSS_Y66
VSS_Y61
VSS_Y59
VSS_Y54
VSS_Y53
VSS_Y52
VSS_Y51
VSS_Y50
VSS_Y49
VSS_Y48
VSS_Y45
VSS_Y44
VSS_Y43
VSS_Y42
VSS_Y39
VSS_Y37
VSS_Y34
VSS_Y33
VSS_Y32
VSS_Y31
VSS_Y28
VSS_Y27
VSS_Y26
VSS_Y25
VSS_Y24
VSS_Y23
VSS_Y22
VSS_Y17
VSS_Y15
VSS_Y10
VSS_Y8
VSS_Y3
VSS_W75
VSS_W72
VSS_W70
VSS_W68
VSS_W65
VSS_W63
VSS_W61
VSS_W58
VSS_W56
VSS_W54
VSS_W51
VSS_W48
VSS_W45
VSS_W42
VSS_W41
VSS_W40
VSS_W36
VSS_W35
VSS_W34
VSS_W28
VSS_W25
VSS_W22
VSS_W20
VSS_W18
VSS_W15
VSS_W13
VSS_W11
VSS_W8
VSS_W6
VSS_W4
VSS_W1
VSS_V73
VSS_V71
VSS_V66
VSS_V64
VSS_V61
VSS_V59
VSS_V57
VSS_V53
VSS_V52
VSS_V51
VSS_V50
VSS_V49
VSS_V48
VSS_V47
VSS_V46
VSS_V45
VSS_V44
VSS_V43
VSS_V42
VSS_V39
VSS_V37
VSS_V34
VSS_V33
VSS_V32
VSS_V31
VSS_V30
VSS_V29
VSS_V28
VSS_V26
VSS_V25
VSS_V24
VSS_V23
VSS_V19
VSS_V17
VSS_V15
VSS_V12
VSS_V10
VSS_V8
VSS_V5
VSS_V3
VSS_U75
VSS_U70
VSS_U68
VSS_U63
VSS_U61
VSS_U56
VSS_U54
VSS_U51
VSS_U48
VSS_U45
VSS_U42
VSS_U34
VSS_U31
VSS_U28
VSS_U25
VSS_U22
VSS_U20
VSS_U15
VSS_U13
VSS_U8
VSS_U6
VSS_U1
VSS_T73
VSS_T71
VSS_T68
VSS_T66
VSS_AD48
VSS_AD47
VSS_AD46
VSS_AD45
VSS_AD44
VSS_AD43
VSS_AD42
VSS_AD39
VSS_AD37
VSS_AD34
VSS_AD33
VSS_AD32
VSS_AD30
VSS_AD29
VSS_AD28
VSS_AD27
VSS_AD26
VSS_AD25
VSS_AD24
VSS_AD23
VSS_AD19
VSS_AD17
VSS_AD15
VSS_AD12
VSS_AD10
VSS_AD8
VSS_AD5
VSS_AD3
VSS_AC75
VSS_AC70
VSS_AC68
VSS_AC63
VSS_AC61
VSS_AC56
VSS_AC54
VSS_AC51
VSS_AC48
VSS_AC45
VSS_AC42
VSS_AC34
VSS_AC31
VSS_AC28
VSS_AC25
VSS_AC22
VSS_AC20
VSS_AC15
VSS_AC13
VSS_AC8
VSS_AC6
VSS_AC1
VSS_AB73
VSS_AB71
VSS_AB68
29/40
VSS_R45
VSS_R42
VSS_R41
VSS_R40
VSS_R36
VSS_R35
VSS_R34
VSS_R31
VSS_R28
VSS_R25
VSS_R22
VSS_R20
VSS_R18
VSS_R15
VSS_R13
VSS_R11
VSS_R8
VSS_R6
VSS_R4
VSS_R1
VSS_P73
VSS_P66
VSS_P61
VSS_P59
VSS_P53
VSS_P52
VSS_P51
VSS_P50
VSS_P49
VSS_P48
VSS_P47
VSS_P46
VSS_P45
VSS_P44
VSS_P43
VSS_P42
VSS_P39
VSS_P37
VSS_P34
VSS_P33
VSS_P32
VSS_P31
VSS_P30
VSS_P29
VSS_P28
VSS_P27
VSS_P26
VSS_P24
VSS_P23
VSS_P17
VSS_P15
VSS_P10
VSS_P8
VSS_P3
VSS_N75
VSS_N72
VSS_N70
VSS_N68
VSS_N65
VSS_N63
VSS_N61
VSS_N58
VSS_N56
VSS_N54
VSS_N51
VSS_N48
VSS_N45
VSS_N42
VSS_N34
VSS_N31
VSS_N28
VSS_N25
VSS_N22
VSS_N20
VSS_N18
VSS_N15
VSS_N13
VSS_N11
VSS_N8
VSS_N6
VSS_N4
VSS_N1
VSS_M73
VSS_M71
VSS_M68
VSS_M66
VSS_M64
VSS_M61
VSS_M59
VSS_M57
VSS_M54
VSS_M51
VSS_M48
VSS_M45
VSS_M42
VSS_M39
VSS_M37
VSS_M34
VSS_M31
VSS_M28
VSS_M25
VSS_M22
VSS_M19
VSS_M17
VSS_M15
VSS_M12
VSS_M10
VSS_M8
VSS_M5
VSS_M3
VSS_L75
VSS_L70
VSS_L68
VSS_L63
VSS_L61
VSS_L56
VSS_L54
VSS_L51
VSS_L48
VSS_L45
VSS_L42
VSS_L41
VSS_L40
VSS_L36
VSS_L35
VSS_L34
VSS_L31
VSS_L28
VSS_L25
VSS_L22
VSS_L20
VSS_L15
VSS_L13
VSS_L8
VSS_L6
VSS_L1
VSS_K73
VSS_K71
VSS_K68
VSS_K66
VSS_K64
VSS_K61
VSS_K57
VSS_K53
VSS_K52
VSS_K51
VSS_K50
VSS_K49
VSS_K48
VSS_K47
VSS_K46
VSS_K45
VSS_K44
VSS_K43
VSS_K42
VSS_K39
VSS_K37
VSS_K34
VSS_K33
VSS_K32
VSS_K31
VSS_K30
VSS_K29
VSS_K28
VSS_K27
VSS_K26
VSS_K25
VSS_K24
VSS_K19
VSS_K17
VSS_K15
VSS_K12
VSS_K10
VSS_K8
VSS_K5
VSS_K3
VSS_J75
VSS_J72
VSS_J70
VSS_J68
VSS_J65
VSS_J63
VSS_J61
VSS_J58
VSS_J56
VSS_J54
VSS_J51
VSS_J48
VSS_J45
VSS_J42
VSS_J34
VSS_J31
VSS_J28
VSS_J25
VSS_J22
VSS_J20
VSS_J18
VSS_J15
VSS_T64
VSS_T61
VSS_T59
VSS_T57
VSS_T54
VSS_T51
VSS_T48
VSS_T45
VSS_T42
VSS_T39
VSS_T37
VSS_T34
VSS_T31
VSS_T28
VSS_T25
VSS_T22
VSS_T19
VSS_T17
VSS_T15
VSS_T12
VSS_T10
VSS_T8
VSS_T5
VSS_T3
VSS_R75
VSS_R72
VSS_R70
VSS_R68
VSS_R65
VSS_R63
VSS_R61
VSS_R58
VSS_R56
VSS_R54
VSS_R51
VSS_R48
28/40
VSS_H34
VSS_H31
VSS_H28
VSS_H25
VSS_H22
VSS_H17
VSS_H15
VSS_H10
VSS_H8
VSS_H3
VSS_G75
VSS_G72
VSS_G70
VSS_G68
VSS_G65
VSS_G63
VSS_G61
VSS_G58
VSS_G56
VSS_G54
VSS_G51
VSS_G48
VSS_G45
VSS_G42
VSS_G34
VSS_G31
VSS_G28
VSS_G25
VSS_G22
VSS_G20
VSS_G18
VSS_G15
VSS_G13
VSS_G11
VSS_G8
VSS_G6
VSS_G4
VSS_G1
VSS_F73
VSS_F71
VSS_F68
VSS_F66
VSS_F64
VSS_F61
VSS_F59
VSS_F57
VSS_F53
VSS_F52
VSS_F50
VSS_F49
VSS_F47
VSS_F46
VSS_F44
VSS_F43
VSS_F41
VSS_F40
VSS_F39
VSS_F37
VSS_F36
VSS_F35
VSS_F33
VSS_F32
VSS_F30
VSS_F29
VSS_F27
VSS_F26
VSS_F24
VSS_F23
VSS_F19
VSS_F17
VSS_F15
VSS_F12
VSS_F10
VSS_F8
VSS_F5
VSS_F3
VSS_E75
VSS_E73
VSS_E72
VSS_E70
VSS_E69
VSS_E68
VSS_E66
VSS_E65
VSS_E63
VSS_E62
VSS_E61
VSS_E59
VSS_E58
VSS_E56
VSS_E55
VSS_E53
VSS_E52
VSS_E21
VSS_E20
VSS_E18
VSS_E17
VSS_E15
VSS_E14
VSS_E13
VSS_E10
VSS_E8
VSS_E7
VSS_E6
VSS_E3
VSS_E1
VSS_D74
VSS_D73
VSS_D71
VSS_D70
VSS_D67
VSS_D66
VSS_D64
VSS_D63
VSS_D61
VSS_D60
VSS_D59
VSS_D57
VSS_D54
VSS_D53
VSS_D52
VSS_D51
VSS_D50
VSS_D49
VSS_D48
VSS_D47
VSS_D46
VSS_D45
VSS_D44
VSS_D43
VSS_D42
VSS_D41
VSS_D40
VSS_D39
VSS_D37
VSS_D35
VSS_D31
VSS_D30
VSS_D29
VSS_D28
VSS_D27
VSS_D26
VSS_D25
VSS_D24
VSS_D21
VSS_D20
VSS_D19
VSS_D17
VSS_D16
VSS_D13
VSS_D12
VSS_D10
VSS_D9
VSS_D6
VSS_D5
VSS_D3
VSS_D2
VSS_C75
VSS_C73
VSS_C71
VSS_C69
VSS_C67
VSS_C64
VSS_C61
VSS_C57
VSS_C56
VSS_C55
VSS_C52
VSS_C49
VSS_C46
VSS_C43
VSS_C40
VSS_C36
VSS_C30
VSS_C27
VSS_C24
VSS_C21
VSS_C15
VSS_C13
VSS_C11
VSS_C10
VSS_C8
VSS_C5
VSS_C1
VSS_B70
VSS_B68
VSS_B65
VSS_B62
VSS_B59
VSS_B55
VSS_B52
VSS_B49
VSS_B46
VSS_B43
VSS_B39
VSS_B37
VSS_B33
VSS_B30
VSS_B27
VSS_B24
VSS_B18
VSS_B13
VSS_B11
VSS_B10
VSS_B8
VSS_B7
VSS_A73
VSS_A72
VSS_A67
VSS_A61
VSS_A53
VSS_A49
VSS_A47
VSS_A44
VSS_A43
VSS_A27
VSS_A21
VSS_A15
VSS_A9
VSS_A3
VSS_J13
VSS_J11
VSS_J8
VSS_J6
VSS_J4
VSS_J1
VSS_H73
VSS_H68
VSS_H66
VSS_H61
VSS_H59
VSS_H54
VSS_H51
VSS_H48
VSS_H45
VSS_H42
VSS_H39
VSS_H37
SHEETDATE
DEPARTMENT
SIZE
PROJECT DOCUMENT NUMBER REV
REVIEWER
DESIGNER
123
7 3 2 1 6 5 4
E
A
B
C
E
D
C
B
A
7 6 5 4
D
C



Thu Sep 14 16:11:54 2023<NAME_2><NAME_1>MB FABCGT AMDV0232 OF 365
SOCKET6096_13568-001SOCKET6096_13568-001SOCKET6096_13568-001SOCKET6096_13568-001IOIOIOIO
CPU0 VSS 2/3
SMLFSMLFSMLFSMLF
DA70
DA68
DA65
DA63
DA61
DA58
DA54
DA51
DA48
DA45
DA42
DA34
DA31
DA28
DA25
DA22
DA20
DA18
DA15
DA13
DA11
DA8
DA6
DA4
DA1
CY73
CY71
CY68
CY66
CY64
CY61
CY59
CY53
CY52
CY51
CY50
CY49
CY48
CY47
CY46
CY45
CY44
CY43
CY42
CY39
CY37
CY34
CY33
CY32
CY31
CY30
CY29
CY28
CY27
CY26
CY25
CY24
CY23
CY19
CY17
CY15
CY12
CY10
CY8
CY5
CY3
CW75
CW70
CW68
CW63
CW61
CW56
CW54
CW51
CW48
CW45
CW42
CW41
CW40
CW36
CW35
CW34
CW31
CW28
CW25
CW22
CW20
CW15
CW13
CW8
CW6
CW1
CV73
CV71
CV68
CV66
CV64
CV61
CV59
CV57
CV54
CV51
CV48
CV45
CV42
CV39
CV37
CV34
CV31
CV28
CV25
CV22
CV19
CV17
CV15
CV12
CV10
CV8
CV5
CV3
CU75
CU72
CU70
CU68
CU65
CU63
CU61
CU56
CU54
CU51
CU48
CU45
CU42
CU34
CU31
CU28
CU25
CU22
CU20
CU18
CU15
CU13
CU11
CU8
CU6
CU4
CU1
CT73
CT68
CT66
CT61
CT59
CT53
CT51
CT50
CT49
CT48
CT47
CT46
CT45
CT44
CT43
CT42
CT39
CT37
CT34
CT33
CT32
CT31
CT30
CT29
CT28
CT27
CT26
CT25
CT24
CT23
CT17
CT15
CT10
CT8
CT3
CR75
CR72
CR70
CR68
CR65
CR63
CR61
CR58
CR56
CR54
CR51
CR48
CR45
CR42
CR41
CR40
CR36
CR35
CR34
CR31
CR28
CR25
CR22
CR20
CR18
CR15
CR13
CR11
CR8
CR6
CR4
CR1
CP73
CP71
CP68
CP66
CP64
CP61
CP59
CP57
CP54
CP51
CP48
CP45
CP42
CP39
CP37
CP34
CP31
CP28
CP25
CP22
U25
CP19
CP17
CP15
CP12
CP10
CP8
CP5
CP3
CN75
CN70
CN68
CN63
CN61
CN56
CN51
CN48
CN45
CN42
CN34
CN31
CN28
CN25
CN22
CN20
CN15
CN13
CN8
CN6
CN1
CM73
CM71
CM68
CM66
CM64
CM61
CM59
CM57
CM53
CM52
CM51
CM49
CM48
CM47
CM46
CM45
CM44
CM43
CM42
CM39
CM37
CM34
CM33
CM32
CM31
CM30
CM29
CM28
CM27
CM26
CM25
CM24
CM23
CM19
CM17
CM15
CM12
CM10
CM8
CM5
CM3
CL75
CL72
CL70
CL68
CL65
CL63
CL61
CL58
CL56
CL54
CL51
CL48
CL45
CL42
CL41
CL40
CL36
CL35
CL34
CL31
CL28
CL25
CL22
CL20
CL18
CL15
CL13
CL11
CL8
CL6
CL4
CL1
CK73
CK68
CK66
CK61
CK59
CK54
CK53
CK52
CK51
CK50
CK49
CK48
CK45
CK44
CK43
CK42
CK39
CK37
CK34
CK33
CK32
CK28
CK27
CK26
CK25
CK24
CK23
CK22
CK17
CK15
CK8
CK3
CJ75
CJ72
CJ70
CJ68
CJ65
CJ63
CJ61
CJ58
CJ56
CJ45
CJ42
CJ41
CJ40
CJ36
CJ35
CJ34
CJ31
CJ23
CJ20
CJ18
CJ15
CJ13
CJ11
CJ8
CJ6
CJ4
CJ1
CH73
CH71
CH68
CH66
CH64
CH61
CH59
CH57
CH54
CH51
CH48
CH45
CH42
CH39
CH37
CH34
CH31
CH28
CH25
CH22
CH19
CH17
CH15
CH12
CH10
CH8
CH5
CH3
CG75
CG70
CG68
CG63
CG61
CG56
CG54
CG51
CG48
CG45
CG34
CG31
CG28
CG25
CG22
CG20
CG15
CG13
CG8
CG6
CG1
CF73
CF71
CF68
CF66
CF64
CF61
CF59
CF57
CF53
CF52
CF51
CF50
CF49
CF48
CF47
CF45
CF44
CF43
CF42
CF39
CF37
CF34
U25
CF33
CF32
CF31
CF30
CF29
CF28
CF27
CF26
CF25
CF24
CF23
CF19
CF17
CF15
CF12
CF10
CF8
CF5
CF3
CE75
CE72
CE70
CE68
CE65
CE63
CE61
CE58
CE56
CE54
CE51
CE48
CE45
CE42
CE41
CE40
CE36
CE35
CE34
CE31
CE28
CE25
CE22
CE20
CE18
CE15
CE13
CE11
CE8
CE6
CE4
CE1
CD73
CD68
CD66
CD61
CD59
CD54
CD51
CD48
CD45
CD42
CD39
CD37
CD34
CD31
CD28
CD25
CD22
CD17
CD15
CD10
CD8
CD3
CC75
CC72
CC70
CC68
CC65
CC63
CC61
CC58
CC56
CC54
CC51
CC48
CC45
CC42
CC34
CC31
CC28
CC25
CC20
CC18
CC15
CC13
CC11
CC8
CC6
CC4
CC1
CB73
CB71
CB68
CB66
CB64
CB61
CB59
CB57
CB53
CB52
CB51
CB50
CB49
CB48
CB47
CB46
CB45
CB43
CB42
CB39
CB37
CB34
CB33
CB32
CB31
CB30
CB29
CB28
CB27
CB26
CB25
CB24
CB23
CB19
CB17
CB15
CB12
CB10
CB8
CB5
CB3
CA75
CA70
CA68
CA63
CA61
CA56
CA54
CA51
CA48
CA45
CA42
CA41
CA40
CA36
CA35
CA34
CA31
CA28
CA25
CA22
CA20
CA15
CA13
CA8
CA6
CA1
BY73
BY71
BY68
BY66
BY64
BY61
BY59
BY57
BY54
BY51
BY48
BY45
BY42
BY39
BY37
BY34
BY31
BY28
BY25
BY22
BY19
BY17
BY15
BY12
BY10
BY8
BY5
BY3
BW75
BW72
BW70
BW68
BW65
BW63
BW61
BW58
BW56
BW54
BW51
BW48
BW45
BW42
BW34
BW31
BW28
BW22
BW20
BW18
BW15
BW13
BW11
BW8
BW6
BW4
BW1
BV73
BV68
BV66
BV61
BV59
BV53
BV52
BV51
BV50
BV49
BV48
BV47
BV46
U25
BV45
BV44
BV43
BV39
BV37
BV34
BV33
BV32
BV31
BV30
BV29
BV28
BV27
BV26
BV25
BV24
BV23
BV17
BV15
BV10
BV8
BV3
BU75
BU72
BU70
BU68
BU65
BU63
BU61
BU58
BU56
BU54
BU51
BU48
BU45
BU42
BU41
BU40
BU36
BU35
BU34
BU31
BU28
BU25
BU22
BU20
BU18
BU15
BU13
BU11
BU8
BU6
BU4
BU1
BT73
BT72
BT71
BT69
BT68
BT66
BT65
BT64
BT62
BT61
BT59
BT58
BT57
BT55
BT54
BT51
BT48
BT45
BT42
BT39
BT37
BT34
BT31
BT28
BT25
BT22
BT21
BT19
BT18
BT17
BT15
BT14
BT12
BT11
BT10
BT8
BT7
BT5
BT4
BT3
BR75
BR73
BR70
BR69
BR68
BR66
BR63
BR62
BR61
BR59
BR56
BR55
BR51
BR49
BR47
BR45
BR43
BR41
BR36
BR34
BR32
BR30
BR28
BR26
BR24
BR22
BR21
BR20
BR17
BR15
BR14
BR13
BR10
BR8
BR7
BR6
BR3
BR1
BP73
BP71
BP68
BP66
BP64
BP61
BP59
BP57
BP54
BP52
BP50
BP48
BP46
BP44
BP42
BP40
BP37
BP35
BP33
BP31
BP29
BP27
BP25
BP23
BP19
BP17
BP15
BP12
BP10
BP8
BP5
BP3
BN75
BN72
BN70
BN68
BN65
BN63
BN61
BN58
BN56
BN53
BN51
BN49
BN47
BN45
BN43
BN41
BN36
BN34
BN32
BN30
BN28
BN26
BN24
BN22
BN20
BN18
BN15
BN13
BN11
BN8
BN6
BN4
BN1
BM73
BM68
BM66
BM61
BM59
BM54
BM52
BM50
BM48
BM46
BM44
BM42
BM40
BM37
BM35
BM33
BM31
BM29
BM27
BM25
BM23
BM17
BM15
BM10
BM8
BM3
BL75
BL72
BL70
BL68
BL65
BL63
BL61
BL58
BL56
BL53
BL51
BL49
BL28
BL26
U25
39/40
VSS_DA70
VSS_DA68
VSS_DA65
VSS_DA63
VSS_DA61
VSS_DA58
VSS_DA42
VSS_DA34
VSS_DA31
VSS_DA28
VSS_DA25
VSS_DA22
VSS_DA11
VSS_DA8
VSS_DA6
VSS_DA4
VSS_DA1
VSS_CY73
VSS_CY71
VSS_CY61
VSS_CY59
VSS_CY53
VSS_CY52
VSS_CY51
VSS_CY50
VSS_CY49
VSS_CY46
VSS_CY45
VSS_CY44
VSS_CY43
VSS_CY42
VSS_CY39
VSS_CY37
VSS_CY34
VSS_CY33
VSS_CY31
VSS_CY30
VSS_CY29
VSS_CY28
VSS_CY27
VSS_CY26
VSS_CY25
VSS_CY24
VSS_CY23
VSS_CY19
VSS_CY17
VSS_CY15
VSS_CY12
VSS_CY10
VSS_CY8
VSS_CY5
VSS_CY3
VSS_CW75
VSS_CW70
VSS_CW68
VSS_CW63
VSS_CW61
VSS_CW56
VSS_CW54
VSS_CW51
VSS_CW48
VSS_CW45
VSS_CW42
VSS_CW41
VSS_CW40
VSS_CW36
VSS_CW35
VSS_CW20
VSS_CW15
VSS_CW13
VSS_CW8
VSS_CW6
VSS_CW1
VSS_CV61
VSS_CV59
VSS_CV57
VSS_CV54
VSS_CV51
VSS_CV48
VSS_CV31
VSS_CV28
VSS_CV25
VSS_CV22
VSS_CV19
VSS_CV17
VSS_CV3
VSS_CU75
VSS_CU72
VSS_CU70
VSS_CU68
VSS_CU65
VSS_CU54
VSS_CU51
VSS_CU48
VSS_CU45
VSS_CU42
VSS_CU34
VSS_CU31
VSS_CU20
VSS_CU18
VSS_CU15
VSS_CU13
VSS_CU11
VSS_CU8
VSS_CU6
VSS_CU4
VSS_CT68
VSS_CT66
VSS_CT61
VSS_CT59
VSS_CT53
VSS_CT51
VSS_CT50
VSS_CT49
VSS_CT47
VSS_CT46
VSS_CT45
VSS_CT44
VSS_CT43
VSS_CT42
VSS_CT39
VSS_CT37
VSS_CT34
VSS_CT33
VSS_CT32
VSS_CT31
VSS_CT30
VSS_CT29
VSS_CT28
VSS_CT27
VSS_CT26
VSS_CT25
VSS_CT24
VSS_CT23
VSS_CT17
VSS_CR72
VSS_CR70
VSS_CR68
VSS_CR65
VSS_CR63
VSS_CR61
VSS_CR45
VSS_CR42
VSS_CR41
VSS_CR40
VSS_CR36
VSS_CR35
VSS_CR20
VSS_CR18
VSS_CR15
VSS_CR13
VSS_CR11
VSS_CR8
VSS_CP68
VSS_CP66
VSS_CP64
VSS_CP61
VSS_CP59
VSS_CP57
VSS_CP39
VSS_CP37
VSS_CP34
VSS_CP31
VSS_CP28
VSS_CP25
VSS_DA54
VSS_DA51
VSS_DA48
VSS_DA45
VSS_DA20
VSS_DA18
VSS_DA15
VSS_DA13
VSS_CY68
VSS_CY66
VSS_CY64
VSS_CY48
VSS_CY47
VSS_CY32
VSS_CW34
VSS_CW31
VSS_CW28
VSS_CW25
VSS_CW22
VSS_CV73
VSS_CV71
VSS_CV68
VSS_CV66
VSS_CV64
VSS_CV45
VSS_CV42
VSS_CV39
VSS_CV37
VSS_CV34
VSS_CV15
VSS_CV12
VSS_CV10
VSS_CV8
VSS_CV5
VSS_CU63
VSS_CU61
VSS_CU56
VSS_CU28
VSS_CU25
VSS_CU22
VSS_CU1
VSS_CT73
VSS_CT48
VSS_CT15
VSS_CT10
VSS_CT8
VSS_CT3
VSS_CR75
VSS_CR58
VSS_CR56
VSS_CR54
VSS_CR51
VSS_CR48
VSS_CR34
VSS_CR31
VSS_CR28
VSS_CR25
VSS_CR22
VSS_CR6
VSS_CR4
VSS_CR1
VSS_CP73
VSS_CP71
VSS_CP54
VSS_CP51
VSS_CP48
VSS_CP45
VSS_CP42
VSS_CP22
38/40
VSS_CP19
VSS_CP17
VSS_CP15
VSS_CP12
VSS_CP10
VSS_CP8
VSS_CP5
VSS_CP3
VSS_CN75
VSS_CN70
VSS_CN68
VSS_CN63
VSS_CN61
VSS_CN51
VSS_CN48
VSS_CN45
VSS_CN42
VSS_CN34
VSS_CN31
VSS_CN28
VSS_CN25
VSS_CN15
VSS_CN13
VSS_CN8
VSS_CN6
VSS_CN1
VSS_CM73
VSS_CM71
VSS_CM68
VSS_CM59
VSS_CM57
VSS_CM53
VSS_CM52
VSS_CM51
VSS_CM49
VSS_CM48
VSS_CM47
VSS_CM46
VSS_CM45
VSS_CM44
VSS_CM33
VSS_CM32
VSS_CM31
VSS_CM30
VSS_CM29
VSS_CM28
VSS_CM23
VSS_CM19
VSS_CM17
VSS_CM15
VSS_CM12
VSS_CM10
VSS_CM8
VSS_CL72
VSS_CL70
VSS_CL68
VSS_CL65
VSS_CL63
VSS_CL61
VSS_CL58
VSS_CL56
VSS_CL48
VSS_CL45
VSS_CL42
VSS_CL41
VSS_CL40
VSS_CL36
VSS_CL35
VSS_CL34
VSS_CL31
VSS_CL25
VSS_CL22
VSS_CL20
VSS_CL18
VSS_CL15
VSS_CL13
VSS_CL11
VSS_CL8
VSS_CL6
VSS_CL4
VSS_CL1
VSS_CK73
VSS_CK68
VSS_CK66
VSS_CK61
VSS_CK59
VSS_CK54
VSS_CK53
VSS_CK52
VSS_CK51
VSS_CK50
VSS_CK49
VSS_CK48
VSS_CK45
VSS_CK44
VSS_CK43
VSS_CK42
VSS_CK39
VSS_CK37
VSS_CK34
VSS_CK32
VSS_CK28
VSS_CK27
VSS_CK26
VSS_CK25
VSS_CK24
VSS_CK23
VSS_CK22
VSS_CK8
VSS_CK3
VSS_CJ75
VSS_CJ72
VSS_CJ70
VSS_CJ68
VSS_CJ65
VSS_CJ56
VSS_CJ45
VSS_CJ42
VSS_CJ41
VSS_CJ40
VSS_CJ36
VSS_CJ35
VSS_CJ18
VSS_CJ15
VSS_CJ13
VSS_CJ11
VSS_CJ8
VSS_CJ6
VSS_CH66
VSS_CH64
VSS_CH61
VSS_CH59
VSS_CH57
VSS_CH54
VSS_CH37
VSS_CH34
VSS_CH31
VSS_CH28
VSS_CH25
VSS_CH22
VSS_CH8
VSS_CH5
VSS_CH3
VSS_CG75
VSS_CG70
VSS_CG68
VSS_CG63
VSS_CG61
VSS_CG56
VSS_CG54
VSS_CG51
VSS_CG48
VSS_CG45
VSS_CG34
VSS_CG31
VSS_CG28
VSS_CG25
VSS_CG22
VSS_CG20
VSS_CG15
VSS_CG13
VSS_CG8
VSS_CG6
VSS_CG1
VSS_CF73
VSS_CF71
VSS_CF68
VSS_CF66
VSS_CF64
VSS_CF61
VSS_CF59
VSS_CF57
VSS_CF53
VSS_CF52
VSS_CF51
VSS_CF50
VSS_CF49
VSS_CF48
VSS_CF47
VSS_CF45
VSS_CF44
VSS_CF43
VSS_CF42
VSS_CF39
VSS_CF37
VSS_CF34
VSS_CH19
VSS_CH51
VSS_CJ4
VSS_CL28
VSS_CL54
VSS_CM5
VSS_CM27
VSS_CM43
VSS_CH17
VSS_CH48
VSS_CJ1
VSS_CJ34
VSS_CL51
VSS_CM3
VSS_CM26
VSS_CM42
VSS_CH15
VSS_CH45
VSS_CH73
VSS_CJ31
VSS_CJ63
VSS_CL75
VSS_CM25
VSS_CM39
VSS_CM66
VSS_CH12
VSS_CH42
VSS_CH71
VSS_CJ23
VSS_CJ61
VSS_CK17
VSS_CM24
VSS_CM37
VSS_CM64
VSS_CN22
VSS_CH10
VSS_CH39
VSS_CH68
VSS_CJ20
VSS_CJ58
VSS_CK15
VSS_CK33
VSS_CM34
VSS_CM61
VSS_CN20
VSS_CN56
37/40
VSS_CF33
VSS_CF32
VSS_CF31
VSS_CF30
VSS_CF29
VSS_CF28
VSS_CF27
VSS_CF26
VSS_CF25
VSS_CF24
VSS_CF23
VSS_CF19
VSS_CF17
VSS_CF15
VSS_CF12
VSS_CF10
VSS_CF8
VSS_CF5
VSS_CF3
VSS_CE75
VSS_CE72
VSS_CE70
VSS_CE68
VSS_CE65
VSS_CE63
VSS_CE61
VSS_CE58
VSS_CE56
VSS_CE54
VSS_CE51
VSS_CE48
VSS_CE45
VSS_CE42
VSS_CE41
VSS_CE40
VSS_CE36
VSS_CE35
VSS_CE34
VSS_CE31
VSS_CE28
VSS_CE25
VSS_CE22
VSS_CE20
VSS_CE18
VSS_CE15
VSS_CE13
VSS_CE11
VSS_CE8
VSS_CE6
VSS_CE4
VSS_CE1
VSS_CD73
VSS_CD68
VSS_CD66
VSS_CD61
VSS_CD59
VSS_CD54
VSS_CD51
VSS_CD48
VSS_CD45
VSS_CD42
VSS_CD39
VSS_CD37
VSS_CD34
VSS_CD31
VSS_CD28
VSS_CD25
VSS_CD22
VSS_CD17
VSS_CD15
VSS_CD10
VSS_CD8
VSS_CD3
VSS_CC75
VSS_CC72
VSS_CC70
VSS_CC68
VSS_CC65
VSS_CC63
VSS_CC61
VSS_CC58
VSS_CC56
VSS_CC54
VSS_CC51
VSS_CC48
VSS_CC45
VSS_CC42
VSS_CC34
VSS_CC31
VSS_CC28
VSS_CC25
VSS_CC20
VSS_CC18
VSS_CC15
VSS_CC13
VSS_CC11
VSS_CC8
VSS_CC6
VSS_CC4
VSS_CC1
VSS_CB73
VSS_CB71
VSS_CB68
VSS_CB66
VSS_CB64
VSS_CB61
VSS_CB59
VSS_CB57
VSS_CB53
VSS_CB52
VSS_CB51
VSS_CB50
VSS_CB49
VSS_CB48
VSS_CB47
VSS_CB46
VSS_CB45
VSS_CB43
VSS_CB42
VSS_CB39
VSS_CB37
VSS_CB34
VSS_CB33
VSS_CB32
VSS_CB31
VSS_CB30
VSS_CB29
VSS_CB28
VSS_CB27
VSS_CB26
VSS_CB25
VSS_CB24
VSS_CB23
VSS_CB19
VSS_CB17
VSS_CB15
VSS_CB12
VSS_CB10
VSS_CB8
VSS_CB5
VSS_CB3
VSS_CA75
VSS_CA70
VSS_CA68
VSS_CA63
VSS_CA61
VSS_CA56
VSS_CA54
VSS_CA51
VSS_CA48
VSS_CA45
VSS_CA42
VSS_CA41
VSS_CA40
VSS_CA36
VSS_CA35
VSS_CA34
VSS_CA31
VSS_CA28
VSS_CA25
VSS_CA22
VSS_CA20
VSS_CA15
VSS_CA13
VSS_CA8
VSS_CA6
VSS_CA1
VSS_BY73
VSS_BY71
VSS_BY68
VSS_BY66
VSS_BY64
VSS_BY61
VSS_BY59
VSS_BY57
VSS_BY54
VSS_BY51
VSS_BY48
VSS_BY45
VSS_BY42
VSS_BY39
VSS_BY37
VSS_BY34
VSS_BY31
VSS_BY28
VSS_BY25
VSS_BY22
VSS_BY19
VSS_BY17
VSS_BY15
VSS_BY12
VSS_BY10
VSS_BY8
VSS_BY5
VSS_BY3
VSS_BW75
VSS_BW72
VSS_BW70
VSS_BW68
VSS_BW65
VSS_BW63
VSS_BW61
VSS_BW58
VSS_BW56
VSS_BW54
VSS_BW51
VSS_BW48
VSS_BW45
VSS_BW42
VSS_BW34
VSS_BW31
VSS_BW28
VSS_BW22
VSS_BW20
VSS_BW18
VSS_BW15
VSS_BW13
VSS_BW11
VSS_BW8
VSS_BW6
VSS_BW4
VSS_BW1
VSS_BV73
VSS_BV68
VSS_BV66
VSS_BV61
VSS_BV59
VSS_BV53
VSS_BV52
VSS_BV51
VSS_BV50
VSS_BV49
VSS_BV48
VSS_BV47
VSS_BV46
34/40
VSS_BV45
VSS_BV44
VSS_BV43
VSS_BV39
VSS_BV34
VSS_BV33
VSS_BV32
VSS_BV31
VSS_BV30
VSS_BV29
VSS_BV28
VSS_BV27
VSS_BV26
VSS_BV25
VSS_BV24
VSS_BV23
VSS_BV17
VSS_BV15
VSS_BV10
VSS_BV8
VSS_BV3
VSS_BU75
VSS_BU72
VSS_BU70
VSS_BU68
VSS_BU65
VSS_BU63
VSS_BU61
VSS_BU58
VSS_BU56
VSS_BU54
VSS_BU51
VSS_BU48
VSS_BU45
VSS_BU42
VSS_BU41
VSS_BU40
VSS_BU36
VSS_BU35
VSS_BU34
VSS_BU31
VSS_BU28
VSS_BU25
VSS_BU22
VSS_BU20
VSS_BU18
VSS_BU15
VSS_BU13
VSS_BU11
VSS_BU8
VSS_BU6
VSS_BU4
VSS_BU1
VSS_BT73
VSS_BT72
VSS_BT71
VSS_BT69
VSS_BT68
VSS_BT66
VSS_BT65
VSS_BT64
VSS_BT62
VSS_BT61
VSS_BT59
VSS_BT58
VSS_BT57
VSS_BT55
VSS_BT54
VSS_BT51
VSS_BT48
VSS_BT45
VSS_BT42
VSS_BT39
VSS_BT37
VSS_BT34
VSS_BT31
VSS_BT28
VSS_BT25
VSS_BT22
VSS_BT21
VSS_BT19
VSS_BT18
VSS_BT17
VSS_BT15
VSS_BT14
VSS_BT12
VSS_BT11
VSS_BT10
VSS_BT8
VSS_BT7
VSS_BT5
VSS_BT4
VSS_BT3
VSS_BR75
VSS_BR73
VSS_BR70
VSS_BR69
VSS_BR68
VSS_BR66
VSS_BR63
VSS_BR62
VSS_BR61
VSS_BR59
VSS_BR56
VSS_BR55
VSS_BR51
VSS_BR49
VSS_BR47
VSS_BR45
VSS_BR43
VSS_BR41
VSS_BR36
VSS_BR34
VSS_BR32
VSS_BR30
VSS_BR28
VSS_BR26
VSS_BR24
VSS_BR22
VSS_BR21
VSS_BR20
VSS_BR17
VSS_BR15
VSS_BR14
VSS_BR13
VSS_BR10
VSS_BR8
VSS_BR7
VSS_BR6
VSS_BR3
VSS_BR1
VSS_BP73
VSS_BP71
VSS_BP68
VSS_BP66
VSS_BP64
VSS_BP61
VSS_BP59
VSS_BP57
VSS_BP54
VSS_BP52
VSS_BP50
VSS_BP48
VSS_BP46
VSS_BP44
VSS_BP42
VSS_BP40
VSS_BP37
VSS_BP35
VSS_BP33
VSS_BP31
VSS_BP29
VSS_BP27
VSS_BP25
VSS_BP23
VSS_BP19
VSS_BP17
VSS_BP15
VSS_BP12
VSS_BP10
VSS_BP8
VSS_BP5
VSS_BP3
VSS_BN75
VSS_BN72
VSS_BN70
VSS_BN68
VSS_BN65
VSS_BN63
VSS_BN61
VSS_BN58
VSS_BN56
VSS_BN53
VSS_BN51
VSS_BN49
VSS_BN47
VSS_BN45
VSS_BN43
VSS_BN41
VSS_BN36
VSS_BN34
VSS_BN32
VSS_BN30
VSS_BN28
VSS_BN26
VSS_BN24
VSS_BN22
VSS_BN20
VSS_BN18
VSS_BN15
VSS_BN13
VSS_BN11
VSS_BN8
VSS_BN6
VSS_BN4
VSS_BN1
VSS_BM73
VSS_BM68
VSS_BM66
VSS_BM61
VSS_BM59
VSS_BM54
VSS_BM52
VSS_BM50
VSS_BM48
VSS_BM46
VSS_BM44
VSS_BM42
VSS_BM40
VSS_BM37
VSS_BM35
VSS_BM33
VSS_BM31
VSS_BM29
VSS_BM27
VSS_BM25
VSS_BM23
VSS_BM17
VSS_BM15
VSS_BM10
VSS_BM8
VSS_BM3
VSS_BL75
VSS_BL72
VSS_BL70
VSS_BL68
VSS_BL65
VSS_BL63
VSS_BL61
VSS_BL58
VSS_BL56
VSS_BL53
VSS_BL51
VSS_BL49
VSS_BL28
VSS_BL26
VSS_BV37
SHEETDATE
DEPARTMENT
SIZE
PROJECT DOCUMENT NUMBER REV
REVIEWER
DESIGNER
123
7 3 2 1 6 5 4
E
A
B
C
E
D
C
B
A
7 6 5 4
D
C



Thu Sep 14 16:11:55 2023<NAME_2><NAME_1>MB FABCGT AMDV0233 OF 365
SOCKET6096_13568-001IOSMLF
CPU0 VSS 3/3
V68V27P68P25K59K23DJ73DJ68DJ66DJ63DJ61DJ59DJ49DJ43DJ19DJ15DJ7DH70DH68DH66DH64DH63DH61DH59DH55DH52DH49DH46DH43DH39DH37DH18DH11DH5DG75DG74DG70DG69DG68DG67DG66DG65DG63DG62DG61DG60DG59DG56DG55DG52DG49DG46DG43DG41DG33DG30DG27DG24DG21DG20DG18DG16DG15DG14DG13DG9DG8DG7DG6DG2DG1DF73DF72DF71DF70DF68DF66DF65DF64DF63DF61DF59DF58DF57DF56DF54DF53DF52DF51DF50DF49DF48DF47DF46DF45DF44DF43DF42DF39DF37DF35DF32DF29DF26DF23DF22DF20
DF19DF18DF17DF15DF13DF12DF11DF10DF8DF6DF5DF4DF3DE75DE70DE68DE63DE61DE56DE33DE29DE26DE23DE20DE15DE13DE8DE6DE1DD73DD71DD68DD66DD64DD61DD59DD57DD53DD52DD50DD49DD47DD46DD44DD43DD41DD40DD39DD37DD36DD35DD33DD32DD30DD29DD27DD26DD24DD23DD19DD17DD15DD12DD10DD8DD5DD3DC75DC72DC70DC68DC65DC63DC61DC58DC56DC54DC51DC48DC45DC42DC34DC31DC28DC25DC22DC20DC18DC15DC13DC11DC8DC6DC4DC1DB73DB68DB66DB61DB59DB54DB51DB48DB45DB42DB39DB37DB34DB31DB28DB25DB22DB17DB15DB10DB8DB3DA75DA72
DA56CY57CU58CT52CN54CM50CK31CK10CG42CF46CC22CB44BW25BV42AN20AM37AJ13AH33AE4AD31AA72AA42
U2540/40
VSS_V68VSS_BV42VSS_CT52VSS_CM50VSS_K59VSS_DA56VSS_CG42VSS_AE4VSS_AH33VSS_BW25VSS_CU58VSS_P25VSS_P68VSS_AN20VSS_CC22VSS_CF46VSS_V27VSS_AA42VSS_AD31VSS_AJ13VSS_AA72VSS_CK10VSS_CN54VSS_K23VSS_AM37VSS_CB44VSS_CK31VSS_CY57VSS_DJ73VSS_DJ68VSS_DJ66VSS_DJ63VSS_DJ61VSS_DJ59VSS_DJ49VSS_DJ43VSS_DJ19VSS_DJ15VSS_DJ7VSS_DH70VSS_DH68VSS_DH59VSS_DH55VSS_DH52VSS_DH49VSS_DH46VSS_DH43VSS_DH39VSS_DG75VSS_DG74VSS_DG70VSS_DG69VSS_DG68VSS_DG67VSS_DG66VSS_DG60VSS_DG59VSS_DG56VSS_DG55VSS_DG52VSS_DG49VSS_DG46VSS_DG27VSS_DG24VSS_DG21VSS_DG20VSS_DG18VSS_DG16VSS_DG15VSS_DG7VSS_DG6VSS_DG2VSS_DG1VSS_DF73VSS_DF72VSS_DF71VSS_DF65VSS_DF64VSS_DF63VSS_DF61VSS_DF59VSS_DF58VSS_DF57VSS_DF56VSS_DF52VSS_DF51VSS_DF50VSS_DF49VSS_DF48VSS_DF47VSS_DF46VSS_DF45VSS_DF44VSS_DF42VSS_DF39VSS_DF37VSS_DF35VSS_DF32VSS_DF29VSS_DF26VSS_DF23VSS_DF22VSS_DF20
VSS_DF13VSS_DF12VSS_DF11VSS_DF10VSS_DF8VSS_DF6VSS_DF5VSS_DE68VSS_DE63VSS_DE61VSS_DE56VSS_DE33VSS_DE29VSS_DE26VSS_DE8VSS_DE6VSS_DE1VSS_DD73VSS_DD71VSS_DD68VSS_DD66VSS_DD53VSS_DD52VSS_DD50VSS_DD49VSS_DD47VSS_DD46VSS_DD44VSS_DD37VSS_DD36VSS_DD35VSS_DD33VSS_DD32VSS_DD30VSS_DD29VSS_DD19VSS_DD17VSS_DD15VSS_DD12VSS_DD10VSS_DD8VSS_DD5VSS_DC68VSS_DC65VSS_DC63VSS_DC61VSS_DC58VSS_DC56VSS_DC54VSS_DC42VSS_DC34VSS_DC31VSS_DC28VSS_DC25VSS_DC22VSS_DC20VSS_DC18VSS_DC11VSS_DC8VSS_DC6VSS_DC4VSS_DC1VSS_DB73VSS_DB68VSS_DB66VSS_DB61VSS_DB45VSS_DB42VSS_DB39VSS_DB37VSS_DB34VSS_DB31VSS_DB28VSS_DB10VSS_DB8VSS_DB3VSS_DA75VSS_DA72
VSS_DH66VSS_DH64VSS_DH63VSS_DH61VSS_DH37VSS_DH18VSS_DH11VSS_DH5VSS_DG65VSS_DG63VSS_DG62VSS_DG61VSS_DG43VSS_DG41VSS_DG33VSS_DG30VSS_DG14VSS_DG13VSS_DG9VSS_DG8VSS_DF70VSS_DF68VSS_DF66VSS_DF54VSS_DF53VSS_DF43
VSS_DF19VSS_DF18VSS_DF17VSS_DF15VSS_DF4VSS_DF3VSS_DE75VSS_DE70VSS_DE23VSS_DE20VSS_DE15VSS_DE13VSS_DD64VSS_DD61VSS_DD59VSS_DD57VSS_DD43VSS_DD41VSS_DD40VSS_DD39VSS_DD27VSS_DD26VSS_DD24VSS_DD23VSS_DD3VSS_DC75VSS_DC72VSS_DC70VSS_DC51VSS_DC48VSS_DC45VSS_DC15VSS_DC13VSS_DB59VSS_DB54VSS_DB51VSS_DB48VSS_DB25VSS_DB22VSS_DB17VSS_DB15
SHEETDATE
DEPARTMENT
SIZE
PROJECT DOCUMENT NUMBER REV
REVIEWER
DESIGNER
123
7 3 2 1 6 5 4
E
A
B
C
E
D
C
B
A
7 6 5 4
D
C



INTERNAL PU
Thu Sep 14 16:11:55 2023<NAME_2><NAME_1>MB FABCGT AMDV0234 OF 365
P1V8_AUX
P3V3_AUXP3V3_AUXPVDD18_S5_P0PVDD18_S5_P0PVDD18_S5_P0283428342816634 8034 8081
34 8034 8028 3428 34CHIPCHIP 2.2K4.7KSN74LVC1G07DBVRSMLF04020.1UFTP_U27_ENX7R040225V25V25V0.1UF0.1UFPCA9617ADP10%10%10%
X7RX7RICSMB_CPU0_4_SCLSMB_CPU0_4_SDAFM_BIOS_POST_CMPLT_NSMB_CPU0_4_XLTR_SCLSMB_CPU0_4_XLTR_SDA
CPU0 GLUE LOGIC
SMLF
040204021000PF5%50VX7RICFM_BIOS_POST_CMPLT_BUF_NFM_BIOS_POST_CMPLT_BUF_R1_N49.9
4.7KSMB_CPU0_4_XLTR_SDA
0402LF1/16WCHIP5%4.7K4.7KSMB_CPU0_4_XLTR_SCL1/16WCHIP5%4.7K0402LFSMB_CPU0_4_SCLSMB_CPU0_4_SDA
21 R6100
21R498
21R495
2
1
R942
2
1 C226
4
5
13
2
U101
2
1
R943
2
1
C43
2
1 C42
81
63
72
4 5
U27
21R590
21R499
C5000
NC
Y
GND
A
VCC
GND
SCLB
SDABSDAA
SCLA
VCCBVCCA
EN
2
1
SHEETDATE
DEPARTMENT
SIZE
PROJECT DOCUMENT NUMBER REV
REVIEWER
DESIGNER
123
7 3 2 1 6 5 4
E
A
B
C
E
D
C
B
A
7 6 5 4
D
IN OUT
BI
OUT
BI
IN
OUT
OUT
OUT
OUT
C



Thu Aug 24 10:13:43 2023<NAME_2><NAME_1>MB FABCGT AMDV0235 OF 365Blank
SHEETDATE
DEPARTMENT
SIZE
PROJECT DOCUMENT NUMBER REV
REVIEWER
DESIGNER
123
7 3 2 1 6 5 4
E
A
B
C
E
D
C
B
A
7 6 5 4
D
C



Thu Aug 24 10:13:43 2023<NAME_2><NAME_1>MB FABCGT AMDV0236 OF 365Blank
SHEETDATE
DEPARTMENT
SIZE
PROJECT DOCUMENT NUMBER REV
REVIEWER
DESIGNER
123
7 3 2 1 6 5 4
E
A
B
C
E
D
C
B
A
7 6 5 4
D
C



Thu Sep 14 16:11:55 2023<NAME_2><NAME_1>MB FABCGT AMDV0237 OF 3659898989898989898989898989898
98989898
9898
989815M_A_CPU1_ALERT_R_NM_A_CPU1_ALERT_N1%0402LF
SOCKET6096_13568-001IO
TP_M_A_CPU1_SA_TEST40TP_M_A_CPU1_SA_TEST39AM_A_CPU1_SA_CA<6:0>M_A_CPU1_SB_CA<6:0>M_A_CPU1_CLK_DP<0>M_A_CPU1_CLK_DN<0>M_A_CPU1_SA_CS_N<0>M_A_CPU1_SA_CS_N<1>M_A_CPU1_SA_RSP<0>M_A_CPU1_SA_PARM_A_CPU1_SB_CS_N<0>M_A_CPU1_SB_CS_N<1>M_A_CPU1_SB_RSP<0>M_A_CPU1_SB_PARM_A_CPU1_RESET_N
M_A_CPU1_SA_DQS_DP<9:0>M_A_CPU1_SB_DQS_DP<9:0>M_A_CPU1_SB_DQS_DN<9:0>M_A_CPU1_SA_DQS_DN<9:0>
M_A_CPU1_SA_CB<7:0>M_A_CPU1_SB_CB<7:0>
M_A_CPU1_SA_DQ<31:0>M_A_CPU1_SB_DQ<31:0>
CPU1 DDR CHAR1958 PLACE CLOSE TO CPU < 25MM
SMLF
21R500
C60
BF72
BL74
BW74
DC73
CU73
CL73
CE73
BW73
DC74
CU74
CL74
CE74
BV74
DD72
CV72
CM72
CF72
BY72
DB74
CT74
CK74
CD74
DF74
DE74
DE73
DD74
DB72
DA74
DA73
CY74
CY72
CW74
CW73
CV74
CT72
CR74
CR73
CP74
CP72
CN74
CN73
CM74
CK72
CJ74
CJ73
CH74
CH72
CG74
CG73
CF74
CD72
CC74
CC73
CB74
BV72
BU74
BU73
BT74
CB72
CA74
CA73
BY74
BK74
BK72
BJ73
BJ74
BH74
BH72
BG73
BR74
BM74
BL73
BP74
BN74
BM72
BC73
AM72
AF72
Y72
P72
H72
AM74
AF74
Y74
P74
H74
AN73
AG73
AA73
R73
J73
AL74
AE74
W74
N74
G74
AJ73
AH74
AH72
AG74
AE73
AD74
AD72
AC74
AC73
AB74
AB72
AA74
W73
V74
V72
U74
U73
T74
T72
R74
N73
M74
M72
L74
L73
K74
K72
J74
G73
F74
F72
E74
AR73
AP74
AP72
AN74
AL73
AK74
AK72
AJ74
BB72
BB74
BA74
BA73
AY72
AY74
AW74
BP72
AV72
AU74
BN73
AW73
AV74
AT74
AR74
BG74
BF74
BD74
BC74
U26
5
6
4
3
2
0
1
6
5
4
3
2
1
0
9
8
7
9
8
7
6
5
4
6
5
3
2
4
3
2
1
0
1
0
9
8
7
9
8
6
5
4
6
7
5
3
2
4
3
1
0
2
1
0
6
7
5
3
4
2
1
0
7
6
5
4
3
1
2
0
31
30
29
28
27
26
25
24
23
22
21
20
19
17
18
16
15
13
14
12
11
9
10
8
7
5
6
4
2
3
0
1
31
30
29
28
27
26
24
25
23
21
22
20
19
18
16
17
15
13
14
11
12
10
8
9
7
6
4
5
3
2
0
1
1/40
TEST40
TEST39A
MA1_CLK_L
MA0_CLK_L
MA1_CLK_H
MAB_DQS_H9
MA0_CLK_H
MAB_PAR
MAA_PAR
MAA0_CS_L0
MAA_DATA3
MAA_DQS_H6
MAB_CA6
MAB_DATA2
MAB_DATA17
MAB_DATA28
MAB_DQS_H0
MAB_DQS_L4
MAA_CA6
MAA_DATA2
MAA_DQS_H5
MAA_DQS_L9
MAB1_RSP_L
MAB_CA5
MAB_CHECK7
MAB_DATA1
MAB_DATA16
MAB_DATA27
MAB_DQS_L3
MAA_CA5
MAA_DATA1
MAA_DQS_H4
MAA_DQS_L8
MAB0_RSP_L
MAB_CA4
MAB_CHECK6
MAB_DATA0
MAB_DATA15
MAB_DATA26
MAB_DQS_L2
MAA_CA4
MAA_DATA0
MAA_DQS_H3
MAA_DQS_L7
MAB_CA3
MAB_CHECK5
MAB_DATA14
MAB_DATA25
MAB_DQS_L1
MAA_CA3
MAA_DATA19
MAA_DQS_H2
MAA_DQS_L6
MAB_CA2
MAB_CHECK4
MAB_DATA13
MAB_DATA24
MAB_DQS_L0
MAA_CA2
MAA_DATA18
MAA_DATA29
MAA_DQS_H1
MAA_DQS_L5
MAB_CA1
MAB_CHECK3
MAB_DATA12
MAB_DATA23
MAA_CA1
MAA_DATA17
MAA_DATA28
MAA_DQS_H0
MAA_DQS_L4
MAB_CA0
MAB_CHECK2
MAB_DATA11
MAB_DATA22
MAA1_RSP_L
MAA_CA0
MAA_CHECK7
MAA_DATA16
MAA_DATA27
MAA_DQS_L3
MAB_CHECK1
MAB_DATA10
MAB_DATA21
MAA0_RSP_L
MAA_CHECK6
MAA_DATA15
MAA_DATA26
MAA_DQS_L2
MAB_CHECK0
MAB_DATA20
MAB_DATA31
MAA_CHECK5
MAA_DATA14
MAA_DATA25
MAA_DQS_L1
MAB1_CS_L1
MAB_DATA30
MAB_DQS_H8
MAA_CHECK4
MAA_DATA13
MAA_DATA24
MAA_DQS_L0
MAB0_CS_L1
MAB1_CS_L0
MAB_DATA9
MAB_DQS_H7
MAA_CHECK3
MAA_DATA9
MAA_DATA12
MAA_DATA23
MAB0_CS_L0
MAB_DATA8
MAB_DQS_H6
MAA_CHECK2
MAA_DATA8
MAA_DATA11
MAA_DATA22
MAB_DATA7
MAB_DQS_H5
MAB_DQS_L9
MAA_CHECK1
MAA_DATA7
MAA_DATA10
MAA_DATA21
MAB_DATA6
MAB_DQS_H4
MAB_DQS_L8
MAA_CHECK0
MAA_DATA6
MAA_DATA20
MAA_DATA31
MAA_DQS_H9
MAB_DATA5
MAB_DQS_H3
MAB_DQS_L7
MAA1_CS_L1
MAA_DATA5
MAA_DATA30
MAA_DQS_H8
MAB_DATA4
MAB_DATA19
MAB_DQS_H2
MAB_DQS_L6
MAA0_CS_L1
MAA1_CS_L0
MAA_DATA4
MAA_DQS_H7
MAB_DATA3
MAB_DATA18
MAB_DATA29
MAB_DQS_H1
MAB_DQS_L5
MA_RESET_L
MA_ALERT_L
CAD NOTE:
SHEETDATE
DEPARTMENT
SIZE
PROJECT DOCUMENT NUMBER REV
REVIEWER
DESIGNER
123
7 3 2 1 6 5 4
E
A
B
C
E
D
C
B
A
7 6 5 4
D
IN
OUT
OUT
IN
OUTOUT
OUT
IN
OUTOUT
OUTOUT
OUT
OUT
BIBI
BIBI
BI
BI
BI
BI
C



Thu Sep 14 16:11:55 2023<NAME_2><NAME_1>MB FABCGT AMDV0238 OF 3659999999999999999999999999999
99999999
9999
999915M_B_CPU1_ALERT_R_NM_B_CPU1_ALERT_N1%0402LF
SOCKET6096_13568-001IO
TP_M_B_CPU1_SA_TEST39BM_B_CPU1_SA_CA<6:0>M_B_CPU1_SB_CA<6:0>M_B_CPU1_CLK_DP<0>M_B_CPU1_CLK_DN<0>M_B_CPU1_SA_CS_N<0>M_B_CPU1_SA_CS_N<1>M_B_CPU1_SA_RSP<0>M_B_CPU1_SA_PARM_B_CPU1_SB_CS_N<1>M_B_CPU1_SB_CS_N<0>M_B_CPU1_SB_RSP<0>M_B_CPU1_SB_PARM_B_CPU1_RESET_N
M_B_CPU1_SA_DQS_DP<9:0>M_B_CPU1_SB_DQS_DP<9:0>M_B_CPU1_SB_DQS_DN<9:0>M_B_CPU1_SA_DQS_DN<9:0>
M_B_CPU1_SB_CB<7:0>M_B_CPU1_SA_CB<7:0>
M_B_CPU1_SA_DQ<31:0>M_B_CPU1_SB_DQ<31:0>
CPU1 DDR CHBR1959 PLACE CLOSE TO CPU < 25MM
SMLF
21R501
BF62
BL64
BW64
DC62
CU62
CL62
CE62
BW62
DC64
CU64
CL64
CE64
BV63
DD62
CV62
CM62
CF62
BY62
DB63
CT63
CK63
CD63
DF62
DE64
DE62
DD63
DB62
DA64
DA62
CY63
CY62
CW64
CW62
CV63
CT62
CR64
CR62
CP63
CP62
CN64
CN62
CM63
CK62
CJ64
CJ62
CH63
CH62
CG64
CG62
CF63
CD62
CC64
CC62
CB63
BV62
BU64
BU62
BT63
CB62
CA64
CA62
BY63
BK63
BK62
BJ62
BJ64
BH63
BH62
BG62
BR64
BM63
BL62
BP63
BN64
BM62
BC62
AM62
AF62
Y62
P62
H62
AM63
AF63
Y63
P63
H63
AN62
AG62
AA62
R62
J62
AL64
AE64
W64
N64
G64
AJ62
AH63
AH62
AG64
AE62
AD63
AD62
AC64
AC62
AB63
AB62
AA64
W62
V63
V62
U64
U62
T63
T62
R64
N62
M63
M62
L64
L62
K63
K62
J64
G62
F63
F62
E64
AR62
AP63
AP62
AN64
AL62
AK63
AK62
AJ64
BB62
BB63
BA64
BA62
AY62
AY63
AW64
BP62
AV62
AU64
BN62
AW62
AV63
AU62
AT62
BG64
BF63
BD63
BC64
U26
5
4
6
3
2
0
1
6
5
4
2
3
1
9
0
9
8
7
6
4
5
8
7
5
6
4
3
2
1
9
0
3
2
1
0
8
7
6
4
5
8
9
7
6
5
4
2
3
1
0
3
2
1
0
6
7
5
4
3
2
1
0
6
7
5
4
3
31
0
1
2
26
27
28
29
30
23
22
24
25
19
20
21
18
17
16
14
15
13
12
10
9
11
8
6
7
5
4
3
0
1
2
31
28
30
29
27
26
25
24
23
22
21
19
20
18
17
16
15
14
13
12
9
10
11
8
7
6
5
3
4
0
1
2
2/40
TEST39B
MBB_DATA20
MBA_DATA24
MBB_DATA19
MB1_CLK_L
MB1_CLK_H
MB0_CLK_L
MB0_CLK_H
MBB_PAR
MBA_PAR
MBB_DQS_H9
MBA_CHECK1
MBA_DATA10
MBA_DATA21
MBB_DQS_H4
MBB_DQS_L8
MBA1_CS_L1
MBA_CHECK0
MBA_DATA20
MBA_DATA31
MBA_DQS_H9
MBB_CA6
MBB_DQS_H3
MBB_DQS_L7
MBA0_CS_L1
MBA1_CS_L0
MBA_CA6
MBA_DATA30
MBA_DQS_H8
MBB_CA5
MBB_DQS_H2
MBB_DQS_L6
MBA0_CS_L0
MBA_CA5
MBA_DQS_H7
MBB_CA4
MBB_DATA18
MBB_DATA29
MBB_DQS_H1
MBB_DQS_L5
MBA_CA4
MBA_DQS_H6
MBB1_RSP_L
MBB_CA3
MBB_DATA9
MBB_DATA17
MBB_DATA28
MBB_DQS_H0
MBB_DQS_L4
MBA_CA3
MBA_DATA9MBA_DQS_H5
MBA_DQS_L9
MBB0_RSP_L
MBB_CA2
MBB_CHECK7
MBB_DATA8
MBB_DATA16
MBB_DATA27
MBB_DQS_L3
MBA_CA2
MBA_DATA8
MBA_DQS_H4
MBA_DQS_L8
MBB_CA1
MBB_CHECK6
MBB_DATA7
MBB_DATA15
MBB_DATA26
MBB_DQS_L2
MBA_CA1
MBA_DATA7
MBA_DQS_H3
MBA_DQS_L7
MBB_CA0
MBB_CHECK5
MBB_DATA6
MBB_DATA14
MBB_DATA25
MBB_DQS_L1
MBA_CA0
MBA_DATA6
MBA_DATA19
MBA_DQS_H2
MBA_DQS_L6
MBB_CHECK4
MBB_DATA5
MBB_DATA13
MBB_DATA24
MBB_DQS_L0
MBA_DATA5
MBA_DATA18
MBA_DATA29
MBA_DQS_H1
MBA_DQS_L5
MBB_CHECK3
MBB_DATA4
MBB_DATA12
MBB_DATA23
MBA1_RSP_L
MBA_DATA4
MBA_DATA17
MBA_DATA28
MBA_DQS_H0
MBA_DQS_L4
MBB_CHECK2
MBB_DATA3
MBB_DATA11
MBB_DATA22
MBA0_RSP_L
MBA_CHECK7
MBA_DATA3
MBA_DATA16
MBA_DATA27
MBA_DQS_L3
MBB_CHECK1
MBB_DATA2
MBB_DATA10
MBB_DATA21
MBA_CHECK6
MBA_DATA2
MBA_DATA15
MBA_DATA26
MBA_DQS_L2
MBB1_CS_L1
MBB_CHECK0
MBB_DATA1
MBB_DATA31
MBA_CHECK5
MBA_DATA1
MBA_DATA14
MBA_DATA25
MBA_DQS_L1
MBB0_CS_L1
MBB1_CS_L0
MBB_DATA0
MBB_DATA30
MBB_DQS_H8
MBA_CHECK4
MBA_DATA0
MBA_DATA13
MBA_DQS_L0
MBB0_CS_L0
MBB_DQS_H7
MBA_CHECK3
MBA_DATA12
MBA_DATA23
MBB_DQS_H6
MBA_CHECK2
MBA_DATA11
MBA_DATA22
MBB_DQS_H5
MBB_DQS_L9
MB_RESET_L
MB_ALERT_L
CAD NOTE:
SHEETDATE
DEPARTMENT
SIZE
PROJECT DOCUMENT NUMBER REV
REVIEWER
DESIGNER
123
7 3 2 1 6 5 4
E
A
B
C
E
D
C
B
A
7 6 5 4
D
OUT
IN
OUT
IN
OUTOUT
OUT
IN
OUTOUT
OUTOUT
OUT
OUT
BIBI
BIBI
BI
BI
BI
BI
C



Thu Sep 14 16:11:56 2023<NAME_2><NAME_1>MB FABCGT AMDV0239 OF 365100100100100100100100100100100100100100100100100100100100100
10010015M_C_CPU1_ALERT_R_NM_C_CPU1_ALERT_N1%0402LF
SOCKET6096_13568-001IOM_C_CPU1_SB_CA<6:0>M_C_CPU1_SA_CA<6:0>TP_M_C_CPU1_SA_TEST39CM_C_CPU1_CLK_DN<0>M_C_CPU1_CLK_DP<0>M_C_CPU1_SA_CS_N<1>M_C_CPU1_SA_CS_N<0>M_C_CPU1_SA_RSP<0>M_C_CPU1_SA_PARM_C_CPU1_SB_CS_N<0>M_C_CPU1_SB_CS_N<1>M_C_CPU1_SB_RSP<0>M_C_CPU1_SB_PARM_C_CPU1_RESET_NM_C_CPU1_SB_DQS_DN<9:0>M_C_CPU1_SA_DQS_DN<9:0>M_C_CPU1_SA_DQS_DP<9:0>M_C_CPU1_SB_DQS_DP<9:0>M_C_CPU1_SA_CB<7:0>M_C_CPU1_SB_CB<7:0>
M_C_CPU1_SA_DQ<31:0>M_C_CPU1_SB_DQ<31:0>
CPU1 DDR CHCR1960 PLACE CLOSE TO CPU < 25MM
SMLF
21R502
BF55
BL57
BW57
DC55
CU55
CL55
CE55
BW55
DC57
CU57
CL57
CE57
BV56
DD55
CV55
CM55
CF55
BY55
DB56
CT56
CK56
CD56
DF55
DE57
DE55
DD56
DB55
DA57
DA55
CY56
CY55
CW57
CW55
CV56
CT55
CR57
CR55
CP56
CP55
CN57
CN55
CM56
CK55
CJ57
CJ55
CH56
CH55
CG57
CG55
CF56
CD55
CC57
CC55
CB56
BV55
BU57
BU55
BT56
CB55
CA57
CA55
BY56
BK56
BK55
BJ55
BJ57
BH56
BH55
BG55
BR57
BM56
BL55
BP56
BN57
BM55
BC55
AM55
AF55
Y55
P55
H55
AM56
AF56
Y56
P56
H56
AN55
AG55
AA55
R55
J55
AL57
AE57
W57
N57
G57
AJ55
AH56
AH55
AG57
AE55
AD56
AD55
AC57
AC55
AB56
AB55
AA57
W55
V56
V55
U57
U55
T56
T55
R57
N55
M56
M55
L57
L55
K56
K55
J57
G55
F56
F55
E57
AR55
AP56
AP55
AN57
AL55
AK56
AK55
AJ57
BB55
BB56
BA57
BA55
AY55
AY56
AW57
BP55
AV55
AU57
BN55
AW55
AV56
AU55
AT55
BG57
BF56
BD56
BC57
U26
6
5
4
3
0
1
2
6
5
4
2
3
0
1
9
8
7
6
4
5
8
9
7
6
4
5
3
2
1
0
9
3
2
1
0
8
7
6
4
5
9
7
8
6
5
3
2
0
1
3
4
2
1
0
6
7
5
4
3
2
1
0
7
6
3
4
5
0
31
2
1
30
29
26
28
27
23
25
24
22
20
21
19
17
18
16
14
15
13
11
12
10
8
9
7
4
5
6
2
3
1
0
31
29
30
27
28
26
24
25
22
23
20
21
17
18
19
16
15
14
13
11
12
10
8
9
7
4
5
6
2
3
1
0
3/40
TEST39C
MC1_CLK_L
MC1_CLK_H
MC0_CLK_L
MC0_CLK_H
MCB_PAR
MCA_PAR
MCB_DQS_H9
MCA_CHECK4
MCA_DATA8
MCA_DATA13
MCA_DATA24
MCA_DQS_L0
MCB0_CS_L0
MCB1_CS_L0
MCB_DATA7
MCB_DQS_H7
MCA_CHECK3
MCA_DATA7
MCA_DATA12
MCA_DATA23
MCB_DATA6
MCB_DQS_H6
MCA_CHECK2
MCA_DATA6
MCA_DATA11
MCA_DATA22
MCB_CA6
MCB_DATA5
MCB_DQS_H5
MCB_DQS_L9
MCA_CA6
MCA_CHECK1
MCA_DATA5
MCA_DATA10
MCA_DATA21
MCB_CA5
MCB_DATA4
MCB_DQS_H4
MCB_DQS_L8
MCA_CA5
MCA_CHECK0
MCA_DATA4
MCA_DATA20
MCA_DATA31
MCA_DQS_H9
MCB_CA4
MCB_DATA3
MCB_DQS_H3
MCB_DQS_L7
MCA1_CS_L1
MCA_CA4
MCA_DATA3
MCA_DATA30
MCA_DQS_H8
MCB_CA3
MCB_DATA2
MCB_DATA19
MCB_DQS_H2
MCB_DQS_L6
MCA0_CS_L1
MCA1_CS_L0
MCA_CA3
MCA_DATA2
MCA_DQS_H7
MCB_CA2
MCB_DATA1
MCB_DATA18
MCB_DATA29
MCB_DQS_H1
MCB_DQS_L5
MCA0_CS_L0
MCA_CA2
MCA_DATA1
MCA_DQS_H6
MCB_CA1
MCB_DATA0
MCB_DATA17
MCB_DATA28
MCB_DQS_H0
MCB_DQS_L4
MCA_CA1
MCA_DATA0
MCA_DQS_H5
MCA_DQS_L9
MCB0_RSP_L
MCB1_RSP_L
MCB_CA0
MCB_CHECK7
MCB_DATA16
MCB_DATA27
MCB_DQS_L3
MCA_CA0
MCA_DQS_H4
MCA_DQS_L8
MCB_CHECK6
MCB_DATA15
MCB_DATA26
MCB_DQS_L2
MCA_DQS_H3
MCA_DQS_L7
MCB_CHECK5
MCB_DATA14
MCB_DATA25
MCB_DQS_L1
MCA_DATA19
MCA_DQS_H2
MCA_DQS_L6
MCB_CHECK4
MCB_DATA13
MCB_DATA24
MCB_DQS_L0
MCA_DATA18
MCA_DATA29
MCA_DQS_H1
MCA_DQS_L5
MCB_CHECK3
MCB_DATA12
MCB_DATA23
MCA_DATA17
MCA_DATA28
MCA_DQS_H0
MCA_DQS_L4
MCB_CHECK2
MCB_DATA11
MCB_DATA22
MCA1_RSP_L
MCA_CHECK7
MCA_DATA16
MCA_DATA27
MCA_DQS_L3
MCB_CHECK1
MCB_DATA10
MCB_DATA21
MCA0_RSP_L
MCA_CHECK6
MCA_DATA15
MCA_DATA26
MCA_DQS_L2
MCB_CHECK0
MCB_DATA9
MCB_DATA20
MCB_DATA31
MCA_CHECK5
MCA_DATA9
MCA_DATA14
MCA_DATA25
MCA_DQS_L1
MCB0_CS_L1
MCB1_CS_L1
MCB_DATA8
MCB_DATA30
MCB_DQS_H8
MC_RESET_L
MC_ALERT_L
CAD NOTE:
SHEETDATE
DEPARTMENT
SIZE
PROJECT DOCUMENT NUMBER REV
REVIEWER
DESIGNER
123
7 3 2 1 6 5 4
E
A
B
C
E
D
C
B
A
7 6 5 4
D
IN
OUT
OUT
IN
OUTOUT
OUT
IN
OUTOUT
OUTOUT
OUT
OUT
BIBI
BIBI
BI
BI
BI
BI
C



Thu Sep 14 16:11:56 2023<NAME_2><NAME_1>MB FABCGT AMDV0240 OF 365101101101101101101101101101101101101101101
101101101101
101101
10110115M_D_CPU1_ALERT_R_NM_D_CPU1_ALERT_N1%0402LF
SOCKET6096_13568-001IO
TP_M_D_CPU1_SA_TEST39DM_D_CPU1_SA_CA<6:0>M_D_CPU1_SB_CA<6:0>M_D_CPU1_CLK_DP<0>M_D_CPU1_CLK_DN<0>M_D_CPU1_SA_CS_N<0>M_D_CPU1_SA_CS_N<1>M_D_CPU1_SA_RSP<0>M_D_CPU1_SA_PARM_D_CPU1_SB_CS_N<0>M_D_CPU1_SB_CS_N<1>M_D_CPU1_SB_RSP<0>M_D_CPU1_SB_PARM_D_CPU1_RESET_N
M_D_CPU1_SA_DQS_DP<9:0>M_D_CPU1_SB_DQS_DP<9:0>M_D_CPU1_SB_DQS_DN<9:0>M_D_CPU1_SA_DQS_DN<9:0>
M_D_CPU1_SB_CB<7:0>M_D_CPU1_SA_CB<7:0>
M_D_CPU1_SA_DQ<31:0>M_D_CPU1_SB_DQ<31:0>
CPU1 DDR CHDR1961 PLACE CLOSE TO CPU < 25MM
SMLF
21R503
BF58
BL60
BW60
DC59
CU59
CL59
CE59
BW59
DC60
CU60
CL60
CE60
BV60
DD58
CV58
CM58
CF58
BY58
DB60
CT60
CK60
CD60
DF60
DE60
DE59
DD60
DB58
DA60
DA59
CY60
CY58
CW60
CW59
CV60
CT58
CR60
CR59
CP60
CP58
CN60
CN59
CM60
CK58
CJ60
CJ59
CH60
CH58
CG60
CG59
CF60
CD58
CC60
CC59
CB60
BV58
BU60
BU59
BT60
CB58
CA60
CA59
BY60
BK60
BK58
BJ59
BJ60
BH60
BH58
BG59
BR60
BM60
BL59
BP60
BN60
BM58
BC59
AM58
AF58
Y58
P58
H58
AM60
AF60
Y60
P60
H60
AN59
AG59
AA59
R59
J59
AL60
AE60
W60
N60
G60
AJ59
AH60
AH58
AG60
AE59
AD60
AD58
AC60
AC59
AB60
AB58
AA60
W59
V60
V58
U60
U59
T60
T58
R60
N59
M60
M58
L60
L59
K60
K58
J60
G59
F60
F58
E60
AR59
AP60
AP58
AN60
AL59
AK60
AK58
AJ60
BB58
BB60
BA60
BA59
AY58
AY60
AW60
BP58
AV58
AU60
BN59
AW59
AV60
AU59
AT58
BG60
BF60
BD60
BC60
U26
6
5
4
2
3
0
1
6
5
4
3
2
0
1
9
9
8
7
6
5
4
8
7
6
5
4
3
2
1
0
9
3
2
1
0
8
7
6
5
4
9
8
7
6
5
4
3
2
1
0
3
2
1
0
5
4
6
7
2
3
0
1
7
6
5
4
3
1
2
0
31
27
26
28
30
29
25
22
23
24
20
19
21
18
17
16
13
12
14
15
9
8
10
11
7
6
5
3
4
0
2
31
1
27
26
28
30
29
25
24
23
22
17
18
19
21
20
13
12
14
15
16
8
9
10
11
7
6
5
3
4
0
2
1
4/40
TEST39D
MD1_CLK_L
MD1_CLK_H
MD0_CLK_L
MD0_CLK_H
MDB_DQS_H9
MDB_CA3
MDB_PAR
MDA_PAR
MDA1_RSP_L
MDA_DATA2
MDA_DATA17
MDA_DATA28
MDA_DQS_H0
MDA_DQS_L4
MDB_CHECK2
MDB_DATA1
MDB_DATA11
MDB_DATA22
MDA0_RSP_L
MDA_CHECK7
MDA_DATA1
MDA_DATA16
MDA_DATA27
MDA_DQS_L3
MDB_CHECK1
MDB_DATA0
MDB_DATA10
MDB_DATA21
MDA_CHECK6
MDA_DATA0
MDA_DATA15
MDA_DATA26
MDA_DQS_L2
MDB1_CS_L1
MDB_CHECK0
MDB_DATA20
MDB_DATA31
MDA_CHECK5
MDA_DATA14
MDA_DATA25
MDA_DQS_L1
MDB0_CS_L1
MDB1_CS_L0
MDB_CA6
MDB_DATA30
MDB_DQS_H8
MDA_CA6
MDA_CHECK4
MDA_DATA13
MDA_DATA24
MDA_DQS_L0
MDB0_CS_L0
MDB_CA5
MDB_DQS_H7
MDA_CA5
MDA_CHECK3
MDA_DATA12
MDA_DATA23
MDB_CA4
MDB_DQS_H6
MDA_CA4
MDA_CHECK2
MDA_DATA11
MDA_DATA22
MDB_DQS_H5
MDB_DQS_L9
MDA_CA3
MDA_CHECK1
MDA_DATA10
MDA_DATA21
MDB_CA2
MDB_DQS_H4
MDB_DQS_L8
MDA1_CS_L1
MDA_CA2
MDA_CHECK0
MDA_DATA20
MDA_DATA31
MDA_DQS_H9
MDB_CA1
MDB_DQS_H3
MDB_DQS_L7
MDA0_CS_L1
MDA1_CS_L0
MDA_CA1
MDA_DATA30
MDA_DQS_H8
MDB_CA0
MDB_DATA9
MDB_DATA19
MDB_DQS_H2
MDB_DQS_L6
MDA0_CS_L0
MDA_CA0
MDA_DATA9
MDA_DQS_H7
MDB_DATA8
MDB_DATA18
MDB_DATA29
MDB_DQS_H1
MDB_DQS_L5
MDA_DATA8
MDA_DQS_H6
MDB1_RSP_L
MDB_DATA7
MDB_DATA17
MDB_DATA28
MDB_DQS_H0
MDB_DQS_L4
MDA_DATA7
MDA_DQS_H5
MDA_DQS_L9
MDB0_RSP_L
MDB_CHECK7
MDB_DATA6
MDB_DATA16
MDB_DATA27
MDB_DQS_L3
MDA_DATA6
MDA_DQS_H4
MDA_DQS_L8
MDB_CHECK6
MDB_DATA5
MDB_DATA15
MDB_DATA26
MDB_DQS_L2
MDA_DATA5
MDA_DQS_H3
MDA_DQS_L7
MDB_CHECK5
MDB_DATA4
MDB_DATA14
MDB_DATA25
MDB_DQS_L1
MDA_DATA4
MDA_DATA19
MDA_DQS_H2
MDA_DQS_L6
MDB_CHECK4
MDB_DATA3
MDB_DATA13
MDB_DATA24
MDB_DQS_L0
MDA_DATA3
MDA_DATA18
MDA_DATA29
MDA_DQS_H1
MDA_DQS_L5
MDB_CHECK3
MDB_DATA2
MDB_DATA12
MDB_DATA23
MD_RESET_L
MD_ALERT_L
CAD NOTE:
SHEETDATE
DEPARTMENT
SIZE
PROJECT DOCUMENT NUMBER REV
REVIEWER
DESIGNER
123
7 3 2 1 6 5 4
E
A
B
C
E
D
C
B
A
7 6 5 4
D
OUT
IN
OUT
IN
OUTOUT
OUT
IN
OUTOUT
OUTOUT
OUT
OUT
BIBI
BIBI
BI
BI
BI
BI
C



Thu Sep 14 16:11:56 2023<NAME_2><NAME_1>MB FABCGT AMDV0241 OF 365102102102102102102102102102102102102102102
102102102102
102102
10210215M_E_CPU1_ALERT_R_NM_E_CPU1_ALERT_N1%0402LF
SOCKET6096_13568-001IO
TP_M_E_CPU1_SA_TEST39EM_E_CPU1_SA_CA<6:0>M_E_CPU1_SB_CA<6:0>M_E_CPU1_CLK_DP<0>M_E_CPU1_CLK_DN<0>M_E_CPU1_SA_CS_N<0>M_E_CPU1_SA_RSP<0>M_E_CPU1_SA_CS_N<1>M_E_CPU1_SA_PARM_E_CPU1_SB_CS_N<1>M_E_CPU1_SB_CS_N<0>M_E_CPU1_SB_RSP<0>M_E_CPU1_SB_PARM_E_CPU1_RESET_N
M_E_CPU1_SA_DQS_DP<9:0>M_E_CPU1_SB_DQS_DP<9:0>M_E_CPU1_SB_DQS_DN<9:0>M_E_CPU1_SA_DQS_DN<9:0>
M_E_CPU1_SB_CB<7:0>M_E_CPU1_SA_CB<7:0>
M_E_CPU1_SA_DQ<31:0>M_E_CPU1_SB_DQ<31:0>
CPU1 DDR CHER1962 PLACE CLOSE TO CPU < 25MM
SMLF
21R504
BF69
BL71
BW71
DC69
CU69
CL69
CE69
BW69
DC71
CU71
CL71
CE71
BV70
DD69
CV69
CM69
CF69
BY69
DB70
CT70
CK70
CD70
DF69
DE71
DE69
DD70
DB69
DA71
DA69
CY70
CY69
CW71
CW69
CV70
CT69
CR71
CR69
CP70
CP69
CN71
CN69
CM70
CK69
CJ71
CJ69
CH70
CH69
CG71
CG69
CF70
CD69
CC71
CC69
CB70
BV69
BU71
BU69
BT70
CB69
CA71
CA69
BY70
BK70
BK69
BJ69
BJ71
BH70
BH69
BG69
BR71
BM70
BL69
BP70
BN71
BM69
BC69
AM69
AF69
Y69
P69
H69
AM70
AF70
Y70
P70
H70
AN69
AG69
AA69
R69
J69
AL71
AE71
W71
N71
G71
AJ69
AH70
AH69
AG71
AE69
AD70
AD69
AC71
AC69
AB70
AB69
AA71
W69
V70
V69
U71
U69
T70
T69
R71
N69
M70
M69
L71
L69
K70
K69
J71
G69
F70
F69
E71
AR69
AP70
AP69
AN71
AL69
AK70
AK69
AJ71
BB69
BB70
BA71
BA69
AY69
AY70
AW71
BP69
AV69
AU71
BN69
AW69
AV70
AU69
AT69
BG71
BF70
BD70
BC71
U26
5
6
4
3
2
1
0
6
5
4
3
2
1
0
9
8
9
7
6
5
4
3
7
8
6
4
5
2
1
0
9
3
2
1
9
0
7
8
6
5
4
3
7
8
6
4
5
2
1
0
2
3
1
0
7
6
4
5
3
2
1
0
7
6
4
5
2
3
1
0
31
30
29
27
28
26
25
23
24
21
22
19
20
18
17
16
15
14
13
12
11
10
9
8
7
6
5
3
4
2
1
0
31
30
29
27
28
26
25
24
23
22
21
19
20
18
17
16
15
14
13
12
11
10
9
8
7
6
5
4
3
2
1
0
5/40
TEST39E
ME1_CLK_L
ME1_CLK_H
ME0_CLK_L
ME0_CLK_H
MEB_DQS_H9
MEB_PAR
MEA_PAR
MEA_DQS_H3
MEA_DQS_L7
MEB_CHECK5
MEB_DATA14
MEB_DATA25
MEB_DQS_L1
MEA_DATA19
MEA_DQS_H2
MEA_DQS_L6
MEB_CHECK4
MEB_DATA13
MEB_DATA24
MEB_DQS_L0
MEA_DATA18
MEA_DATA29
MEA_DQS_H1
MEA_DQS_L5
MEB_CHECK3
MEB_DATA12
MEB_DATA23
MEA_DATA17
MEA_DATA28
MEA_DQS_H0
MEA_DQS_L4
MEB_CHECK2
MEB_DATA9
MEB_DATA11
MEB_DATA22
MEA0_RSP_L
MEA1_RSP_L
MEA_CHECK7
MEA_DATA9
MEA_DATA16
MEA_DATA27
MEA_DQS_L3
MEB_CA6
MEB_CHECK1
MEB_DATA8
MEB_DATA10
MEB_DATA21
MEA_CA6
MEA_CHECK6
MEA_DATA8
MEA_DATA15
MEA_DATA26
MEA_DQS_L2
MEB_CA5
MEB_CHECK0
MEB_DATA7
MEB_DATA20
MEB_DATA31
MEA_CA5
MEA_CHECK5
MEA_DATA7
MEA_DATA14
MEA_DATA25
MEA_DQS_L1
MEB0_CS_L1
MEB1_CS_L1
MEB_CA4
MEB_DATA6
MEB_DATA30
MEB_DQS_H8
MEA_CA4
MEA_CHECK4
MEA_DATA6
MEA_DATA13
MEA_DATA24
MEA_DQS_L0
MEB0_CS_L0
MEB1_CS_L0
MEB_CA3
MEB_DATA5
MEB_DQS_H7
MEA_CA3
MEA_CHECK3
MEA_DATA5
MEA_DATA12
MEA_DATA23
MEB_CA2
MEB_DATA4
MEB_DQS_H6
MEA_CA2
MEA_CHECK2
MEA_DATA4
MEA_DATA11
MEA_DATA22
MEB_CA1
MEB_DATA3
MEB_DQS_H5
MEB_DQS_L9
MEA_CA1
MEA_CHECK1
MEA_DATA3
MEA_DATA10
MEA_DATA21
MEB_CA0
MEB_DATA2
MEB_DQS_H4
MEB_DQS_L8
MEA_CA0
MEA_CHECK0
MEA_DATA2
MEA_DATA20
MEA_DATA31
MEA_DQS_H9
MEB_DATA1
MEB_DQS_H3
MEB_DQS_L7
MEA0_CS_L1
MEA1_CS_L1
MEA_DATA1
MEA_DATA30
MEA_DQS_H8
MEB_DATA0
MEB_DATA19
MEB_DQS_H2
MEB_DQS_L6
MEA0_CS_L0
MEA1_CS_L0
MEA_DATA0
MEA_DQS_H7
MEB_DATA18
MEB_DATA29
MEB_DQS_H1
MEB_DQS_L5
MEA_DQS_H6
MEB_DATA17
MEB_DATA28
MEB_DQS_H0
MEB_DQS_L4
MEA_DQS_H5
MEA_DQS_L9
MEB0_RSP_L
MEB1_RSP_L
MEB_CHECK7
MEB_DATA16
MEB_DATA27
MEB_DQS_L3
MEA_DQS_H4
MEA_DQS_L8
MEB_CHECK6
MEB_DATA15
MEB_DATA26
MEB_DQS_L2
ME_RESET_L
ME_ALERT_L
CAD NOTE:
SHEETDATE
DEPARTMENT
SIZE
PROJECT DOCUMENT NUMBER REV
REVIEWER
DESIGNER
123
7 3 2 1 6 5 4
E
A
B
C
E
D
C
B
A
7 6 5 4
D
OUT
IN
OUT
IN
OUTOUT
OUT
OUT
IN
OUT
OUTOUT
OUT
OUT
BIBI
BIBI
BI
BI
BI
BI
C



Thu Sep 14 16:11:56 2023<NAME_2><NAME_1>MB FABCGT AMDV0242 OF 365103103103103103103103103103103103103103103
103103103103
103103103103
15M_F_CPU1_ALERT_R_NM_F_CPU1_ALERT_N1%0402LF
SOCKET6096_13568-001IO
TP_M_F_CPU1_SA_TEST39FM_F_CPU1_SA_CA<6:0>M_F_CPU1_SB_CA<6:0>M_F_CPU1_CLK_DP<0>M_F_CPU1_CLK_DN<0>M_F_CPU1_SA_CS_N<0>M_F_CPU1_SA_CS_N<1>M_F_CPU1_SA_RSP<0>M_F_CPU1_SA_PARM_F_CPU1_SB_CS_N<0>M_F_CPU1_SB_CS_N<1>M_F_CPU1_SB_RSP<0>M_F_CPU1_SB_PARM_F_CPU1_RESET_N
M_F_CPU1_SA_DQS_DP<9:0>M_F_CPU1_SB_DQS_DP<9:0>M_F_CPU1_SB_DQS_DN<9:0>M_F_CPU1_SA_DQS_DN<9:0>
M_F_CPU1_SA_CB<7:0>M_F_CPU1_SB_CB<7:0>M_F_CPU1_SB_DQ<31:0>M_F_CPU1_SA_DQ<31:0>
CPU1 DDR CHFR1963 PLACE CLOSE TO CPU < 25MM
SMLF
21R505
BF65
BL67
BW67
DC66
CU66
CL66
CE66
BW66
DC67
CU67
CL67
CE67
BV67
DD65
CV65
CM65
CF65
BY65
DB67
CT67
CK67
CD67
DF67
DE67
DE66
DD67
DB65
DA67
DA66
CY67
CY65
CW67
CW66
CV67
CT65
CR67
CR66
CP67
CP65
CN67
CN66
CM67
CK65
CJ67
CJ66
CH67
CH65
CG67
CG66
CF67
CD65
CC67
CC66
CB67
BV65
BU67
BU66
BT67
CB65
CA67
CA66
BY67
BK67
BK65
BJ66
BJ67
BH67
BH65
BG66
BR67
BM67
BL66
BP67
BN67
BM65
BC66
AM65
AF65
Y65
P65
H65
AM67
AF67
Y67
P67
H67
AN66
AG66
AA66
R66
J66
AL67
AE67
W67
N67
G67
AJ66
AH67
AH65
AG67
AE66
AD67
AD65
AC67
AC66
AB67
AB65
AA67
W66
V67
V65
U67
U66
T67
T65
R67
N66
M67
M65
L67
L66
K67
K65
J67
G66
F67
F65
E67
AR66
AP67
AP65
AN67
AL66
AK67
AK65
AJ67
BB65
BB67
BA67
BA66
AY65
AY67
AW67
BP65
AV65
AU67
BN66
AW66
AV67
AU66
AT65
BG67
BF67
BD67
BC67
U26
6
5
4
3
1
2
0
6
5
4
3
2
0
1
8
9
7
6
5
9
8
7
5
6
4
3
2
1
0
4
3
2
0
1
9
8
7
6
5
8
9
7
6
4
3
2
1
0
4
5
3
2
1
0
7
5
4
6
3
2
0
1
6
5
7
4
3
0
2
1
31
30
28
29
26
27
25
24
22
23
21
19
20
18
17
16
15
13
12
14
11
10
8
9
6
7
5
3
4
2
1
0
31
29
30
28
27
26
24
25
22
23
21
20
19
18
17
16
15
14
12
13
10
11
9
8
7
6
4
3
5
2
1
0
6/40
TEST39F
MF1_CLK_L
MF1_CLK_H
MF0_CLK_L
MF0_CLK_H
MFB_DQS_H9
MFB_PAR
MFA_PAR
MFA0_CS_L0
MFA_DATA7
MFA_DQS_H7
MFB_DATA6
MFB_DATA18
MFB_DATA29
MFB_DQS_H1
MFB_DQS_L5
MFA_DATA6
MFA_DQS_H6
MFB1_RSP_L
MFB_DATA5
MFB_DATA17
MFB_DATA28
MFB_DQS_H0
MFB_DQS_L4
MFA_DATA5
MFA_DQS_H5
MFA_DQS_L9
MFB0_RSP_L
MFB_CHECK7
MFB_DATA4
MFB_DATA16
MFB_DATA27
MFB_DQS_L3
MFA_DATA4
MFA_DQS_H4
MFA_DQS_L8
MFB_CHECK6
MFB_DATA3
MFB_DATA15
MFB_DATA26
MFB_DQS_L2
MFA_DATA3
MFA_DQS_H3
MFA_DQS_L7
MFB_CHECK5
MFB_DATA2
MFB_DATA14
MFB_DATA25
MFB_DQS_L1
MFA_DATA2
MFA_DATA19
MFA_DQS_H2
MFA_DQS_L6
MFB_CA6
MFB_CHECK4
MFB_DATA1
MFB_DATA13
MFB_DATA24
MFB_DQS_L0
MFA_CA6
MFA_DATA1
MFA_DATA18
MFA_DATA29
MFA_DQS_H1
MFA_DQS_L5
MFB_CA5
MFB_CHECK3
MFB_DATA0
MFB_DATA12
MFB_DATA23
MFA1_RSP_L
MFA_CA5
MFA_DATA0
MFA_DATA17
MFA_DATA28
MFA_DQS_H0
MFA_DQS_L4
MFB_CA4
MFB_CHECK2
MFB_DATA11
MFB_DATA22
MFA0_RSP_L
MFA_CA4
MFA_CHECK7
MFA_DATA16
MFA_DATA27
MFA_DQS_L3
MFB_CA3
MFB_CHECK1
MFB_DATA10
MFB_DATA21
MFA_CA3
MFA_CHECK6
MFA_DATA15
MFA_DATA26
MFA_DQS_L2
MFB1_CS_L1
MFB_CA2
MFB_CHECK0
MFB_DATA20
MFB_DATA31
MFA_CA2
MFA_CHECK5
MFA_DATA14
MFA_DATA25
MFA_DQS_L1
MFB0_CS_L1
MFB1_CS_L0
MFB_CA1
MFB_DATA30
MFB_DQS_H8
MFA_CA1
MFA_CHECK4
MFA_DATA13
MFA_DATA24
MFA_DQS_L0
MFB0_CS_L0
MFB_CA0
MFB_DQS_H7
MFA_CA0
MFA_CHECK3
MFA_DATA12
MFA_DATA23
MFB_DQS_H6
MFA_CHECK2
MFA_DATA11
MFA_DATA22
MFB_DQS_H5
MFB_DQS_L9
MFA_CHECK1
MFA_DATA10
MFA_DATA21
MFB_DATA9
MFB_DQS_H4
MFB_DQS_L8
MFA1_CS_L1
MFA_CHECK0
MFA_DATA9
MFA_DATA20
MFA_DATA31
MFA_DQS_H9
MFB_DATA8
MFB_DQS_H3
MFB_DQS_L7
MFA0_CS_L1
MFA1_CS_L0
MFA_DATA8
MFA_DATA30
MFA_DQS_H8
MFB_DATA7
MFB_DATA19
MFB_DQS_H2
MFB_DQS_L6
MF_RESET_L
MF_ALERT_L
CAD NOTE:
SHEETDATE
DEPARTMENT
SIZE
PROJECT DOCUMENT NUMBER REV
REVIEWER
DESIGNER
123
7 3 2 1 6 5 4
E
A
B
C
E
D
C
B
A
7 6 5 4
D
IN
OUT
OUT
IN
OUTOUT
OUT
IN
OUTOUT
OUTOUT
OUT
OUT
BIBI
BIBI
BI
BI
BI
BI
C



Thu Sep 14 16:11:57 2023<NAME_2><NAME_1>MB FABCGT AMDV0243 OF 365104104104104104104104104104104104104104104
104104104104
104104
10410415M_G_CPU1_ALERT_R_NM_G_CPU1_ALERT_N1%0402LF
SOCKET6096_13568-001IO
TP_M_G_CPU1_SA_TEST39GM_G_CPU1_SA_CA<6:0>M_G_CPU1_SB_CA<6:0>M_G_CPU1_CLK_DN<0>M_G_CPU1_CLK_DP<0>M_G_CPU1_SA_CS_N<0>M_G_CPU1_SA_CS_N<1>M_G_CPU1_SA_PARM_G_CPU1_SA_RSP<0>M_G_CPU1_SB_CS_N<0>M_G_CPU1_SB_CS_N<1>M_G_CPU1_SB_RSP<0>M_G_CPU1_SB_PARM_G_CPU1_RESET_N
M_G_CPU1_SA_DQS_DP<9:0>M_G_CPU1_SB_DQS_DP<9:0>M_G_CPU1_SB_DQS_DN<9:0>M_G_CPU1_SA_DQS_DN<9:0>
M_G_CPU1_SA_CB<7:0>M_G_CPU1_SB_CB<7:0>
M_G_CPU1_SA_DQ<31:0>M_G_CPU1_SB_DQ<31:0>
CPU1 DDR CHGR1964 PLACE CLOSE TO CPU < 25MM
SMLF
21R506
BF4
BL3
BW2
DC3
CU3
CL3
CE3
BW3
DC2
CU2
CL2
CE2
BV2
DD4
CV4
CM4
CF4
BY4
DB2
CT2
CK2
CD2
DF2
DE2
DE3
DD2
DB4
DA2
DA3
CY2
CY4
CW2
CW3
CV2
CT4
CR2
CR3
CP2
CP4
CN2
CN3
CM2
CK4
CJ2
CJ3
CH2
CH4
CG2
CG3
CF2
CD4
CC2
CC3
CB2
BV4
BU2
BU3
BT2
CB4
CA2
CA3
BY2
BK2
BK4
BJ3
BJ2
BH2
BH4
BG3
BR2
BM2
BL2
BP2
BN2
BM4
BC3
AM4
AF4
Y4
P4
H4
AM2
AF2
Y2
P2
H2
AN3
AG3
AA3
R3
J3
AL2
AE2
W2
N2
G2
AJ3
AH2
AH4
AG2
AE3
AD2
AD4
AC2
AC3
AB2
AB4
AA2
W3
V2
V4
U2
U3
T2
T4
R2
N3
M2
M4
L2
L3
K2
K4
J2
G3
F2
F4
E2
AR3
AP2
AP4
AN2
AL3
AK2
AK4
AJ2
BB4
BB2
BA2
BA3
AY4
AY2
AW2
BP4
AW3
AV2
BN3
AV4
AU2
AT2
AR2
BG2
BF2
BD2
BC2
U26
6
5
4
3
2
1
0
6
5
4
3
2
1
0
9
8
7
6
5
4
9
8
7
6
5
4
3
2
1
0
9
3
2
1
0
8
7
6
5
4
9
8
7
6
5
3
2
1
0
4
3
2
1
0
7
5
6
3
4
2
0
1
7
6
5
4
3
2
1
0
31
30
29
27
28
26
25
24
22
23
21
20
19
18
17
16
15
14
13
12
11
10
9
8
7
6
5
4
2
3
1
0
31
30
29
28
27
26
25
24
23
22
21
20
18
19
17
16
14
15
13
12
11
10
9
8
7
6
5
4
2
3
1
0
7/40
TEST39G
MG1_CLK_L
MG1_CLK_H
MG0_CLK_L
MG0_CLK_H
MGA_PAR
MGB_DQS_H9
MGB_PAR
MGA_CHECK1
MGA_DATA0
MGA_DATA10
MGA_DATA21
MGB_DATA0
MGB_DQS_H4
MGB_DQS_L8
MGA_CHECK0
MGA_DATA20
MGA_DATA31
MGA_DQS_H9
MGB_DQS_H3
MGB_DQS_L7
MGA0_CS_L1
MGA1_CS_L1
MGA_DATA30
MGA_DQS_H8
MGB_DATA19
MGB_DQS_H2
MGB_DQS_L6
MGA0_CS_L0
MGA1_CS_L0
MGA_DQS_H7
MGB_DATA18
MGB_DATA29
MGB_DQS_H1
MGB_DQS_L5
MGA_DQS_H6
MGB_DATA17
MGB_DATA28
MGB_DQS_H0
MGB_DQS_L4
MGA_DQS_H5
MGA_DQS_L9
MGB0_RSP_L
MGB1_RSP_L
MGB_CHECK7
MGB_DATA16
MGB_DATA27
MGB_DQS_L3
MGA_DQS_H4
MGA_DQS_L8
MGB_CA6
MGB_CHECK6
MGB_DATA15
MGB_DATA26
MGB_DQS_L2
MGA_CA6
MGA_DQS_H3
MGA_DQS_L7
MGB_CA5
MGB_CHECK5
MGB_DATA14
MGB_DATA25
MGB_DQS_L1
MGA_CA5
MGA_DATA9
MGA_DATA19
MGA_DQS_H2
MGA_DQS_L6
MGB_CA4
MGB_CHECK4
MGB_DATA9
MGB_DATA13
MGB_DATA24
MGB_DQS_L0
MGA_CA4
MGA_DATA8
MGA_DATA18
MGA_DATA29
MGA_DQS_H1
MGA_DQS_L5
MGB_CA3
MGB_CHECK3
MGB_DATA8
MGB_DATA12
MGB_DATA23
MGA_CA3
MGA_DATA7
MGA_DATA17
MGA_DATA28
MGA_DQS_H0
MGA_DQS_L4
MGB_CA2
MGB_CHECK2
MGB_DATA7
MGB_DATA11
MGB_DATA22
MGA0_RSP_L
MGA1_RSP_L
MGA_CA2
MGA_CHECK7
MGA_DATA6
MGA_DATA16
MGA_DATA27
MGA_DQS_L3
MGB_CA1
MGB_CHECK1
MGB_DATA6
MGB_DATA10
MGB_DATA21
MGA_CA1
MGA_CHECK6
MGA_DATA5
MGA_DATA15
MGA_DATA26
MGA_DQS_L2
MGB_CA0
MGB_CHECK0
MGB_DATA5
MGB_DATA20
MGB_DATA31
MGA_CA0
MGA_CHECK5
MGA_DATA4
MGA_DATA14
MGA_DATA25
MGA_DQS_L1
MGB0_CS_L1
MGB1_CS_L1
MGB_DATA4
MGB_DATA30
MGB_DQS_H8
MGA_CHECK4
MGA_DATA3
MGA_DATA13
MGA_DATA24
MGA_DQS_L0
MGB0_CS_L0
MGB1_CS_L0
MGB_DATA3
MGB_DQS_H7
MGA_CHECK3
MGA_DATA2
MGA_DATA12
MGA_DATA23
MGB_DATA2
MGB_DQS_H6
MGA_CHECK2
MGA_DATA1
MGA_DATA11
MGA_DATA22
MGB_DATA1
MGB_DQS_H5
MGB_DQS_L9
MG_RESET_L
MG_ALERT_L
CAD NOTE:
SHEETDATE
DEPARTMENT
SIZE
PROJECT DOCUMENT NUMBER REV
REVIEWER
DESIGNER
123
7 3 2 1 6 5 4
E
A
B
C
E
D
C
B
A
7 6 5 4
D
IN
OUT
OUT
IN
OUTOUT
IN
OUT
OUTOUT
OUTOUT
OUT
OUT
BIBI
BIBI
BI
BI
BI
BI
C



Thu Sep 14 16:11:57 2023<NAME_2><NAME_1>MB FABCGT AMDV0244 OF 365105105105105105105105105105105105105105105
105105105105
105105
10510515M_H_CPU1_ALERT_R_NM_H_CPU1_ALERT_N1%0402LF
SOCKET6096_13568-001IO
TP_M_H_CPU1_SA_TEST39HM_H_CPU1_SA_CA<6:0>M_H_CPU1_SB_CA<6:0>M_H_CPU1_CLK_DN<0>M_H_CPU1_CLK_DP<0>M_H_CPU1_SA_CS_N<0>M_H_CPU1_SA_CS_N<1>M_H_CPU1_SA_RSP<0>M_H_CPU1_SA_PARM_H_CPU1_SB_CS_N<1>M_H_CPU1_SB_CS_N<0>M_H_CPU1_SB_RSP<0>M_H_CPU1_SB_PARM_H_CPU1_RESET_N
M_H_CPU1_SA_DQS_DP<9:0>M_H_CPU1_SB_DQS_DP<9:0>M_H_CPU1_SB_DQS_DN<9:0>M_H_CPU1_SA_DQS_DN<9:0>
M_H_CPU1_SB_CB<7:0>M_H_CPU1_SA_CB<7:0>
M_H_CPU1_SA_DQ<31:0>M_H_CPU1_SB_DQ<31:0>
CPU1 DDR CHHR1985 PLACE CLOSE TO CPU < 25MM
SMLF
21R507
BF14
BL14
BW12
DC14
CU14
CL14
CE14
BW14
DC12
CU12
CL12
CE12
BV13
DD14
CV14
CM14
CF14
BY14
DB13
CT13
CK13
CD13
DF14
DE12
DE14
DD13
DB14
DA12
DA14
CY13
CY14
CW12
CW14
CV13
CT14
CR12
CR14
CP13
CP14
CN12
CN14
CM13
CK14
CJ12
CJ14
CH13
CH14
CG12
CG14
CF13
CD14
CC12
CC14
CB13
BV14
BU12
BU14
BT13
CB14
CA12
CA14
BY13
BK13
BK14
BJ14
BJ12
BH13
BH14
BG14
BR12
BM13
BL12
BP13
BN12
BM14
BC14
AM14
AF14
Y14
P14
H14
AM13
AF13
Y13
P13
H13
AN14
AG14
AA14
R14
J14
AL12
AE12
W12
N12
G12
AJ14
AH13
AH14
AG12
AE14
AD13
AD14
AC12
AC14
AB13
AB14
AA12
W14
V13
V14
U12
U14
T13
T14
R12
N14
M13
M14
L12
L14
K13
K14
J12
G14
F13
F14
E12
AR14
AP13
AP14
AN12
AL14
AK13
AK14
AJ12
BB14
BB13
BA12
BA14
AY14
AY13
AW12
BP14
AW14
AV13
BN14
AV14
AU12
AU14
AT14
BG12
BF13
BD13
BC12
U26
6
4
5
3
1
2
0
6
4
5
3
2
1
0
9
8
9
8
7
6
5
4
3
7
6
5
2
4
3
1
0
9
8
2
1
0
9
8
7
6
5
4
3
7
6
5
4
3
0
1
2
2
1
0
7
4
6
5
3
2
1
6
0
7
4
5
3
2
0
1
30
29
28
31
27
24
25
26
22
23
20
19
21
18
15
16
17
12
13
14
11
10
9
6
8
7
5
4
3
1
2
31
0
30
28
29
26
27
25
24
22
23
21
19
20
17
18
15
16
13
14
11
12
10
8
6
7
9
5
4
3
1
2
0
8/40
TEST39H
MH1_CLK_L
MH1_CLK_H
MH0_CLK_L
MH0_CLK_H
MHB_PAR
MHA_PAR
MHB_DQS_H9
MHA_CHECK5
MHA_DATA14
MHA_DATA25
MHA_DQS_L1
MHB0_CS_L1
MHB1_CS_L0
MHB_DATA30
MHB_DQS_H8
MHA_CHECK4
MHA_DATA13
MHA_DATA24
MHA_DQS_L0
MHB0_CS_L0
MHB_DQS_H7
MHA_CHECK3
MHA_DATA9
MHA_DATA12
MHA_DATA23
MHB_DATA9
MHB_DQS_H6
MHA_CHECK2
MHA_DATA8
MHA_DATA11
MHA_DATA22
MHB_DATA8
MHB_DQS_H5
MHB_DQS_L9
MHA_CHECK1
MHA_DATA7
MHA_DATA10
MHA_DATA21
MHB_DATA7
MHB_DQS_H4
MHB_DQS_L8
MHA1_CS_L1
MHA_CHECK0
MHA_DATA6
MHA_DATA20
MHA_DATA31
MHA_DQS_H9
MHB_DATA6
MHB_DQS_H3
MHB_DQS_L7
MHA0_CS_L1
MHA1_CS_L0
MHA_DATA5
MHA_DATA30
MHA_DQS_H8
MHB_DATA5
MHB_DATA19
MHB_DQS_H2
MHB_DQS_L6
MHA0_CS_L0
MHA_DATA4
MHA_DQS_H7
MHB_CA6
MHB_DATA4
MHB_DATA18
MHB_DATA29
MHB_DQS_H1
MHB_DQS_L5
MHA_CA6
MHA_DATA3
MHA_DQS_H6
MHB1_RSP_L
MHB_CA5
MHB_DATA3
MHB_DATA17
MHB_DATA28
MHB_DQS_H0
MHB_DQS_L4
MHA_CA5
MHA_DATA2
MHA_DQS_H5
MHA_DQS_L9
MHB0_RSP_L
MHB_CA4
MHB_CHECK7
MHB_DATA2
MHB_DATA16
MHB_DATA27
MHB_DQS_L3
MHA_CA4
MHA_DATA1
MHA_DQS_H4
MHA_DQS_L8
MHB_CA3
MHB_CHECK6
MHB_DATA1
MHB_DATA15
MHB_DATA26
MHB_DQS_L2
MHA_CA3
MHA_DATA0
MHA_DQS_H3
MHA_DQS_L7
MHB_CA2
MHB_CHECK5
MHB_DATA0
MHB_DATA14
MHB_DATA25
MHB_DQS_L1
MHA_CA2
MHA_DATA19
MHA_DQS_H2
MHA_DQS_L6
MHB_CA1
MHB_CHECK4
MHB_DATA13
MHB_DATA24
MHB_DQS_L0
MHA_CA1
MHA_DATA18
MHA_DATA29
MHA_DQS_H1
MHA_DQS_L5
MHB_CA0
MHB_CHECK3
MHB_DATA12
MHB_DATA23
MHA1_RSP_L
MHA_CA0
MHA_DATA17
MHA_DATA28
MHA_DQS_H0
MHA_DQS_L4
MHB_CHECK2
MHB_DATA11
MHB_DATA22
MHA0_RSP_L
MHA_CHECK7
MHA_DATA16
MHA_DATA27
MHA_DQS_L3
MHB_CHECK1
MHB_DATA10
MHB_DATA21
MHA_CHECK6
MHA_DATA15
MHA_DATA26
MHA_DQS_L2
MHB1_CS_L1
MHB_CHECK0
MHB_DATA20
MHB_DATA31
MH_RESET_L
MH_ALERT_L
CAD NOTE:
SHEETDATE
DEPARTMENT
SIZE
PROJECT DOCUMENT NUMBER REV
REVIEWER
DESIGNER
123
7 3 2 1 6 5 4
E
A
B
C
E
D
C
B
A
7 6 5 4
D
IN
OUT
OUT
IN
OUTOUT
OUT
IN
OUTOUT
OUTOUT
OUT
OUT
BIBI
BIBI
BI
BI
BI
BI
C



Thu Sep 14 16:11:57 2023<NAME_2><NAME_1>MB FABCGT AMDV0245 OF 365106106106106106106106106106106106106106106
106106106106
106106
10610615M_I_CPU1_ALERT_R_NM_I_CPU1_ALERT_N1%0402LF
SOCKET6096_13568-001IO
TP_M_I_CPU1_SA_TEST39IM_I_CPU1_SA_CA<6:0>M_I_CPU1_SB_CA<6:0>M_I_CPU1_CLK_DP<0>M_I_CPU1_CLK_DN<0>M_I_CPU1_SA_CS_N<1>M_I_CPU1_SA_RSP<0>M_I_CPU1_SA_CS_N<0>M_I_CPU1_SA_PARM_I_CPU1_SB_CS_N<0>M_I_CPU1_SB_CS_N<1>M_I_CPU1_SB_RSP<0>M_I_CPU1_SB_PARM_I_CPU1_RESET_N
M_I_CPU1_SA_DQS_DP<9:0>M_I_CPU1_SB_DQS_DP<9:0>M_I_CPU1_SB_DQS_DN<9:0>M_I_CPU1_SA_DQS_DN<9:0>
M_I_CPU1_SB_CB<7:0>M_I_CPU1_SA_CB<7:0>
M_I_CPU1_SA_DQ<31:0>M_I_CPU1_SB_DQ<31:0>
CPU1 DDR CHIR1984 PLACE CLOSE TO CPU < 25MM
SMLF
21R508
BF21
BL21
BW19
DC21
CU21
CL21
CE21
BW21
DC19
CU19
CL19
CE19
BV20
DD21
CV21
CM21
CF21
BY21
DB20
CT20
CK20
CD20
DF21
DE19
DE21
DD20
DB21
DA19
DA21
CY20
CY21
CW19
CW21
CV20
CT21
CR19
CR21
CP20
CP21
CN19
CN21
CM20
CK21
CJ19
CJ21
CH20
CH21
CG19
CG21
CF20
CD21
CC19
CC21
CB20
BV21
BU19
BU21
BT20
CB21
CA19
CA21
BY20
BK20
BK21
BJ21
BJ19
BH20
BH21
BG21
BR19
BM20
BL19
BP20
BN19
BM21
BC21
AM21
AF21
Y21
P21
H21
AM20
AF20
Y20
P20
H20
AN21
AG21
AA21
R21
J21
AL19
AE19
W19
N19
G19
AJ21
AH20
AH21
AG19
AE21
AD20
AD21
AC19
AC21
AB20
AB21
AA19
W21
V20
V21
U19
U21
T20
T21
R19
N21
M20
M21
L19
L21
K20
K21
J19
G21
F20
F21
E19
AR21
AP20
AP21
AN19
AL21
AK20
AK21
AJ19
BB21
BB20
BA19
BA21
AY21
AY20
AW19
BP21
AW21
AV20
BN21
AV21
AU19
AU21
AT21
BG19
BF20
BD20
BC19
U26
6
5
4
3
2
6
5
1
0
4
3
2
0
1
8
9
9
7
6
5
3
4
1
2
0
9
8
8
7
6
4
3
5
2
1
9
0
6
7
4
3
5
1
2
0
8
7
6
4
5
3
2
1
0
6
7
5
4
3
1
2
7
0
4
5
6
2
3
1
0
31
29
30
27
28
26
25
24
22
20
23
21
19
18
17
16
14
15
13
12
11
10
9
8
7
6
5
4
3
2
1
0
31
30
29
27
28
25
24
26
23
21
22
20
18
19
17
16
15
14
11
12
13
9
10
7
8
5
6
4
2
3
0
1
9/40
TEST39I
MIA_DATA5
MIA_DATA17
MIA_DATA28
MIA_DQS_H0
MIA_DQS_L4
MIB_CHECK2
MIB_DATA5
MIB_DATA11
MIB_DATA22
MI_ALERT_L
MIA0_RSP_L
MIA1_RSP_L
MIA_CHECK7
MIA_DATA4
MIA_DATA16
MIA_DATA27
MIA_DQS_L3
MIB_CHECK1
MIB_DATA4
MIB_DATA10
MIB_DATA21
MIB_PAR
MIA_CHECK6
MIA_DATA3
MIA_DATA15
MIA_DATA26
MIA_DQS_L2
MIA_PAR
MIB1_CS_L1
MIB_CHECK0
MIB_DATA3
MIB_DATA20
MIB_DATA31
MIB_DQS_H9
MIA_CHECK5
MIA_DATA2
MIA_DATA14
MIA_DATA25
MIA_DQS_L1
MIB0_CS_L1
MIB1_CS_L0
MIB_DATA2
MIB_DATA30
MIB_DQS_H8
MIA_CHECK4
MIA_DATA1
MIA_DATA13
MIA_DATA24
MIA_DQS_L0
MIB0_CS_L0
MIB_DATA1
MIB_DQS_H7
MIA_CHECK3
MIA_DATA0
MIA_DATA12
MIA_DATA23
MIB_DATA0
MIB_DQS_H6
MI_RESET_L
MI0_CLK_L
MI1_CLK_L
MIA_CHECK2
MIA_DATA11
MIA_DATA22
MIB_DQS_H5
MIB_DQS_L9
MIA_CHECK1
MIA_DATA10
MIA_DATA21
MIB_DQS_H4
MIB_DQS_L8
MIA_CHECK0
MIA_DATA20
MIA_DATA31
MIA_DQS_H9
MIB_CA6
MIB_DQS_H3
MIB_DQS_L7
MIA0_CS_L1
MIA1_CS_L1
MIA_CA6
MIA_DATA30
MIA_DQS_H8
MIB_CA5
MIB_DATA19
MIB_DQS_H2
MIB_DQS_L6
MI0_CLK_H
MI1_CLK_H
MIA0_CS_L0
MIA1_CS_L0
MIA_CA5
MIA_DQS_H7
MIB_CA4
MIB_DATA18
MIB_DATA29
MIB_DQS_H1
MIB_DQS_L5
MIA_CA4
MIA_DQS_H6
MIB1_RSP_L
MIB_CA3
MIB_DATA17
MIB_DATA28
MIB_DQS_H0
MIB_DQS_L4
MIA_CA3
MIA_DQS_H5
MIA_DQS_L9
MIB0_RSP_L
MIB_CA2
MIB_CHECK7
MIB_DATA16
MIB_DATA27
MIB_DQS_L3
MIA_CA2
MIA_DATA9
MIA_DQS_H4
MIA_DQS_L8
MIB_CA1
MIB_CHECK6
MIB_DATA9
MIB_DATA15
MIB_DATA26
MIB_DQS_L2
MIA_CA1
MIA_DATA8
MIA_DQS_H3
MIA_DQS_L7
MIB_CA0
MIB_CHECK5
MIB_DATA8
MIB_DATA14
MIB_DATA25
MIB_DQS_L1
MIA_CA0
MIA_DATA7
MIA_DATA19
MIA_DQS_H2
MIA_DQS_L6
MIB_CHECK4
MIB_DATA7
MIB_DATA13
MIB_DATA24
MIB_DQS_L0
MIA_DATA6
MIA_DATA18
MIA_DATA29
MIA_DQS_H1
MIA_DQS_L5
MIB_CHECK3
MIB_DATA6
MIB_DATA12
MIB_DATA23
CAD NOTE:
SHEETDATE
DEPARTMENT
SIZE
PROJECT DOCUMENT NUMBER REV
REVIEWER
DESIGNER
123
7 3 2 1 6 5 4
E
A
B
C
E
D
C
B
A
7 6 5 4
D
OUT
IN
OUT
IN
OUTOUT
OUT
OUT
IN
OUT
OUTOUT
OUT
OUT
BIBI
BIBI
BI
BI
BI
BI
C



Thu Sep 14 16:11:57 2023<NAME_2><NAME_1>MB FABCGT AMDV0246 OF 365107107107107107107107107107107107107107107
107107107107
107107
10710715M_J_CPU1_ALERT_R_NM_J_CPU1_ALERT_N1%0402LF
SOCKET6096_13568-001IO
TP_M_J_CPU1_SA_TEST39JM_J_CPU1_SA_CA<6:0>M_J_CPU1_SB_CA<6:0>M_J_CPU1_CLK_DP<0>M_J_CPU1_CLK_DN<0>M_J_CPU1_SA_CS_N<0>M_J_CPU1_SA_CS_N<1>M_J_CPU1_SA_RSP<0>M_J_CPU1_SB_CS_N<0>M_J_CPU1_SB_CS_N<1>M_J_CPU1_SA_PARM_J_CPU1_SB_PARM_J_CPU1_SB_RSP<0>M_J_CPU1_RESET_N
M_J_CPU1_SA_DQS_DP<9:0>M_J_CPU1_SB_DQS_DP<9:0>M_J_CPU1_SB_DQS_DN<9:0>M_J_CPU1_SA_DQS_DN<9:0>
M_J_CPU1_SB_CB<7:0>M_J_CPU1_SA_CB<7:0>
M_J_CPU1_SA_DQ<31:0>M_J_CPU1_SB_DQ<31:0>
CPU1 DDR CHJR1983 PLACE CLOSE TO CPU < 25MM
SMLF
21R509
BF18
BL17
BW16
DC17
CU17
CL17
CE17
BW17
DC16
CU16
CL16
CE16
BV16
DD18
CV18
CM18
CF18
BY18
DB16
CT16
CK16
CD16
DF16
DE16
DE17
DD16
DB18
DA16
DA17
CY16
CY18
CW16
CW17
CV16
CT18
CR16
CR17
CP16
CP18
CN16
CN17
CM16
CK18
CJ16
CJ17
CH16
CH18
CG16
CG17
CF16
CD18
CC16
CC17
CB16
BV18
BU16
BU17
BT16
CB18
CA16
CA17
BY16
BK16
BK18
BJ17
BJ16
BH16
BH18
BG17
BR16
BM16
BL16
BP16
BN16
BM18
BC17
AM18
AF18
Y18
P18
H18
AM16
AF16
Y16
P16
H16
AN17
AG17
AA17
R17
J17
AL16
AE16
W16
N16
G16
AJ17
AH16
AH18
AG16
AE17
AD16
AD18
AC16
AC17
AB16
AB18
AA16
W17
V16
V18
U16
U17
T16
T18
R16
N17
M16
M18
L16
L17
K16
K18
J16
G17
F16
F18
E16
AR17
AP16
AP18
AN16
AL17
AK16
AK18
AJ16
BB18
BB16
BA16
BA17
AY18
AY16
AW16
BP18
AW17
AV16
BN17
AV18
AU16
AU17
AT18
BG16
BF16
BD16
BC16
U26
6
5
4
3
1
2
0
6
5
4
2
3
1
0
9
8
9
8
6
7
5
4
2
3
1
0
8
9
7
6
5
4
3
2
1
0
8
9
7
5
6
4
3
1
2
0
7
6
5
4
3
2
1
0
7
6
5
4
2
3
0
1
6
7
5
4
3
2
1
0
31
29
28
30
27
26
24
25
23
22
19
20
21
18
17
16
15
14
13
12
10
11
9
8
6
7
5
3
4
1
2
31
0
30
29
28
27
26
24
25
22
23
21
20
19
18
17
16
15
14
13
12
11
10
8
9
7
6
5
3
4
2
1
0
10/40
TEST39J
MJB_DATA7
MJB_DATA6
MJB_DATA5
MJB_DQS_H5
MJB_DQS_L4
MJB_DQS_L0
MJA_DATA31
MJB_DATA0
MJB_DATA3
MJB_DATA4
MJA_DQS_H4
MJA_DQS_H8
MJA_DQS_L4
MJA_DQS_L5
MJA_DQS_L7
MJA_DATA22
MJA_CA5
MJA_CA6
MJ0_CLK_H
MJ0_CLK_L
MJ1_CLK_H
MJ1_CLK_L
MJA0_CS_L0
MJA0_CS_L1
MJA0_RSP_L
MJA1_CS_L0
MJA1_CS_L1
MJA1_RSP_L
MJA_CA0
MJA_CA1
MJA_CA2
MJA_CA3
MJA_CA4
MJA_CHECK0
MJA_CHECK1
MJA_CHECK2
MJA_CHECK3
MJA_CHECK4
MJA_CHECK5
MJA_CHECK6
MJA_CHECK7
MJA_DATA0
MJA_DATA1
MJA_DATA2
MJA_DATA3
MJA_DATA4
MJA_DATA5
MJA_DATA6
MJA_DATA7
MJA_DATA8
MJA_DATA9
MJA_DATA10
MJA_DATA11
MJA_DATA12
MJA_DATA13
MJA_DATA14
MJA_DATA15
MJA_DATA16
MJA_DATA17
MJA_DATA18
MJA_DATA19
MJA_DATA20
MJA_DATA21
MJA_DATA23
MJA_DATA24
MJA_DATA25
MJA_DATA26
MJA_DATA27
MJA_DATA28
MJA_DATA29
MJA_DATA30
MJA_DQS_H0
MJA_DQS_H1
MJA_DQS_H2
MJA_DQS_H3
MJA_DQS_H5
MJA_DQS_H6
MJA_DQS_H7
MJA_DQS_H9
MJA_DQS_L0
MJA_DQS_L1
MJA_DQS_L2
MJA_DQS_L3
MJA_DQS_L6
MJA_DQS_L8
MJA_DQS_L9
MJA_PAR
MJB0_CS_L0
MJB0_CS_L1
MJB0_RSP_L
MJB1_CS_L0
MJB1_CS_L1
MJB1_RSP_L
MJB_CA0
MJB_CA1
MJB_CA2
MJB_CA3
MJB_CA4
MJB_CA5
MJB_CA6
MJB_CHECK0
MJB_CHECK1
MJB_CHECK2
MJB_CHECK3
MJB_CHECK4
MJB_CHECK5
MJB_CHECK6
MJB_CHECK7
MJB_DATA1
MJB_DATA2
MJB_DATA8
MJB_DATA9
MJB_DATA10
MJB_DATA11
MJB_DATA12
MJB_DATA13
MJB_DATA14
MJB_DATA15
MJB_DATA16
MJB_DATA17
MJB_DATA18
MJB_DATA19
MJB_DATA20
MJB_DATA21
MJB_DATA22
MJB_DATA23
MJB_DATA24
MJB_DATA25
MJB_DATA26
MJB_DATA27
MJB_DATA28
MJB_DATA29
MJB_DATA30
MJB_DATA31
MJB_DQS_H0
MJB_DQS_H1
MJB_DQS_H2
MJB_DQS_H3
MJB_DQS_H4
MJB_DQS_H6
MJB_DQS_H7
MJB_DQS_H8
MJB_DQS_H9
MJB_DQS_L1
MJB_DQS_L2
MJB_DQS_L3
MJB_DQS_L5
MJB_DQS_L6
MJB_DQS_L7
MJB_DQS_L8
MJB_DQS_L9
MJB_PAR
MJ_ALERT_L
MJ_RESET_L
CAD NOTE:
SHEETDATE
DEPARTMENT
SIZE
PROJECT DOCUMENT NUMBER REV
REVIEWER
DESIGNER
123
7 3 2 1 6 5 4
E
A
B
C
E
D
C
B
A
7 6 5 4
D
IN
OUT
IN
OUT
OUT
OUTOUT
IN
OUTOUT
OUTOUT
OUT
OUT
BIBI
BIBI
BI
BI
BI
BI
C



Thu Sep 14 16:11:58 2023<NAME_2><NAME_1>MB FABCGT AMDV0247 OF 365108108108108108108108108108108108108108108
108108108108
108108
10810815M_K_CPU1_ALERT_R_NM_K_CPU1_ALERT_N1%0402LF
SOCKET6096_13568-001IO
TP_M_K_CPU1_SA_TEST39KM_K_CPU1_SA_CA<6:0>M_K_CPU1_SB_CA<6:0>M_K_CPU1_CLK_DN<0>M_K_CPU1_CLK_DP<0>M_K_CPU1_SA_CS_N<0>M_K_CPU1_SA_CS_N<1>M_K_CPU1_SA_RSP<0>M_K_CPU1_SA_PARM_K_CPU1_SB_CS_N<0>M_K_CPU1_SB_CS_N<1>M_K_CPU1_SB_RSP<0>M_K_CPU1_SB_PARM_K_CPU1_RESET_N
M_K_CPU1_SA_DQS_DP<9:0>M_K_CPU1_SB_DQS_DP<9:0>M_K_CPU1_SB_DQS_DN<9:0>M_K_CPU1_SA_DQS_DN<9:0>
M_K_CPU1_SB_CB<7:0>M_K_CPU1_SA_CB<7:0>
M_K_CPU1_SA_DQ<31:0>M_K_CPU1_SB_DQ<31:0>
CPU1 DDR CHKR1956 PLACE CLOSE TO CPU < 25MM
SMLF
21R510
BF7
BL7
BW5
DC7
CU7
CL7
CE7
BW7
DC5
CU5
CL5
CE5
BV6
DD7
CV7
CM7
CF7
BY7
DB6
CT6
CK6
CD6
DF7
DE5
DE7
DD6
DB7
DA5
DA7
CY6
CY7
CW5
CW7
CV6
CT7
CR5
CR7
CP6
CP7
CN5
CN7
CM6
CK7
CJ5
CJ7
CH6
CH7
CG5
CG7
CF6
CD7
CC5
CC7
CB6
BV7
BU5
BU7
BT6
CB7
CA5
CA7
BY6
BK6
BK7
BJ7
BJ5
BH6
BH7
BG7
BR5
BM6
BL5
BP6
BN5
BM7
BC7
AM7
AF7
Y7
P7
H7
AM6
AF6
Y6
P6
H6
AN7
AG7
AA7
R7
J7
AL5
AE5
W5
N5
G5
AJ7
AH6
AH7
AG5
AE7
AD6
AD7
AC5
AC7
AB6
AB7
AA5
W7
V6
V7
U5
U7
T6
T7
R5
N7
M6
M7
L5
L7
K6
K7
J5
G7
F6
F7
E5
AR7
AP6
AP7
AN5
AL7
AK6
AK7
AJ5
BB7
BB6
BA5
BA7
AY7
AY6
AW5
BP7
AW7
AV6
BN7
AV7
AU5
AU7
AT7
BG5
BF6
BD6
BC5
U26
6
5
4
3
1
2
5
6
4
0
2
1
0
3
9
8
8
9
7
5
6
4
3
2
1
0
8
9
7
5
6
4
3
2
1
0
9
8
7
6
5
4
3
2
0
1
7
6
4
5
3
2
1
0
7
6
4
5
3
2
0
1
7
6
5
4
3
2
1
0
31
30
28
29
27
26
25
24
23
22
20
21
19
18
17
16
15
13
14
12
11
10
8
9
7
6
4
5
3
2
1
0
31
30
29
28
27
26
25
24
23
22
21
20
19
18
16
15
17
14
13
12
11
10
8
9
7
6
4
5
3
2
1
0
36/40
TEST39K
MKA0_CS_L0
MKA_CA0
MKA_DQS_H7
MKB_DATA9
MKB_DATA18
MKB_DATA29
MKB_DQS_H1
MKB_DQS_L5
MKA_DATA9
MKA_DQS_H6
MKB1_RSP_L
MKB_DATA8
MKB_DATA17
MKB_DATA28
MKB_DQS_H0
MKB_DQS_L4
MKA_DATA8
MKA_DQS_H5
MKA_DQS_L9
MKB0_RSP_L
MKB_CHECK7
MKB_DATA7
MKB_DATA16
MKB_DATA27
MKB_DQS_L3
MKA_DATA7
MKA_DQS_H4
MKA_DQS_L8
MKB_CHECK6
MKB_DATA6
MKB_DATA15
MKB_DATA26
MKB_DQS_L2
MKB_PAR
MKA_DATA6MKA_DQS_H3
MKA_DQS_L7
MKA_PAR
MKB_CHECK5
MKB_DATA5
MKB_DATA14
MKB_DATA25
MKB_DQS_L1
MKA_DATA5
MKA_DATA19
MKA_DQS_H2
MKA_DQS_L6
MKB_CHECK4
MKB_DATA4
MKB_DATA13
MKB_DATA24
MKB_DQS_L0
MKA_DATA4
MKA_DATA18
MKA_DATA29
MKA_DQS_H1
MKA_DQS_L5
MKB_CHECK3
MKB_DATA3
MKB_DATA12
MKB_DATA23
MKA1_RSP_L
MKA_DATA3
MKA_DATA17
MKA_DATA28
MKA_DQS_H0
MKA_DQS_L4
MKB_CHECK2
MKB_DATA2
MKB_DATA11
MKB_DATA22
MK_ALERT_L
MKA0_RSP_L
MKA_CHECK7
MKA_DATA2
MKA_DATA16
MKA_DATA27
MKA_DQS_L3
MKB_CHECK1
MKB_DATA1
MKB_DATA10
MKB_DATA21
MKA_CHECK6
MKA_DATA1
MKA_DATA15
MKA_DATA26
MKA_DQS_L2
MKB1_CS_L1
MKB_CHECK0
MKB_DATA0
MKB_DATA20
MKB_DATA31
MKB_DQS_H9
MK1_CLK_L
MKA_CHECK5
MKA_DATA0
MKA_DATA14
MKA_DATA25
MKA_DQS_L1
MKB0_CS_L1
MKB1_CS_L0
MKB_CA6
MKB_DATA30
MKB_DQS_H8
MK0_CLK_L
MKA_CA6
MKA_CHECK4
MKA_DATA13
MKA_DATA24
MKA_DQS_L0
MKB0_CS_L0
MKB_CA5
MKB_DQS_H7
MKA_CA5
MKA_CHECK3
MKA_DATA12
MKA_DATA23
MKB_CA4
MKB_DQS_H6
MK_RESET_L
MKA_CA4
MKA_CHECK2
MKA_DATA11
MKA_DATA22
MKB_CA3
MKB_DQS_H5
MKB_DQS_L9
MK1_CLK_H
MKA_CA3
MKA_CHECK1
MKA_DATA10
MKA_DATA21
MKB_CA2
MKB_DQS_H4
MKB_DQS_L8
MK0_CLK_H
MKA1_CS_L1
MKA_CA2
MKA_CHECK0
MKA_DATA20
MKA_DATA31
MKA_DQS_H9
MKB_CA1
MKB_DQS_H3
MKB_DQS_L7
MKA0_CS_L1
MKA1_CS_L0
MKA_CA1
MKA_DATA30
MKA_DQS_H8
MKB_CA0
MKB_DATA19
MKB_DQS_H2
MKB_DQS_L6
CAD NOTE:
SHEETDATE
DEPARTMENT
SIZE
PROJECT DOCUMENT NUMBER REV
REVIEWER
DESIGNER
123
7 3 2 1 6 5 4
E
A
B
C
E
D
C
B
A
7 6 5 4
D
IN
OUT
OUT
IN
OUTOUT
OUT
IN
OUTOUT
OUTOUT
OUT
OUT
BIBI
BIBI
BI
BI
BI
BI
C



Thu Sep 14 16:11:58 2023<NAME_2><NAME_1>MB FABCGT AMDV0248 OF 365109109109109109109109109109109109109109109
109109109109
109109
10910915M_L_CPU1_ALERT_R_NM_L_CPU1_ALERT_N1%0402LF
SOCKET6096_13568-001IO
TP_M_L_CPU1_SA_TEST39LM_L_CPU1_SA_CA<6:0>M_L_CPU1_SB_CA<6:0>M_L_CPU1_CLK_DP<0>M_L_CPU1_CLK_DN<0>M_L_CPU1_SA_CS_N<0>M_L_CPU1_SA_CS_N<1>M_L_CPU1_SA_RSP<0>M_L_CPU1_SA_PARM_L_CPU1_SB_CS_N<1>M_L_CPU1_SB_CS_N<0>M_L_CPU1_SB_PARM_L_CPU1_SB_RSP<0>M_L_CPU1_RESET_N
M_L_CPU1_SA_DQS_DP<9:0>M_L_CPU1_SB_DQS_DP<9:0>M_L_CPU1_SB_DQS_DN<9:0>M_L_CPU1_SA_DQS_DN<9:0>
M_L_CPU1_SB_CB<7:0>M_L_CPU1_SA_CB<7:0>
M_L_CPU1_SA_DQ<31:0>M_L_CPU1_SB_DQ<31:0>
CPU1 DDR CHLR1957 PLACE CLOSE TO CPU < 25MM
SMLF
21R511
BF11
BL10
BW9
DC10
CU10
CL10
CE10
BW10
DC9
CU9
CL9
CE9
BV9
DD11
CV11
CM11
CF11
BY11
DB9
CT9
CK9
CD9
DF9
DE9
DE10
DD9
DB11
DA9
DA10
CY9
CY11
CW9
CW10
CV9
CT11
CR9
CR10
CP9
CP11
CN9
CN10
CM9
CK11
CJ9
CJ10
CH9
CH11
CG9
CG10
CF9
CD11
CC9
CC10
CB9
BV11
BU9
BU10
BT9
CB11
CA9
CA10
BY9
BK9
BK11
BJ10
BJ9
BH9
BH11
BG10
BR9
BM9
BL9
BP9
BN9
BM11
BC10
AM11
AF11
Y11
P11
H11
AM9
AF9
Y9
P9
H9
AN10
AG10
AA10
R10
J10
AL9
AE9
W9
N9
G9
AJ10
AH9
AH11
AG9
AE10
AD9
AD11
AC9
AC10
AB9
AB11
AA9
W10
V9
V11
U9
U10
T9
T11
R9
N10
M9
M11
L9
L10
K9
K11
J9
G10
F9
F11
E9
AR10
AP9
AP11
AN9
AL10
AK9
AK11
AJ9
BB11
BB9
BA9
BA10
AY11
AY9
AW9
BP11
AW10
AV9
BN10
AV11
AU9
AU10
AT11
BG9
BF9
BD9
BC9
U26
4
5
6
2
3
1
0
4
5
6
2
3
0
1
9
8
9
8
7
5
6
7
6
4
3
5
3
4
2
1
0
2
1
9
8
9
0
7
5
6
8
6
7
4
3
5
4
2
0
1
2
3
1
0
7
5
6
3
4
2
1
0
7
6
5
4
3
2
1
0
31
29
30
28
27
26
24
25
23
22
20
21
19
18
17
15
16
13
14
11
10
12
8
9
6
7
4
5
2
1
3
0
30
31
29
26
27
28
24
25
22
23
21
20
17
18
19
16
14
15
13
12
11
10
8
9
6
7
5
4
1
2
3
0
35/40
TEST39L
MLA_CA1
MLA_CHECK1
MLA_DATA4
MLA_DATA10
MLA_DATA21
MLB_CA0
MLB_DATA3
MLB_DQS_H4
MLB_DQS_L8
MLA_CA0
MLA_CHECK0
MLA_DATA3
MLA_DATA20
MLA_DATA31
MLA_DQS_H9
MLB_DATA2
MLB_DQS_H3
MLB_DQS_L7
MLA1_CS_L1
MLA_DATA2
MLA_DATA30
MLA_DQS_H8
MLB_DATA1
MLB_DATA19
MLB_DQS_H2
MLB_DQS_L6
MLA0_CS_L1
MLA1_CS_L0
MLA_DATA1
MLA_DQS_H7
MLB_DATA0
MLB_DATA18
MLB_DATA29
MLB_DQS_H1
MLB_DQS_L5
ML1_CLK_L
MLA0_CS_L0
MLA_DATA0
MLA_DQS_H6
MLB_DATA17
MLB_DATA28
MLB_DQS_H0
MLB_DQS_L4
MLB_PAR
ML0_CLK_L
MLA_DQS_H5
MLA_DQS_L9
MLA_PAR
MLB1_RSP_L
MLB_CHECK7
MLB_DATA16
MLB_DATA27
MLB_DQS_L3
MLA_DQS_H4
MLA_DQS_L8
MLB0_RSP_L
MLB_CHECK6
MLB_DATA15
MLB_DATA26
MLB_DQS_L2
MLA_DQS_H3
MLA_DQS_L7
MLB_CHECK5
MLB_DATA14
MLB_DATA25
MLB_DQS_L1
ML1_CLK_H
MLA_DATA19
MLA_DQS_H2
MLA_DQS_L6
MLB_CHECK4
MLB_DATA13
MLB_DATA24
MLB_DQS_L0
ML0_CLK_H
MLA_DATA18
MLA_DATA29
MLA_DQS_H1
MLA_DQS_L5
MLB_CHECK3
MLB_DATA12
MLB_DATA23
MLA_DATA17
MLA_DATA28
MLA_DQS_H0
MLA_DQS_L4
MLB_CHECK2
MLB_DATA11
MLB_DATA22
ML_ALERT_L
MLA1_RSP_L
MLA_CHECK7
MLA_DATA16
MLA_DATA27
MLA_DQS_L3
MLB_CA6
MLB_CHECK1
MLB_DATA9
MLB_DATA10
MLB_DATA21
MLA0_RSP_L
MLA_CA6
MLA_CHECK6
MLA_DATA9
MLA_DATA15
MLA_DATA26
MLA_DQS_L2
MLB_CA5
MLB_CHECK0
MLB_DATA8
MLB_DATA20
MLB_DATA31
MLB_DQS_H9
MLA_CA5
MLA_CHECK5
MLA_DATA8
MLA_DATA14
MLA_DATA25
MLA_DQS_L1
MLB1_CS_L1
MLB_CA4
MLB_DATA7
MLB_DATA30
MLB_DQS_H8
MLA_CA4
MLA_CHECK4
MLA_DATA7
MLA_DATA13
MLA_DATA24
MLA_DQS_L0
MLB0_CS_L1
MLB1_CS_L0
MLB_CA3
MLB_DATA6
MLB_DQS_H7
MLA_CA3
MLA_CHECK3
MLA_DATA6
MLA_DATA12
MLA_DATA23
MLB0_CS_L0
MLB_CA2
MLB_DATA5
MLB_DQS_H6
ML_RESET_L
MLA_CA2
MLA_CHECK2
MLA_DATA5
MLA_DATA11
MLA_DATA22
MLB_CA1
MLB_DATA4
MLB_DQS_H5
MLB_DQS_L9
CAD NOTE:
SHEETDATE
DEPARTMENT
SIZE
PROJECT DOCUMENT NUMBER REV
REVIEWER
DESIGNER
123
7 3 2 1 6 5 4
E
A
B
C
E
D
C
B
A
7 6 5 4
D
IN
OUT
IN
OUT
OUTOUT
OUT
IN
OUTOUT
OUTOUT
OUT
OUT
BIBI
BIBI
BI
BI
BI
BI
C



LANE REVERSALCPU1 G1[15:0] TO OCP SLOT#1Thu Sep 14 16:11:58 2023<NAME_2><NAME_1>MB FABCGT AMDV0249 OF 365
67672323 2323137137P5E_CPU1_G1_TX_DN<15:0>P5E_CPU1_G1_TX_DP<15:0>SMLF
CPU1 PCIE G0/G1
IOSOCKET6096_13568-001SMLFSOCKET6096_13568-001GMI_CPU0_G2_CPU1_G0_TX_DP<0:15>GMI_CPU0_G2_CPU1_G0_TX_DN<0:15> GMI_CPU1_G0_CPU0_G2_TX_DN<0:15>GMI_CPU1_G0_CPU0_G2_TX_DP<0:15>IOP5E_CPU1_G1_RX_DN<15:0>P5E_CPU1_G1_RX_DP<15:0>
AL52
AJ52
AN52
AL49
AJ49
AN49
AL46
AJ46
AN46
AL43
AJ43
AN43
AK40
AH40
AM40
AP40
AL53
AJ53
AN53
AL50
AJ50
AN50
AL47
AJ47
AN47
AL44
AJ44
AN44
AK41
AH41
AM41
AP41
U53
R53
W53
U50
R50
N50
W50
R47
N47
U47
R44
N44
U44
P41
T41
V41
U52
R52
W52
U49
R49
N49
W49
R46
N46
U46
R43
N43
U43
P40
T40
V40
U26
AE52
AC52
AG52
AE49
AC49
AG49
AE46
AC46
AG46
AE43
AC43
AA43
AG43
AB40
AD40
AF40
AE53
AC53
AG53
AE50
AC50
AG50
AE47
AC47
AG47
AE44
AC44
AA44
AG44
AB41
AD41
AF41
N53
J53
G53
L53
J50
G50
L50
J47
G47
L47
J44
G44
L44
H41
K41
M41
N52
J52
G52
L52
J49
G49
L49
J46
G46
L46
J43
G43
L43
H40
K40
M40
U26
1
8
2
5
4
1
2
0
15
14
13
12
11
10
9
7
6
5
4
3
2
1
0
15
14
13
12
11
10
8
7
6
5
4
3
2
1
0
14
13
12
11
10
9
8
7
6
5
4
3
2
1
0
13
12
10
11
9
8
7
6
5
4
3
2
0
1
15
13
10
9
8
7
5
6
4
3
1
2
0
15
14
13
12
10
11
9
8
7
6
5
4
3
2
0
1
15
14
14
15
12
11
9
0
15
14
13
11
12
10
9
8
7
6
3
3
4
5
6
7
8
9
10
11
12
13
14
15
12/40
G1_RXN7
G1_RXN6
G1_RXN5
G1_RXP7
G1_TXN7
G1_RXN4
G1_RXP6
G1_TXN6
G1_RXN3
G1_RXP5
G1_TXN5
G1_TXP7
G1_RXN2
G1_RXP4
G1_TXN4
G1_TXP6
G1_RXN1
G1_RXP3
G1_TXN3
G1_TXP5
G1_RXN0
G1_RXP2
G1_TXN2
G1_TXP4
G1_RXP1
G1_TXN1
G1_TXP3
G1_RXP0
G1_TXN0
G1_TXP2
G1_TXP1
G1_TXP0
G1_RXN8
G1_RXN9
G1_RXN10
G1_RXN11
G1_RXN12
G1_RXN13
G1_RXN14
G1_RXN15
G1_RXP8
G1_RXP9
G1_RXP10
G1_RXP11
G1_RXP12
G1_RXP13
G1_RXP14
G1_RXP15
G1_TXN8
G1_TXN9
G1_TXN10
G1_TXN11
G1_TXN12
G1_TXN13
G1_TXN14
G1_TXN15
G1_TXP8
G1_TXP9
G1_TXP10
G1_TXP11
G1_TXP12
G1_TXP13
G1_TXP14
G1_TXP15
11/40
G0_TXP15
G0_TXP14
G0_TXP13
G0_TXP12
G0_TXP11
G0_TXP10
G0_TXP9
G0_TXP8
G0_TXP7
G0_TXP6
G0_TXP5
G0_TXP4
G0_TXP3
G0_TXP2
G0_TXP1
G0_TXP0
G0_TXN15
G0_TXN14
G0_TXN13
G0_TXN12
G0_TXN11
G0_TXN10
G0_TXN9
G0_TXN8
G0_TXN7
G0_TXN6
G0_TXN5
G0_TXN4
G0_TXN3
G0_TXN2
G0_TXN1
G0_TXN0
G0_RXP15
G0_RXP14
G0_RXP13
G0_RXP12
G0_RXP11
G0_RXP10
G0_RXP9
G0_RXP8
G0_RXP7
G0_RXP6
G0_RXP5
G0_RXP4
G0_RXP3
G0_RXP2
G0_RXP1
G0_RXP0
G0_RXN15
G0_RXN14
G0_RXN13
G0_RXN12
G0_RXN11
G0_RXN10
G0_RXN9
G0_RXN8
G0_RXN7
G0_RXN6
G0_RXN5
G0_RXN4
G0_RXN3
G0_RXN2
G0_RXN1
G0_RXN0
SHEETDATE
DEPARTMENT
SIZE
PROJECT DOCUMENT NUMBER REV
REVIEWER
DESIGNER
123
7 3 2 1 6 5 4
E
A
B
C
E
D
C
B
A
7 6 5 4
D
OUTIN
IN OUT
IN
IN
OUT
OUT
C



LANE REVERSALLANE REVERSALThu Sep 14 16:11:59 2023<NAME_2><NAME_1>MB FABCGT AMDV0250 OF 365
2222 222222222222SOCKET6096_13568-001SOCKET6096_13568-001IOIOGMI_CPU0_G0_CPU1_G2_TX_DP<15:0>GMI_CPU0_G0_CPU1_G2_TX_DN<15:0>GMI_CPU1_G3_CPU0_G1_TX_DP<15:0>GMI_CPU1_G3_CPU0_G1_TX_DN<15:0>GMI_CPU1_G2_CPU0_G0_TX_DP<15:0>GMI_CPU1_G2_CPU0_G0_TX_DN<15:0>GMI_CPU0_G1_CPU1_G3_TX_DP<15:0>GMI_CPU0_G1_CPU1_G3_TX_DN<15:0>
CPU1 PCIE G2/G3
SMLFSMLF
V35
T35
P35
U32
N32
R32
U29
N29
R29
W26
N26
R26
U26
W23
R23
U23
V36
T36
P36
U33
N33
R33
U30
N30
R30
W27
N27
R27
U27
W24
R24
U24
AP36
AM36
AH36
AK36
AN33
AJ33
AL33
AN30
AJ30
AL30
AN27
AJ27
AL27
AN24
AJ24
AL24
AP35
AM35
AH35
AK35
AN32
AJ32
AL32
AN29
AJ29
AL29
AN26
AJ26
AL26
AN23
AJ23
AL23
U26
M35
K35
H35
L32
G32
J32
L29
G29
J29
L26
G26
J26
L23
G23
J23
N23
M36
K36
H36
L33
G33
J33
L30
G30
J30
L27
G27
J27
L24
G24
J24
N24
AF36
AD36
AB36
AG33
AA33
AC33
AE33
AG30
AC30
AE30
AG27
AC27
AE27
AG24
AC24
AE24
AF35
AD35
AB35
AG32
AA32
AC32
AE32
AG29
AC29
AE29
AG26
AC26
AE26
AG23
AC23
AE23
U26
1
0
2
3
5
4
6
7
8
10
9
11
12
13
14
15
0
2
1
3
4
5
6
7
8
9
10
11
12
13
14
15
1
2
3
0
7
8
5
4
6
13
12
11
9
10
14
15
0
1
3
2
5
4
6
8
7
10
11
9
13
12
14
15
0
1
2
3
4
5
6
7
9
8
10
11
12
14
13
15
0
2
1
3
4
5
7
6
8
9
10
11
12
13
14
15
0
1
3
4
2
5
6
7
9
8
10
11
14
12
13
15
0
1
2
3
5
4
6
7
8
10
9
12
13
11
14
15
14/40
G3_RXN2||SATA22_RXN
G3_TXN9||SATA31_TXN
G3_RXN12||SATA34_RXN
G3_RXN15||SATA37_RXN
G3_TXP5||SATA25_TXP
G3_RXN9||SATA31_RXN
G3_TXP2||SATA22_TXPG3_RXP2||SATA22_RXP
G3_RXP5||SATA25_RXP
G3_RXP14||SATA36_RXP
G3_TXN4||SATA24_TXN
G3_TXN7||SATA27_TXN
G3_TXN10||SATA32_TXN
G3_TXN13||SATA35_TXN
G3_RXP11||SATA33_RXP
G3_TXN1||SATA21_TXN
G3_TXP9||SATA31_TXP
G3_TXP15||SATA37_TXP
G3_RXN1||SATA21_RXN
G3_RXN4||SATA24_RXN
G3_RXN7||SATA27_RXN
G3_TXP12||SATA34_TXP
G3_RXP9||SATA31_RXP
G3_TXP7||SATA27_TXP
G3_TXN8||SATA30_TXN
G3_RXN11||SATA33_RXN
G3_RXN14||SATA36_RXN
G3_TXP1||SATA21_TXP
G3_TXP4||SATA24_TXP
G3_RXP7||SATA27_RXP
G3_RXN8||SATA30_RXN
G3_TXN12||SATA34_TXN
G3_TXN15||SATA37_TXN
G3_RXP1||SATA21_RXP
G3_RXP4||SATA24_RXP
G3_RXP10||SATA32_RXP
G3_RXP13||SATA35_RXP
G3_TXN3||SATA23_TXN
G3_TXN6||SATA26_TXNG3_RXN6||SATA26_RXN
G3_TXN0||SATA20_TXN
G3_TXP8||SATA30_TXP
G3_TXP14||SATA36_TXP
G3_RXN0||SATA20_RXN
G3_RXN3||SATA23_RXN
G3_RXP8||SATA30_RXP
G3_TXP11||SATA33_TXP
G3_RXN13||SATA35_RXN
G3_TXP6||SATA26_TXP
G3_RXN10||SATA32_RXN
G3_TXP0||SATA20_TXP
G3_TXP3||SATA23_TXPG3_RXP3||SATA23_RXP
G3_RXP6||SATA26_RXP
G3_RXP15||SATA37_RXP
G3_TXN5||SATA25_TXN
G3_TXN11||SATA33_TXN
G3_TXN14||SATA36_TXN
G3_RXP0||SATA20_RXP
G3_RXP12||SATA34_RXP
G3_TXN2||SATA22_TXN
G3_RXN5||SATA25_RXN
G3_TXP10||SATA32_TXP
G3_TXP13||SATA35_TXP
13/40
G2_TXP0
G2_RXN7
G2_RXN6
G2_RXN5
G2_RXP7
G2_TXN7
G2_RXN4
G2_RXP6
G2_TXN6
G2_RXN3
G2_RXP5
G2_TXN5
G2_TXP7
G2_RXN2
G2_RXP4
G2_TXN4
G2_TXP6
G2_RXN1
G2_RXP3
G2_TXN3
G2_TXP5
G2_RXN0
G2_RXP2
G2_TXN2
G2_TXP4
G2_RXP1
G2_TXN1
G2_TXP3
G2_RXP0
G2_TXN0
G2_TXP2
G2_TXP1
G2_RXN15
G2_RXP15
G2_RXN13
G2_RXP13
G2_RXN11
G2_RXP11
G2_RXN9
G2_RXP9
G2_RXN14
G2_RXP14
G2_RXN12
G2_RXP12
G2_RXN10
G2_RXP10
G2_RXN8
G2_RXP8
G2_TXN15
G2_TXP15
G2_TXN13
G2_TXP13
G2_TXN11
G2_TXP11
G2_TXN9
G2_TXP9
G2_TXN14
G2_TXP14
G2_TXN12
G2_TXP12
G2_TXN10
G2_TXP10
G2_TXN8
G2_TXP8
SHEETDATE
DEPARTMENT
SIZE
PROJECT DOCUMENT NUMBER REV
REVIEWER
DESIGNER
123
7 3 2 1 6 5 4
E
A
B
C
E
D
C
B
A
7 6 5 4
D
IN OUT
OUTIN
IN
IN
OUT
OUT
C



CPU1 P0[15:0] TO EXAMAXCPU1 P1[15:0] TO EXAMAXThu Sep 14 16:11:59 2023<NAME_2><NAME_1>MB FABCGT AMDV0251 OF 365
32932966663183186565P5E_CPU1_P1_RX_DP<15:0>P5E_CPU1_P1_RX_DN<15:0> P5E_CPU1_P1_TX_DN<15:0>P5E_CPU1_P1_TX_DP<15:0>SOCKET6096_13568-001IOP5E_CPU1_P0_RX_DP<15:0>SMLFSOCKET6096_13568-001
CPU1 PCIE P0/P1
SMLFP5E_CPU1_P0_RX_DN<15:0>P5E_CPU1_P0_TX_DP<15:0>P5E_CPU1_P0_TX_DN<15:0>IO
CV41
CY41
DB41
CW44
DC44
DA44
CW47
DC47
DA47
CW50
DC50
DA50
CW53
DC53
DA53
CU53
CV40
CY40
DB40
CW43
DC43
DA43
CW46
DC46
DA46
CW49
DC49
DA49
CW52
DC52
DA52
CU52
CD40
CF40
CH40
CC43
CJ43
CG43
CE43
CC46
CG46
CE46
CC49
CG49
CE49
CC52
CG52
CE52
CD41
CF41
CH41
CC44
CJ44
CG44
CE44
CC47
CG47
CE47
CC50
CG50
CE50
CC53
CG53
CE53
U26
CM41
CP41
CT41
CN44
CU44
CR44
CN47
CU47
CR47
CL50
CU50
CR50
CN50
CL53
CR53
CN53
CM40
CP40
CT40
CN43
CU43
CR43
CN46
CU46
CR46
CL49
CU49
CR49
CN49
CL52
CR52
CN52
BT40
BV40
CB40
BY40
BU43
CA43
BW43
BU46
CA46
BW46
BU49
CA49
BW49
BU52
CA52
BW52
BT41
BV41
CB41
BY41
BU44
CA44
BW44
BU47
CA47
BW47
BU50
CA50
BW50
BU53
CA53
BW53
U26
14
13
12
11
10
9
8
7
6
5
4
3
2
1
15
14
13
12
11
9
8
7
6
5
4
3
1
0
10
2
9
9
1
15
4
0
1
2
4
3
5
6
8
7
0
2
1
3
4
5
6
7
8
9
10
11
13
12
14
15
9
10
11
12
13
14
15
2
0
10
15
14
15
11
12
13
10
7
8
6
1
2
3
4
5
3
4
5
6
7
8
10
11
12
14
15
2
3
4
6
7
8
9
11
13
0
0
1
2
3
5
6
7
8
9
10
11
12
13
14
12
5
13
0
0
1
14
15
16/40
P1_RXN6
P1_RXN5
P1_RXP7
P1_TXN7
P1_RXN4
P1_RXP6
P1_TXN6
P1_RXN3
P1_RXP5
P1_TXN5
P1_TXP7
P1_RXN2
P1_RXP4
P1_TXN4
P1_TXP6
P1_RXN1
P1_RXP3
P1_TXN3
P1_TXP5
P1_RXN0
P1_RXP2
P1_TXN2
P1_TXP4
P1_RXP1
P1_TXN1
P1_TXP3
P1_RXP0
P1_TXN0
P1_TXP2
P1_TXP1
P1_TXP0
P1_RXN7
P1_TXN15
P1_TXP15
P1_TXN14
P1_TXP14
P1_TXN13
P1_TXP13
P1_TXN12
P1_TXP12
P1_TXN11
P1_TXP11
P1_TXN10
P1_TXP10
P1_TXN9
P1_TXP9
P1_TXN8
P1_TXP8
P1_RXN15
P1_RXP15
P1_RXN14
P1_RXP14
P1_RXN13
P1_RXP13
P1_RXN12
P1_RXP12
P1_RXN11
P1_RXP11
P1_RXN10
P1_RXP10
P1_RXN9
P1_RXP9
P1_RXN8
P1_RXP8
15/40
P0_RXP11||SATA13_RXP
P0_TXP12||SATA14_TXP
P0_TXP15||SATA17_TXP
P0_RXN11||SATA13_RXN
P0_RXN14||SATA16_RXN
P0_TXN15||SATA17_TXN
P0_RXP13||SATA15_RXP
P0_TXN9||SATA11_TXN
P0_TXN12||SATA14_TXN
P0_RXP10||SATA12_RXP
P0_RXN9||SATA11_RXN
P0_TXP11||SATA13_TXP
P0_TXP14||SATA16_TXP
P0_RXN10||SATA12_RXN
P0_RXN13||SATA15_RXN
P0_TXP9||SATA11_TXPP0_RXP9||SATA11_RXP
P0_TXN14||SATA16_TXN
P0_RXP12||SATA14_RXP
P0_RXP15||SATA17_RXP
P0_TXN8||SATA10_TXN
P0_TXN11||SATA13_TXN
P0_RXN8||SATA10_RXN
P0_TXP13||SATA15_TXP
P0_TXP10||SATA12_TXP
P0_RXN15||SATA17_RXN
P0_TXP8||SATA10_TXP
P0_RXN12||SATA14_RXN
P0_RXP8||SATA10_RXP
P0_RXP14||SATA16_RXP
P0_TXN10||SATA12_TXN
P0_TXN13||SATA15_TXN
P0_TXP3||SATA03_TXP
P0_TXP6||SATA06_TXP
P0_TXP0||SATA00_TXP
P0_RXP3||SATA03_RXP
P0_RXP6||SATA06_RXP
P0_TXN5||SATA05_TXN
P0_RXP0||SATA00_RXP
P0_TXN2||SATA02_TXNP0_RXN2||SATA02_RXN
P0_RXN5||SATA05_RXN
P0_TXP2||SATA02_TXP
P0_TXP5||SATA05_TXPP0_RXP5||SATA05_RXP
P0_RXP2||SATA02_RXP
P0_TXN1||SATA01_TXN
P0_TXN7||SATA07_TXN
P0_TXN4||SATA04_TXN
P0_RXN7||SATA07_RXN
P0_RXN1||SATA01_RXN
P0_RXN4||SATA04_RXN
P0_TXP7||SATA07_TXP
P0_TXP1||SATA01_TXP
P0_TXP4||SATA04_TXPP0_RXP4||SATA04_RXP
P0_RXP7||SATA07_RXP
P0_TXN6||SATA06_TXN
P0_RXP1||SATA01_RXP
P0_TXN0||SATA00_TXN
P0_TXN3||SATA03_TXNP0_RXN3||SATA03_RXN
P0_RXN6||SATA06_RXN
P0_RXN0||SATA00_RXN
SHEETDATE
DEPARTMENT
SIZE
PROJECT DOCUMENT NUMBER REV
REVIEWER
DESIGNER
123
7 3 2 1 6 5 4
E
A
B
C
E
D
C
B
A
7 6 5 4
D
OUTIN OUT
ININ
IN
OUTOUT
C



CPU1 P2[15:0] TO EXAMAXCPU1 P3[15:0] TO EXAMAXThu Sep 14 16:11:59 2023<NAME_2><NAME_1>MB FABCGT AMDV0252 OF 365
67673513516634034066P5E_CPU1_P3_TX_DN<15:0>P5E_CPU1_P3_TX_DP<15:0>P5E_CPU1_P3_RX_DN<15:0>P5E_CPU1_P3_RX_DP<15:0>P5E_CPU1_P2_TX_DP<15:0>P5E_CPU1_P2_RX_DN<15:0>P5E_CPU1_P2_RX_DP<15:0>
CPU1 PCIE P2/P3
SMLFSOCKET6096_13568-001SMLFSOCKET6096_13568-001IOIOP5E_CPU1_P2_TX_DN<15:0>
BW24
CA24
BU24
BW27
CA27
BU27
BW30
CA30
BU30
BW33
CA33
BU33
BY36
CB36
BV36
BT36
BW23
CA23
BU23
BW26
CA26
BU26
BW29
CA29
BU29
BW32
CA32
BU32
BY35
CB35
BV35
BT35
CN23
CR23
CL23
CN26
CR26
CU26
CL26
CR29
CU29
CN29
CR32
CU32
CN32
CT35
CP35
CM35
CN24
CR24
CL24
CN27
CR27
CU27
CL27
CR30
CU30
CN30
CR33
CU33
CN33
CT36
CP36
CM36
U26
CE24
CG24
CC24
CE27
CG27
CC27
CE30
CG30
CC30
CE33
CG33
CJ33
CC33
CH36
CF36
CD36
CE23
CG23
CC23
CE26
CG26
CC26
CE29
CG29
CC29
CE32
CG32
CJ32
CC32
CH35
CF35
CD35
CU23
DA23
DC23
CW23
DA26
DC26
CW26
DA29
DC29
CW29
DA32
DC32
CW32
DB35
CY35
CV35
CU24
DA24
DC24
CW24
DA27
DC27
CW27
DA30
DC30
CW30
DA33
DC33
CW33
DB36
CY36
CV36
U26
4
0
1
1
0
0
14
13
12
11
10
9
8
7
6
5
4
3
2
1
0
15
14
13
12
11
10
9
8
7
6
5
4
3
2
1
3
15
15
14
13
12
11
10
8
9
7
6
5
4
3
2
15
14
10
9
8
13
12
11
7
6
5
4
3
2
15
14
14
15
13
12
11
12
13
11
10
9
10
9
8
8
7
6
6
5
5
3
1
1
0
0
14
13
13
12
11
12
11
10
10
9
8
8
9
6
7
7
5
6
5
3
4
4
2
0
2
1
0
1
15
15
14
3
4
7
2
2
17/40
P2_RXN7
P2_RXN6
P2_RXN5
P2_RXP7
P2_TXN7
P2_RXN4
P2_RXP6
P2_TXN6
P2_RXN3
P2_RXP5
P2_TXN5
P2_TXP7
P2_RXN2
P2_RXP4
P2_TXN4
P2_TXP6
P2_RXN1
P2_RXP3
P2_TXN3
P2_TXP5
P2_RXN0
P2_RXP2
P2_TXN2
P2_TXP4
P2_RXP1
P2_TXN1
P2_TXP3
P2_RXP0
P2_TXN0
P2_TXP2
P2_TXP1
P2_TXP0
P2_TXN15
P2_TXP15
P2_TXN14
P2_TXP14
P2_TXN13
P2_TXP13
P2_TXN12
P2_TXP12
P2_TXN11
P2_TXP11
P2_TXN10
P2_TXP10
P2_TXN9
P2_TXP9
P2_TXN8
P2_TXP8
P2_RXN15
P2_RXP15
P2_RXN14
P2_RXP14
P2_RXN13
P2_RXP13
P2_RXN12
P2_RXP12
P2_RXN11
P2_RXP11
P2_RXN10
P2_RXP10
P2_RXN9
P2_RXP9
P2_RXN8
P2_RXP8
18/40
P3_TXN15
P3_TXP15
P3_TXN14
P3_TXP14
P3_TXN13
P3_TXP13
P3_TXN12
P3_TXP12
P3_TXN11
P3_TXP11
P3_TXN10
P3_TXP10
P3_TXN9
P3_TXP9
P3_TXN8
P3_TXP8
P3_TXN7
P3_TXP7
P3_TXN6
P3_TXP6
P3_TXN5
P3_TXP5
P3_TXN4
P3_TXP4
P3_TXN3
P3_TXP3
P3_TXN2
P3_TXP2
P3_TXN1
P3_TXP1
P3_TXN0
P3_TXP0
P3_RXN15
P3_RXP15
P3_RXN14
P3_RXP14
P3_RXN13
P3_RXP13
P3_RXN12
P3_RXP12
P3_RXN11
P3_RXP11
P3_RXN10
P3_RXP10
P3_RXN9
P3_RXP9
P3_RXN8
P3_RXP8
P3_RXN7
P3_RXP7
P3_RXN6
P3_RXP6
P3_RXN5
P3_RXP5
P3_RXN4
P3_RXP4
P3_RXN3
P3_RXP3
P3_RXN2
P3_RXP2
P3_RXN1
P3_RXP1
P3_RXN0
P3_RXP0
SHEETDATE
DEPARTMENT
SIZE
PROJECT DOCUMENT NUMBER REV
REVIEWER
DESIGNER
123
7 3 2 1 6 5 4
E
A
B
C
E
D
C
B
A
7 6 5 4
D
ININ
ININ OUTOUT
OUTOUT
C



CPU1 P5[3:2] TO EXAMAXP3E_CPU1_P5_RX_DP/N<1> PN SWAPP3E_CPU1_P5_RX_DP/N<0> PN SWAPCPU1 P4[3:0] TO M.2
Thu Sep 14 16:12:37 2023<NAME_2><NAME_1>MB FABCGT AMDV0253 OF 365
1221221221222626 12212212212267672626144144P3E_CPU1_P5_TX_DP<0>P3E_CPU1_P5_TX_DN<0>P3E_CPU1_P5_TX_DN<1>P3E_CPU1_P5_TX_DP<1>P3E_CPU1_P5_RX_DP<1>P3E_CPU1_P5_RX_DN<1>P3E_CPU1_P5_RX_DP<0>P3E_CPU1_P5_RX_DN<0>WAFL_CPU0_TX0_CPU1_RX1_DNWAFL_CPU0_TX0_CPU1_RX1_DPP3E_CPU1_P5_TX_C_DP<0>P3E_CPU1_P5_TX_C_DN<0>P3E_CPU1_P5_TX_C_DP<1>P3E_CPU1_P5_TX_C_DN<1>DIFF BUS_0.22UFDIFF BUS_0.22UFP3E_CPU1_P4_TX_DP<3:0>P3E_CPU1_P4_TX_DN<3:0>WAFL_CPU1_TX1_CPU0_RX0_DPWAFL_CPU1_TX1_CPU0_RX0_DNP3E_CPU1_P4_RX_DN<3:0>P3E_CPU1_P4_RX_DP<3:0>C0201X6SDIFF BUS_0.22UF20%6.3VDIFF BUS_0.22UFSMLFSOCKET6096_13568-001IO
CPU1 PCIE P4/P5/WAFL
C47
C50
C48
C51
E46
E49
E47
E50
C41
C44
C42
C45
E40
E43
E41
E44
DE44
DE47
DE50
DE53
DE43
DE46
DE49
DE52
DG45
DG48
DG51
DG54
DG44
DG47
DG50
DG53
U26
2 1
2 1
2 1
2 1
2 1
2 1
2 1
2 1
0
1
0
1
2
3
2
3
0
2
1
0
1
3
2
3
C2075
C2076
C2074
C2073
19/40
WAFL_TXP1||P5_TXP1
WAFL_TXN1||P5_TXN1
WAFL_TXP0||P5_TXP0
WAFL_TXN0||P5_TXN0
WAFL_RXP1||P5_RXP1
WAFL_RXN1||P5_RXN1
WAFL_RXP0||P5_RXP0
WAFL_RXN0||P5_RXN0
P4_RXN1
P4_RXN0
P4_RXP1
P4_TXN1
P4_RXP0
P4_TXN0
P4_TXP1
P4_TXP0
P5_TXP3
P5_TXP2
P5_TXN3
P5_TXN2
P5_RXP3
P5_RXP2
P5_RXN3
P5_RXN2
P4_TXP3
P4_TXP2
P4_TXN3
P4_TXN2
P4_RXP3
P4_RXP2
P4_RXN3
P4_RXN2
SHEETDATE
DEPARTMENT
SIZE
PROJECT DOCUMENT NUMBER REV
REVIEWER
DESIGNER
123
7 3 2 1 6 5 4
E
A
B
C
E
D
C
B
A
7 6 5 4
D
OUTOUT
OUTOUT
OUTOUT
OUTOUTININ
ININININ
ININ
C



Thu Sep 14 16:11:59 2023<NAME_2><NAME_1>MB FABCGT AMDV0254 OF 365
PVDD18_S5_P1
PVDD18_S5_P1P3V3_AUXPVDD18_S5_P15454545454 8254825482548227548227548281825427548227548254 82545454541611615417354173541735417421781838183
54825482548254825482548216721021722622421722621722421721054 8254 8254 8254 8254 8254 821735417354173541745417354
82 5482 54
54174
541732105417421021021721727 548227 548227 548227 548227 8227548227548254545454210
275482275482545433332.2K2.2K2.2K2.2KEMPTYAPML_CPU1_ALERT_NCPU1_BP3CPU1_BP2CPU1_BP0CPU1_CORETYPE0CPU1_SP5R3CPU1_SP5R4CPU1_CORETYPE0CPU1_XTRIG_L6CPU1_XTRIG_L4TP_CPU1_TEST6_CCD3TP_CPU1_TEST6_CCD2TP_CPU1_TEST6_CCD0APML_CPU1_ALERT_R_NCPU1_PROCHOT_NCPU1_XTRIG_L7CPU1_XTRIG_L62.2K
CPU1 MISC 1/2
CPU1_PROCHOT_NNC_CPU1_AZ_SYNCNC_CPU1_AZ_SDIN0NC_CPU1_AZ_RST_NNC_CPU1_AZ_SDIN1NC_CPU1_AZ_SDOUTNC_CPU1_AZ_SDIN2NC_CPU1_AZ_BITCLKCPU1_BP3CPU1_BP2CPU1_BP0CPU1_BP1TP_CPU1_TEST6_X3D3TP_CPU1_TEST6_X3D2TP_CPU1_TEST6_X3D1TP_CPU1_TEST6_X3D0TP_CPU1_TEST4_CCD6TP_CPU1_TEST4_CCD5TP_CPU1_TEST4_CCD4TP_CPU1_TEST6_IODTP_CPU1_TEST4_CCD3TP_CPU1_TEST4_CCD2TP_CPU1_TEST4_CCD1TP_CPU1_TEST4_CCD0TP_CPU1_TEST6_X3D5TP_CPU1_TEST6_CCD1TP_CPU1_TEST6_X3D4TP_CPU1_TEST5_CCD11TP_CPU1_TEST4_CCD11TP_CPU1_TEST5_CCD10TP_CPU1_TEST4_CCD9TP_CPU1_TEST4_CCD10TP_CPU1_TEST4_CCD8TP_CPU1_TEST5_CCD9TP_CPU1_TEST4_CCD7TP_CPU1_TEST5_CCD8TP_CPU1_TEST5_CCD7TP_CPU1_TEST5_CCD6TP_CPU1_TEST5_CCD5TP_CPU1_TEST5_CCD4TP_CPU1_TEST4_IODTP_CPU1_TEST5_CCD3TP_CPU1_TEST5_CCD1TP_CPU1_TEST5_CCD0TP_CPU1_UART1_RXTP_CPU1_UART0_CTS_NTP_CPU1_UART0_TXTP_CPU1_UART0_RTS_NTP_CPU1_UART0_RXTP_CPU1_TEST41_IODTP_CPU1_TEST5_IODTP_CPU1_UART0_INTR
SMB_APML_CPU1_SCLSMB_APML_CPU1_SDAJTAG_CPU1_DBREQ_NJTAG_CPU1_TMSJTAG_CPU1_TCKJTAG_CPU1_TDISVID_PVDDCR_CPU1_P1_SVTOFM_P1_PCC1_NFM_P1_PCC0_N
CPU1_CORETYPE2CPU1_CORETYPE1CPU1_SP5R2CPU1_SP5R1CPU1_SA1CPU1_SA0PRSNT_CPU1_NTP_CPU1_TEST47_CCD3TP_CPU1_TEST47_IOD1TP_CPU1_TEST47_IOD0TP_CPU1_TEST47_CCD2TP_CPU1_TEST47_CCD1TP_CPU1_TEST47_CCD0VSENSE_PVDDCR_CPU0_P1_DPVSENSE_PVDDCR_CPU1_P1_DPTP_VSENSE_PVDD33_S5_P1VSENSE_PVDD18_S5_P1_DPVSENSE_PVDD11_S3_P1_DPVSENSE_PVDDIO_P1_DPVSENSE_PVDD18_S5_P1_DNVSENSE_VSS_SENSE_C_P1VSENSE_VSS_SENSE_B_P1VSENSE_VSS_SENSE_A_P1TP_CPU1_TEST50_IODCPU1_CORETYPE2CPU1_CORETYPE1CPU1_SP5R4CPU1_SP5R3CPU1_SP5R2CPU1_SP5R1JTAG_CPU1_DBREQ_NJTAG_CPU1_TMSJTAG_CPU1_TCKJTAG_CPU1_TDIJTAG_CPU1_TRST_N
CPU1_SA1CPU1_SA0
JTAG_CPU1_TDO
IO
NANANANANANANANANANACHIPCHIP
EMPTYEMPTYEMPTYEMPTYEMPTYEMPTY
EMPTY
10%10%10%10%10%10%0.001UF0.001UF0.001UF0.001UF0.001UF0.001UF2.2K2.2K2.2K2.2K2.2K2.2K2.2K2.2K2.2K 2.2K
50V50V50V50V50V50VC0402C0402C0402C0402C0402C0402
0402LF0402LF 0402LF2.2KJTAG_CPU1_TRST_NSVID_PVDDCR_CPU0_P1_SVTOSOCKET6096_13568-001SMLF0JTAG_CPU1_R_TDOJTAG_CPU1_TDO0SVID_PVDDCR_CPU0_P1_SVD_R SVID_PVDDCR_CPU0_P1_SVD0SVID_PVDDCR_CPU0_P1_SVC_R SVID_PVDDCR_CPU0_P1_SVC0SVID_PVDDCR_CPU1_P1_SVD_R SVID_PVDDCR_CPU1_P1_SVD0SVID_PVDDCR_CPU1_P1_SVC_R SVID_PVDDCR_CPU1_P1_SVC0CPU1_XTRIG_R2_L5 CPU1_XTRIG_L50CPU1_XTRIG_R2_L4 CPU1_XTRIG_L40CPU1_XTRIG_R2_L7 CPU1_XTRIG_L70CPU1_XTRIG_R2_L6 CPU1_XTRIG_L600000402LF1KCHIP1/16W1%0402LF1KCHIP1/16W1%0402LF1KCHIP1/16W1%0402LF1KCHIP1/16W1%0402LF1KCHIP1/16W1%0402LF1KCHIP1/16W1%
APML_CPU1_ALERT_NCPU1_THERMTRIP_N CPU1_THERMTRIP_R_NCPU1_XTRIG_L7CPU1_XTRIG_L5CPU1_XTRIG_R1_L7CPU1_XTRIG_R1_L6CPU1_XTRIG_R1_L5CPU1_XTRIG_R1_L4SMLFIOCPU1_BP3CPU1_BP2CPU1_BP1CPU1_BP0SCONN8_G802M0083150RD3HRSMLFIOSCONN8_G802M0083150RD3HRTP_CPU1_TEST5_CCD2VSENSE_PVDDCR_SOC_P1_DP
2.2KCPU1_XTRIG_L5CPU1_XTRIG_L42.2K2.2K2.2K2.2KCPU1_THERMTRIP_NCPU1_BP15454
21 R497
21 R488
21R540
21R539
21R538
21R537
21R534
21R533
21R532
21R531
2
1 R521
2
1R519
2
1R518
21R516
21R514
21R512
21R535
21R520
21R515
21R513
21R522
21R517
21 R931
21 R932
21 R930
21 R929
21 R862
21 R928
21 R486
21 R618
21PR236
21PR237
21PR169
21PR170
2
1 C230
2
1
R523
2
1 C231
2
1 C232
2
1
R524
2
1
R525
2
1 C233
2
1
R526
2
1 C234
2
1 C235
2
1
R527
2
1
R528
TP11 TP12 TP13 TP14 TP15 TP16 TP17 TP18 TP19 TP20
2 1R529
A65
A66
C65
C66
B73
DJ3
BR54
C3
BR53
B3
DG3
C2
BP53
C74
DH3
DJ32
DH33
DJ34
DG35
DF34
DG34
DJ33
A17
A16
DJ9
B61
D7
B58
E32
CK46
CJ24
B60
W31
CJ53
AA23
CJ52
AA29
CJ29
AA47
AA49
Y46
CJ46
CJ30
AA46
AA24
Y29
CK47
CK29
Y47
AA26
CJ51
CJ25
AA53
Y30
CJ49
CJ27
AA51
AA25
AA28
CJ47
CK30
AA48
AA27
CJ50
CJ26
AA52
AA30
CJ48
CJ28
AA50
C18
C17
B17
DG73
B21
DH72
A22
DJ72
A23
DH10
DH73
C68
C19
DH71
DJ71
DJ56
DJ55
DH8
A69
DG72
C22
C16
B66
D68
B69
C70
A62
A63
C62
C63
D32
A32
A33
D33
C33
A34
C32
A68
U26
1111111111
R536
87
65
43
21
87
65
43
21
J49
J7
87
65
43
21
87
65
43
21
20/40
CORETYPE2
BP3
BP2
BP1
BP0
TEST41_IOD
TEST47_CCD3
TEST6_CCD0
TEST6_X3D3
TEST6_X3D2
TEST47_IOD1 TEST6_X3D1
TEST47_IOD0 TEST6_X3D0
TEST5_CCD11
TEST4_CCD11
TEST5_CCD10
TEST4_CCD9
TEST4_CCD10
TEST47_CCD2
TEST4_CCD8
TEST5_CCD9
TEST47_CCD1
TEST4_CCD7
TEST50_IOD
TEST5_CCD8
TEST47_CCD0
TEST4_CCD6
TEST5_CCD7
TEST4_CCD5
TEST5_CCD6
TEST4_CCD4
TEST5_CCD5
TEST6_IOD
TEST4_CCD3
TEST5_CCD4
TEST5_IOD
TEST4_CCD2
TEST4_IOD
TEST5_CCD3
TEST4_CCD1
TEST5_CCD2
TEST6_CCD3
TEST4_CCD0
TEST5_CCD1
TEST6_CCD2
TEST6_X3D5
TEST5_CCD0
TEST6_CCD1
TEST6_X3D4
VDDCR_CPU0_SENSE
VDDCR_CPU1_SENSE
VDDCR_SOC_SENSE
VDD_33_S5_SENSE
VDD_18_S5_SENSE
VDD_11_S3_SENSE
VDDIO_SENSE
VSS_SENSE_D
VSS_SENSE_C
VSS_SENSE_B
VSS_SENSE_A
UART1_TXD||AGPIO142
UART1_RXD||AGPIO141
RTC_LDO_SELECT
TCK
SP5R1
AZ_SDIN1||SW_MCLK
AZ_SDIN0||SW_MDATA3
AZ_RST_L||SW_MDATA1
AZ_SDOUT||SW_MDATA2
AZ_SDIN2||SW_MDATA0
UART0_CTS_L||UART2_TXD||AGPIO135
UART0_TXD||AGPIO138
UART0_INTR||AGPIO139
UART0_RTS_L||UART2_RXD||AGPIO137
UART0_RXD||AGPIO136
SVC1
SVT1
SVC0
SVD1
SVT0
SVD0 AZ_SYNC
AZ_BITCLK
PCC1_L
PCC0_L
SP5R4
SP5R3
SP5R2
CORETYPE1
CORETYPE0
SA1
XTRIG_L7
XTRIG_L6
XTRIG_L5
XTRIG_L4
TRST_L
TMS
THERMTRIP_L
TDO
TDI
SID
SIC
SA0
PROCHOT_L
DBREQ_L
CPU_PRESENT_L
ALERT_L
21
SHEETDATE
DEPARTMENT
SIZE
PROJECT DOCUMENT NUMBER REV
REVIEWER
DESIGNER
123
7 3 2 1 6 5 4
E
A
B
C
E
D
C
B
A
7 6 5 4
D
OUT
OUT
OUT
OUTOUTOUTOUTOUTOUTOUT
OUTOUTOUTOUT
OUTOUT
OUTOUT
BI
BI
BIBI
OUTOUT
OUTOUT
OUTOUTOUT
OUTOUT
OUT
OUTOUT
OUT
OUTOUT
OUT
OUTOUTOUTOUT
OUTOUTOUT
OUTOUT
OUTOUT
ININ
OUT
OUTOUT
IN
INININ
OUTIN
ININ
IN
IN
ININ
BIBI
BIBI
IN
OUTOUTOUTOUTOUTOUTOUTOUTOUTOUT
C



Thu Sep 14 16:12:00 2023<NAME_2><NAME_1>MB FABCGT AMDV0255 OF 365CPU1_PWRGD_OUTPVDD18_S5_P1
PVDD18_S5_P1PVDD11_S3_P1PVDD18_S5_P12.7PFC0402NPO50V0.1PF2.7PFNPO50V0.1PFC04021/16W CHIP55 825581857855 15955825582558255555581 183183144144
82 55558182 5581558155558155818555815581
55811552855 1595582 1618181
552876
55812881558155555581 122122137137137137137137137137122122818381835581558155555515955159551595515916155
2828558185 78558185558176
55 15955 15982 5581555581555555810EMPTY0EMPTY
FM_CPU1_BMC_RST_NPWRGD_CPU1_PWROKI3C_1_SPD_DDRGL_CPU1_R_SCLTP_SLOT2_BUF_SKU_ID1TP_SLOT2_BUF_SKU_ID0FM_CPU1_BMC_RST_NFM_BMC_TPM_PRES_NFM_BMC_READY_NCPU1_SLP_S3_NCPU1_SLP_S5_N1KCPU1_SMERR_N2.2K0402LF5%CLK_100M_CPU1_CLK13_DNCLK_100M_CPU1_CLK13_DPCLK_100M_CPU1_CLK12_DNCLK_100M_CPU1_CLK13_R_DNCLK_100M_CPU1_CLK13_R_DP1/16WCLK_100M_CPU1_CLK12_DP5%0402LFCLK_100M_CPU1_CLK12_R_DNCLK_100M_CPU1_CLK12_R_DPCLK_100M_CPU1_CLK11_R_DNCLK_100M_CPU1_CLK11_R_DP0402LFEMPTYFM_BMC_TPM_PRES_NFM_BMC_READY_N4.7K4.7KCPU1_NMI_SYNC_FLOOD_NRST_CPU1_SYS_NCPU1_FORCE_SELFREFRESHCHIPCHIPEMPTYRST_CPU1_RESETL_NEMPTYEMPTY4.7KCPU1_NV_SAVE_N4.7KEMPTYEMPTYCPU1_SPD_HOST_CTRL_N
CPU1_FORCE_SELFREFRESHIRQ_WAKE_NCLK_100M_CPU1_CLK05_R_DP1%20M0402LF1/16W CHIP50VI3C_1_SPD_DDRGL_CPU1_R_SDAIRQ_CPU_BMC_NMI_NSMB_CPU1_SEC_SCL1%1KEMPTY1%EMPTY1K1%1KEMPTY1%EMPTY1KCPU1_SLP_S3_NFM_CPU1_SLP_S3_NCPU1_SLP_S5_NFM_CPU1_SLP_S5_N
XTAL_CPU1_X32K_X2XTAL_CPU1_R_X32K_X2EMPTY0XTAL_CPU1_R_X32K_X1EMPTY0CPU1_SPD_HOST_CTRL_R_N0 CLK_CPU0_RTCCLKCHIP04.7K4.7K4.7KCHIP4.7K4.7KEMPTY4.7KEMPTY4.7KEMPTY4.7KEMPTY4.7K4.7KEMPTYEMPTY4.7K1%10M0402LF
RST_CPU1_RSMRST_N1000PFCPU1_PWR_GD_IN50V5%X7R0402CPU1_NMI_SYNC_FLOOD_NINT_CPU1_HP_UBM_NXTAL_CPU1_X32K_X2XTAL_CPU1_X32K_X1CPU1_SMERR_NCLK_100M_CPU1_CLK11_DNCLK_100M_CPU1_CLK11_DPCLK_100M_CPU1_CLK05_DNCLK_100M_CPU1_CLK05_DPCLK_100M_CPU1_CLK04_DNCLK_100M_CPU1_CLK04_DPCLK_100M_CPU1_CLK03_DNCLK_100M_CPU1_CLK03_DPCLK_100M_CPU1_CLK02_DNCLK_100M_CPU1_CLK02_DPCLK_100M_CPU1_CLK01_DNCLK_100M_CPU1_CLK01_DP1/16W5%5%1/16W1/16W1/16W00402LF1/16W1/16W1/16W5%0402LF5%5%CHIPCLK_100M_CPU1_CLK01_R_DPCLK_100M_CPU1_CLK01_R_DNCHIP1/16W0402LFCLK_100M_CPU1_CLK04_R_DN0402LF5%00402LF0402LF000402LF000CHIP0402LFCHIP05%CHIPRST_CPU1_PERST0_NRST_CPU1_PERST1_N1/16W5%1/16W5%00CPU1_NV_SAVE_N1/16W5%5%05%SMLF32.768KHZ2.2KSOCKET6096_13568-001IONC_CPU1_PWR_BTN_NRST_CPU1_SYS_NXTAL_CPU1_X48M_X2XTAL_CPU1_X48M_X1I3C_0_SPD_DDRAF_CPU1_R_SCLI3C_0_SPD_DDRAF_CPU1_R_SDAI3C_1_SPD_DDRGL_CPU1_R_SCLI3C_1_SPD_DDRGL_CPU1_R_SDASMB_CPU1_SEC_SDAXTAL_CPU1_X32K_X1
CLK_100M_REF_IN_DPCLK_100M_REF_IN_DNPWRGD_CPU1_PWROKRST_CPU1_RESETL_NCPU1_PWRGD_OUTCLK_CPU1_RTCCLKSMLF
10PF50V0402NPO1%10PF0402NPO1%
1/16W0I3C_0_SPD_DDRAF_CPU1_R_SDAI3C_0_SPD_DDRAF_CPU1_R_SCLMISCSMLF48MHZEMPTY2.2K1K4.7KIRQ_CPU_BMC_NMI_N4.7KRST_CPU1_RSMRST_NCPU1 MISC 2/20402LFCHIP2.2KCPU1_FORCE_SELFREFRESHXTAL_CPU1_X48M_X1XTAL_CPU1_X48M_X249.9CPU1_SPD_HOST_CTRL_NXTAL_CPU1_X48M_X2_R0402LFCLK_100M_CPU1_CLK03_R_DNCLK_100M_CPU1_CLK03_R_DPCLK_100M_CPU1_CLK02_R_DNCLK_100M_CPU1_CLK02_R_DP0402LF0402LFCHIP1/16WCHIP01/16W05%00402LF05%1/16W0402LFCLK_100M_CPU1_CLK05_R_DNCLK_100M_CPU1_CLK04_R_DPCHIP5555
2
1 C5024
2
1 R563
2
1 R543
2
1 R542
2
1 R541
21 R557
2 1 R550
2 1 R547
2 1 R551
2 1 R553
21 R556
21 R559
21 R562
2 1 R549
2 1 R548
R583
R584
R456R546R545R544
R491R5030R5031R5032
21 R192
21 R191
21R575
21 R1424
21R570
DJ16
DJ17
DJ13
DJ14
DJ10
DH6
DJ11
DG4
DJ5
B15
D15
D14
B14
DH9
DG10
B67
A19
A20
D69
DH36
DJ8
DH7
DG36
D18
B64
DJ31
B4
A4
B72
C72
A5
C7
B71
A71
DJ20
DJ21
DH12
DG12
DJ51
DJ50
DJ48
DJ47
DJ53
DJ54
DJ45
DJ44
DJ41
DJ42
B9
C9
B12
C12
A10
A11
B6
C6
A8
A7DJ35
B63
B16
A13
C14
A14
DH15
DH16
DG32
DG31
DF31
DE30
DH30
DJ29
DG11
DE32
DF33
DH4
DE40
DF40
DF36
DE36
U26
21R573
21R574
2
1 C237
31
42
Y4
21
R571
2
1 C239
21
Y5
2
1 C238
2
1 C236
21212121212121212121
R8350
R8351
R6503
2 1 R558
R4305
R4306
R3201
R3200
R3199
R3198
R3197
R3196
R3195
R3194
R3354
R3355
R3353
R3352
R572
R5103
21
21/40
AGPIO7
NMI_SYNC_FLOOD_L
SEC_SCL||AGPIO262
SEC_SDA||AGPIO263
AGPIO257||SGPIO1_CLK||CLK_REQ01_L
PWROK||SVI_RST_L
AGPIO6||DEVSLP1||SATA_ZP1_L
AGPIO5||DEVSLP0||SATA_ZP0_L
GENINT_L||PM_INTR_L||UBM_CPRSNT_CHANGE_DET_L||AGPIO89
AGPIO22
AGPIO88
AGPIO21
AGPIO87
AGPIO109
AGPIO107
AGPIO106
AGPIO105
AGPIO104
RESET_L
REFCLK100SSC_N||GPP_CLK10N
REFCLK100SSC_P||GPP_CLK10P
SMERR_L||AGPIO24
I2C5_SDA||BMC_SDA||SMBUS1_SDA||AGPIO20
I2C5_SCL||BMC_SCL||SMBUS1_SCL||AGPIO19
I2C4_SDA||HP_SDA||UBM_SDA||AGPIO14
I2C4_SCL||HP_SCL||UBM_SCL||AGPIO13
I3C3_SCL||I2C3_SCL||SPD3_SCL||AGPIO151
I3C1_SDA||I2C1_SDA||SPD1_SDA||AGPIO148
AGPIO116||CLK_REQ12_L
PWRGD_OUT||AGPIO12
AGPIO259||SGPIO3_CLK
I3C0_SCL||I2C0_SCL||SPD0_SCL||SMBUS0_SCL||AGPIO145
I3C2_SCL||I2C2_SCL||SPD2_SCL||AGPIO149
I3C1_SCL||I2C1_SCL||SPD1_SCL||AGPIO147
I3C0_SDA||I2C0_SDA||SPD0_SDA||SMBUS0_SDA||AGPIO146
AGPIO115||CLK_REQ11_L
PCIE_RST0_L||AGPIO266
AGPIO256||SGPIO0_CLK
AGPIO258||SGPIO2_CLK||CLK_REQ02_L
I3C3_SDA||I2C3_SDA||SPD3_SDA||AGPIO152
SGPIO_DATAOUT||AGPIO260
I3C2_SDA||I2C2_SDA||SPD2_SDA||AGPIO150
SGPIO_LOAD||AGPIO261
PCIE_RST1_L||AGPIO26
AGPIO3||SPD_HOST_CTRL_L
AGPIO4||SATA_ACT_L
GPP_CLK11P
GPP_CLK01P
GPP_CLK12P
GPP_CLK02P
GPP_CLK11N
GPP_CLK13P
GPP_CLK01N
GPP_CLK03P
GPP_CLK12N
GPP_CLK14P
GPP_CLK02N
GPP_CLK04P
GPP_CLK13N
GPP_CLK15P
GPP_CLK03N
GPP_CLK05P
GPP_CLK14N
GPP_CLK04N
GPP_CLK15N
GPP_CLK05N
RTCCLK
FORCE_SELFREFRESH
NV_SAVE_L
PWR_BTN_L||AGPIO0
X48M_X2
X48M_X1
X32K_X2
X32K_X1
WAKE_L||AGPIO2
SYS_RESET_L||AGPIO1
SLP_S5_L
SLP_S3_L
RSMRST_L
PWR_GOOD
X2
G2G1
X1
21 21
2
1
21
2
1
21 21
21 21
21 21
21 21
21 21
21 21
21 21
SHEETDATE
DEPARTMENT
SIZE
PROJECT DOCUMENT NUMBER REV
REVIEWER
DESIGNER
123
7 3 2 1 6 5 4
E
A
B
C
E
D
C
B
A
7 6 5 4
D
OUT
OUTOUT
OUT
OUTOUT
OUTOUTOUTOUT
OUTOUTOUTOUT
OUTOUTOUT
OUTOUT
INININ
OUT
OUT
OUTOUT
OUT
OUTOUT
OUTOUT
OUTOUT
OUTOUT
OUTOUT
OUTOUT
OUT
OUTOUT
OUTOUT
IN
INBI
BIOUTBIOUT
OUT
OUT
ININ
IN
ININ
IN
IN
IN
OUTOUT
OUT
OUT
OUT
IN
BI
BI
ININ
IN
OUT
OUTOUT
C



Thu Sep 14 16:12:00 2023<NAME_2><NAME_1>MB FABCGT AMDV0256 OF 365
7676SPI_CPU1_R_CLKSPI_CPU1_CLK33SOCKET6096_13568-001IOPD_ESPI_CPU1_CLK2NC_CPU1_USB3_USB11_TXNNC_CPU1_USB3_USB11_TXPNC_CPU1_USB10_OC_NNC_CPU1_USB11_OC_NNC_CPU1_USB00_OC_NNC_CPU1_USB01_OC_NNC_CPU1_USB2_USB00_DNNC_CPU1_USB2_USB00_DPNC_CPU1_USB3_USB00_RXNNC_CPU1_USB3_USB00_RXPNC_CPU1_USB3_USB00_TXPNC_CPU1_USB3_USB00_TXNNC_CPU1_USB2_USB01_DNNC_CPU1_USB2_USB01_DPNC_CPU1_USB3_USB01_RXNNC_CPU1_USB3_USB01_RXPNC_CPU1_USB3_USB01_TXNNC_CPU1_USB3_USB01_TXPNC_CPU1_USB2_USB10_DNNC_CPU1_USB2_USB10_DPNC_CPU1_USB3_USB10_RXNNC_CPU1_USB3_USB10_RXPNC_CPU1_USB3_USB10_TXNNC_CPU1_USB3_USB10_TXPNC_CPU1_USB2_USB11_DNNC_CPU1_USB2_USB11_DPNC_CPU1_USB3_USB11_RXNNC_CPU1_USB3_USB11_RXP
CPU1 SPI/USB
SMLF
21 R738
DG58
DH58
DJ62
DH62
DH40
DH60
DJ60
DH69
DJ69
DJ65
DH65
DG40
DJ67
DH67
E30
E29
C29
C28
E24
A28
A29
C25
C26
E27
E26
E23
A26
A25
DH27
DG26
DF30
DE27
DJ26
DJ23
DG28
DF27
DG23
DJ27
DG25
DF25
DE24
DH24
DF24
DG29
DJ28
DG22
DF28
DJ22
DJ25
U26
22/40
ESPI_RSTOUT_L||AGPIO23
ESPI_CLK1||SPI_CLK1||AGPIO75
ESPI_CLK2||AGPIO74
ESPI0_ALERT_L||AGPIO108
AGPIO76||SPI_TPM_CS_L
ESPI_CLK0||SPI_CLK0||AGPIO117
ESPI1_ALERT_L||AGPIO110
ESPI_RSTIN_L||KBRST_L||AGPIO129
USB01_OC_L||AGPIO265
SPI_CS1_L||AGPIO119
SPI_CS2_L||AGPIO126
ESPI0_DAT0||SPI0_DAT0||AGPIO120
ESPI0_DAT1||SPI0_DAT1||AGPIO121
ESPI0_DAT2||SPI0_DAT2||AGPIO122
ESPI0_DAT3||SPI0_DAT3||AGPIO123
ESPI1_DAT2||SPI1_DAT2||AGPIO133
ESPI1_DAT3||SPI1_DAT3||AGPIO134
ESPI_CS1_L||AGPIO125
ESPI1_DAT0||SPI1_DAT0||AGPIO131
ESPI1_DAT1||SPI1_DAT1||AGPIO132
SPI_CS0_L||AGPIO118
USB00_OC_L||AGPIO264
ESPI_CS0_L||AGPIO124
USB11_OC_L||AGPIO17
USB10_OC_L||AGPIO16
USB11_TXP
USB11_TXN
USB11_RXP
USB11_RXN
USB11_DP
USB11_DN
USB10_TXP
USB10_TXN
USB10_RXP
USB10_RXN
USB10_DP
USB10_DN
USB01_TXP
USB01_TXN
USB01_RXP
USB01_RXN
USB01_DP
USB01_DN
USB00_TXP
USB00_TXN
USB00_RXP
USB00_RXN
USB00_DP
USB00_DN
SHEETDATE
DEPARTMENT
SIZE
PROJECT DOCUMENT NUMBER REV
REVIEWER
DESIGNER
123
7 3 2 1 6 5 4
E
A
B
C
E
D
C
B
A
7 6 5 4
D
OUT
IN
C



Thu Sep 14 16:12:01 2023<NAME_2><NAME_1>MB FABCGT AMDV0257 OF 365
PVDDCR_CPU0_P1PVDDCR_CPU1_P1
PVDD18_S5_P1
PVDD11_S3_P1
PVDD18_S5_P1PVDD_33_S5
PVDDCR_SOC_P1PVDDCR_SOC_P1PVDDCR_CPU0_P1PVDDIO_P1PVDDCR_CPU1_P1
P1V5_BAT
SMLF
CPU1 POWER
IO IOIOSMLFSOCKET6096_13568-001SMLFSOCKET6096_13568-001SMLFIOSOCKET6096_13568-001SOCKET6096_13568-001SMLFIOSOCKET6096_13568-001
0402LF05%CHIP1/16W0402LF05%EMPTY1/16WCPU1_VDDBT_RTC_G
2
1R373
2
1 R374
Y19
Y12
Y5
V22
U18
U11
U4
P22
P19
P12
P5
L18
L11
L4
K22
H19
H12
H5
E11
E4
C4
BM5
BJ48
BJ11
BJ4
BH48
BH25
BH23
BG48
BG28
BG26
BG24
BG22
BF48
BF27
BF25
BF23
BD48
BD28
BD26
BD24
BD22
BD19
BD12
BD5
BC48
BC27
BC25
BC23
BB49
BB28
BB26
BB24
BB22
BA48
BA27
BA25
BA23
BA18
BA11
BA4
B5
AY49
AY28
AY26
AY24
AY22
AW48
AW27
AW25
AW23
AV47
AV45
AV43
AV41
AV39
AV36
AV34
AV32
AV30
AV28
AV26
AV24
AV22
AV19
AV12
AV5
AU40
AU35
AU31
AU27
AU23
AT22
AR18
AR11
AR4
AM22
AM19
AM12
AM5
AJ18
AJ11
AJ4
AH22
AF19
AF12
AF5
AD22
AC18
AC11
AC4
AA22
U26
DJ57
B36
D23
DG42
DH14
C59
C23
DF41
DH13
C58
E36
E33
DJ4
DH21
DH17
DG17
D72
D65
D62
D58
D36
D34
D22
D11
D8
D4
C54
C53
C35
C34
C31
BD72
BD69
BD65
BD62
BD58
BD55
BD21
BD18
BD14
BD11
BD7
BD4
B40
A60
A59
A57
A56
A55
A54
A51
A50
A48
A45
A42
A41
A35
A31
U26
Y71
Y64
Y57
V54
U72
U65
U58
P71
P64
P57
P54
L72
L65
L58
K54
H71
H64
H57
DG71
DG64
DE72
DE65
DE58
DB71
DB64
DB57
CY54
CW72
CW65
CW58
CT71
CT64
CT57
CT54
CN72
CN65
CN58
CM54
CK71
CK64
CK57
CJ54
CG72
CG65
CG58
CF54
CD71
CD64
CD57
CB54
CA72
CA65
CA58
BV71
BV64
BV57
BV54
BR72
BR65
BR58
BN54
BM71
BM64
BM57
BM53
BM51
BL54
BL52
BL50
BK53
BK51
BJ72
BJ65
BJ58
BJ54
BJ52
BJ50
BH53
BH51
BG54
BG52
BG50
BF71
BF64
BF57
BF53
BF51
BD54
BD52
BD50
BA72
BA65
BA58
AV71
AV64
AV57
BH27
AR72
AR65
AR58
AM71
AM64
AM57
AM54
AJ72
AJ65
AJ58
AH54
AF71
AF64
AF57
AD54
AC72
AC65
AC58
AA54
BN23
BP51
BN52
BC54
BC52
BB53
BB51
BA54
BA52
BA50
AY53
AY51
AW54
AW52
AW50
AV53
AV51
AV49
AU54
AU52
AU50
AT53
AT51
AR54
AR52
DG5
DE18
DE11
DE4
DB19
DB12
DB5
CY22
CW18
CW11
CW4
CT22
CT19
CT12
CT5
CN18
CN11
CN4
CM22
CK19
CK12
CK5
CJ22
CG18
CG11
CG4
CF22
CD19
CD12
CD5
CB22
CA18
CA11
CA4
BV22
BV19
BV12
BV5
BR18
BR11
BR4
BP22
BN48
BN44
BN40
BN33
BN29
BN25
BM49
BM47
BM45
BM43
BM41
BM39
BM36
BM34
BM32
BM30
BM28
BM26
BM24
BM22
BM19
BM12
BL48
BL27
BL25
BL23
BK49
BK28
BK26
BK24
BK22
BJ27
BJ25
BJ23
BJ18
U26
DH57
DH56
DH54
DH53
DH51
DH50
DH48
DH47
DH45
DH44
DH42
DH41
DH35
DH34
DH32
DH31
DH29
DH28
DH26
DH25
DH23
DH22
DH20
DH19
DG57
DG19
DE54
DE51
DE48
DE45
DE42
DE41
DE35
DE34
DE31
DE28
DE25
DE22
DD54
DD51
DD48
DD45
DD42
DD34
DD31
DD28
DD25
DD22
DC41
DC40
DC36
DC35
DB53
DB52
DB50
DB49
DB47
DB46
DB44
DB43
DB33
DB32
DB30
DB29
DB27
DB26
DB24
DB23
DA41
DA40
DA36
DA35
CV53
CV52
CV50
CV49
CV47
CV46
CV44
CV43
CV33
CV32
CV30
CV29
CV27
CV26
CV24
CV23
CU41
CU40
CU36
CU35
CP53
CP52
CP50
CP49
CP47
CP46
CP44
CP43
CP33
CP32
CP30
CP29
CP27
CP26
CP24
CP23
CN41
CN40
CN36
CN35
CL47
CL46
CL44
CL43
CL33
CL32
CL30
CL29
CK41
CK40
CK36
CK35
CH53
CH52
CH50
CH49
CH47
CH46
CH44
CH43
CH33
CH32
CH30
CH29
CH27
CH26
CH24
CH23
CG41
CG40
CG36
CG35
CD53
CD52
CD50
CD49
CD47
CD46
CD44
CD43
CD33
CD32
CD30
CD29
CD27
CD26
CD24
CD23
CC41
CC40
CC36
CC35
BY53
BY52
BY50
BY49
BY47
BY46
BY44
BY43
BY33
BY32
BY30
BY29
BY27
BY26
BY24
BY23
BW41
BW40
BW36
BW35
BT53
BT52
BT50
BT49
BT47
BT46
BT44
BT43
BT33
BT32
BT30
BT29
BT27
BT26
BT24
BT23
BR52
BR50
BR48
BR46
BR44
BR42
BR40
BR35
BR33
BR31
BR29
BR27
BR25
BR23
BP49
BP47
BP45
BP43
BP41
BP39
BP36
BP34
BP32
BP30
BP28
BP26
BP24
BN50
BN46
BN42
BN35
BN31
BN27
U26
Y41
Y40
Y36
Y35
W47
W46
W44
W43
W33
W32
W30
W29
U41
U40
U36
U35
T53
T52
T50
T49
T47
T46
T44
T43
T33
T32
T30
T29
T27
T26
T24
T23
N41
N40
N36
N35
M53
M52
M50
M49
M47
M46
M44
M43
M33
M32
M30
M29
M27
M26
M24
M23
J41
J40
J36
J35
H53
H52
H50
H49
H47
H46
H44
H43
H33
H32
H30
H29
H27
H26
H24
H23
G41
G40
G36
G35
F54
F51
F48
F45
F42
F34
F31
F28
F25
F22
E54
E51
E48
E45
E42
E35
E34
E31
E28
E25
E22
D56
D55
C20
B57
B56
B54
B53
B51
B50
B48
B47
B45
B44
B42
B41
B35
B34
B32
B31
B29
B28
B26
B25
B23
B22
B20
B19
AU48
AU46
AU44
AU42
AU33
AU29
AU25
AT49
AT47
AT45
AT43
AT41
AT39
AT36
AT34
AT32
AT30
AT28
AT26
AT24
AR50
AR48
AR46
AR44
AR42
AR40
AR35
AR33
AR31
AR29
AR27
AR25
AR23
AP53
AP52
AP50
AP49
AP47
AP46
AP44
AP43
AP33
AP32
AP30
AP29
AP27
AP26
AP24
AP23
AL41
AL40
AL36
AL35
AK53
AK52
AK50
AK49
AK47
AK46
AK44
AK43
AK33
AK32
AK30
AK29
AK27
AK26
AK24
AK23
AG41
AG40
AG36
AG35
AF53
AF52
AF50
AF49
AF47
AF46
AF44
AF43
AF33
AF32
AF30
AF29
AF27
AF26
AF24
AF23
AC41
AC40
AC36
AC35
AB53
AB52
AB50
AB49
AB47
AB46
AB44
AB43
AB33
AB32
AB30
AB29
AB27
AB26
AB24
AB23
U26
26/40
VDDCR_SOC_BG22
VDDCR_SOC_BG24
VDDCR_SOC_BG26
VDDCR_SOC_BG28
VDDCR_SOC_BG48
VDDCR_SOC_BH23
VDDCR_SOC_BH25
VDDCR_SOC_BH48
VDDCR_SOC_BJ4
VDDCR_SOC_BJ11
VDDCR_SOC_BJ48
VDDCR_SOC_BM5
VDDCR_SOC_BF48
VDDCR_SOC_BF27
VDDCR_SOC_BF25
VDDCR_SOC_BF23
VDDCR_SOC_BD48
VDDCR_SOC_BD28
VDDCR_SOC_BD26
VDDCR_SOC_BD24
VDDCR_SOC_BD22
VDDCR_SOC_BD19
VDDCR_SOC_BD12
VDDCR_SOC_BD5
VDDCR_SOC_BC48
VDDCR_SOC_BC27
VDDCR_SOC_BC25
VDDCR_SOC_BC23
VDDCR_SOC_BB49
VDDCR_SOC_BB28
VDDCR_SOC_BB26
VDDCR_SOC_BB24
VDDCR_SOC_BB22
VDDCR_SOC_BA48
VDDCR_SOC_BA27
VDDCR_SOC_BA25
VDDCR_SOC_BA23
VDDCR_SOC_BA18
VDDCR_SOC_BA11
VDDCR_SOC_BA4
VDDCR_SOC_AY49
VDDCR_SOC_AY28
VDDCR_SOC_AY26
VDDCR_SOC_AY24
VDDCR_SOC_AY22
VDDCR_SOC_AW48
VDDCR_SOC_AW27
VDDCR_SOC_AW25
VDDCR_SOC_AW23
VDDCR_SOC_AV47
VDDCR_SOC_AV45
VDDCR_SOC_AV43
VDDCR_SOC_AV41
VDDCR_SOC_AV39
VDDCR_SOC_AV36
VDDCR_SOC_AV34
VDDCR_SOC_AV32
VDDCR_SOC_AV30
VDDCR_SOC_AV28
VDDCR_SOC_AV26
VDDCR_SOC_AV24
VDDCR_SOC_AV22
VDDCR_SOC_AV19
VDDCR_SOC_AV12
VDDCR_SOC_AV5
VDDCR_SOC_AU40
VDDCR_SOC_AU35
VDDCR_SOC_AU31
VDDCR_SOC_AU27
VDDCR_SOC_AU23
VDDCR_SOC_AT22
VDDCR_SOC_AR18
VDDCR_SOC_AR11
VDDCR_SOC_AR4
VDDCR_SOC_AM22
VDDCR_SOC_AM19
VDDCR_SOC_AM12
VDDCR_SOC_AM5
VDDCR_SOC_AJ18
VDDCR_SOC_AJ11
VDDCR_SOC_AJ4
VDDCR_SOC_AH22
VDDCR_SOC_AF19
VDDCR_SOC_AF12
VDDCR_SOC_AF5
VDDCR_SOC_AD22
VDDCR_SOC_AC18
VDDCR_SOC_AC11
VDDCR_SOC_AC4
VDDCR_SOC_AA22
VDDCR_SOC_Y19
VDDCR_SOC_Y12
VDDCR_SOC_Y5
VDDCR_SOC_V22
VDDCR_SOC_U18
VDDCR_SOC_U11
VDDCR_SOC_U4
VDDCR_SOC_P22
VDDCR_SOC_P19
VDDCR_SOC_P12
VDDCR_SOC_P5
VDDCR_SOC_L18
VDDCR_SOC_L11
VDDCR_SOC_L4
VDDCR_SOC_K22
VDDCR_SOC_H19
VDDCR_SOC_H12
VDDCR_SOC_H5
VDDCR_SOC_E11
VDDCR_SOC_E4
VDDCR_SOC_C4
VDDCR_SOC_B5
23/40
TEST6_X3D6
TEST4_CCD15
TEST4_CCD12
TEST5_CCD12
TEST5_CCD15
TEST4_CCD14
TEST5_CCD14
TEST4_CCD13
TEST5_CCD13
TEST6_X3D7
RSVD_A60
RSVD_BD7
RSVD_D36
RSVD_BD58
RSVD_BD55
RSVD_A54
RSVD_A51
RSVD_A50
RSVD_A48
RSVD_C53
RSVD_A45
RSVD_C35
RSVD_D65
RSVD_A42
RSVD_C34
RSVD_D62
RSVD_BD21
RSVD_A41
RSVD_C31
RSVD_D58
RSVD_BD18
RSVD_DJ4
RSVD_A35
RSVD_B40
RSVD_BD14
RSVD_DH21
RSVD_A31
RSVD_D34
RSVD_BD11
RSVD_DH17
RSVD_A59
RSVD_D22
RSVD_DG17
RSVD_A57
RSVD_D11
RSVD_BD4
RSVD_BD72
RSVD_A56
RSVD_D8
RSVD_E36
RSVD_BD69
RSVD_A55
RSVD_D4
RSVD_E33
RSVD_BD65
RSVD_C54
RSVD_D72
RSVD_BD62
27/40
VDD_11_S3_CT19
VDD_11_S3_CT22
VDD_11_S3_CW4
VDD_11_S3_CW11
VDD_11_S3_CW18
VDD_11_S3_CY22
VDD_11_S3_DB5
VDD_11_S3_DB12
VDD_11_S3_DB19
VDD_11_S3_DE4
VDD_11_S3_DE11
VDD_11_S3_DE18
VDD_11_S3_DG5
VDDIO_CT64
VDDIO_CT71
VDDIO_CW58
VDDIO_CW65
VDDIO_CW72
VDDIO_CY54
VDDIO_DB57
VDDIO_DB64
VDDIO_DB71
VDDIO_DE58
VDDIO_DE65
VDDIO_DE72
VDDIO_DG64
VDDIO_DG71
VDDBT_RTC_G
VDDIO_AUDIO
VDD_33_S5_BP51
VDD_33_S5_BN52
VDD_11_S3_CT12
VDD_18_S5_BB53
VDD_18_S5_BB51
VDD_18_S5_BA54
VDD_18_S5_BA52
VDD_18_S5_BA50
VDD_18_S5_AY53
VDD_18_S5_AY51
VDD_18_S5_AW54
VDD_18_S5_AW52
VDD_18_S5_BC54
VDD_18_S5_BC52
VDD_18_S5_AW50
VDD_18_S5_AV53
VDD_18_S5_AV51
VDD_18_S5_AV49
VDD_18_S5_AU52
VDD_18_S5_AU50
VDD_18_S5_AT53
VDD_18_S5_AT51
VDD_18_S5_AR54
VDD_18_S5_AR52
VDD_18_S5_AU54
VDD_11_S3_CT5
VDD_11_S3_CN18
VDD_11_S3_CN11
VDD_11_S3_CN4
VDD_11_S3_CM22
VDD_11_S3_CK19
VDD_11_S3_CK12
VDD_11_S3_CK5
VDD_11_S3_CJ22
VDD_11_S3_CG18
VDD_11_S3_CG11
VDD_11_S3_CG4
VDD_11_S3_CF22
VDD_11_S3_CD19
VDD_11_S3_CD12
VDD_11_S3_CD5
VDD_11_S3_CB22
VDD_11_S3_CA18
VDD_11_S3_CA11
VDD_11_S3_CA4
VDD_11_S3_BV22
VDD_11_S3_BV19
VDD_11_S3_BV12
VDD_11_S3_BV5
VDD_11_S3_BR18
VDD_11_S3_BR11
VDD_11_S3_BR4
VDD_11_S3_BP22
VDD_11_S3_BN48
VDD_11_S3_BN44
VDD_11_S3_BN40
VDD_11_S3_BN33
VDD_11_S3_BN29
VDD_11_S3_BN25
VDD_11_S3_BM49
VDD_11_S3_BM47
VDD_11_S3_BM45
VDD_11_S3_BM43
VDD_11_S3_BM41
VDD_11_S3_BM39
VDD_11_S3_BM36
VDD_11_S3_BM34
VDD_11_S3_BM32
VDD_11_S3_BM30
VDD_11_S3_BM28
VDD_11_S3_BM26
VDD_11_S3_BM24
VDD_11_S3_BM22
VDD_11_S3_BM19
VDD_11_S3_BM12
VDD_11_S3_BL48
VDD_11_S3_BL27
VDD_11_S3_BL25
VDD_11_S3_BL23
VDD_11_S3_BK49
VDD_11_S3_BK28
VDD_11_S3_BK26
VDD_11_S3_BK24
VDD_11_S3_BK22
VDD_11_S3_BJ27
VDD_11_S3_BJ25
VDD_11_S3_BJ23
VDD_11_S3_BJ18
VDDIO_CT57
VDDIO_CT54
VDDIO_CN72
VDDIO_CN65
VDDIO_CN58
VDDIO_CM54
VDDIO_CK71
VDDIO_CK64
VDDIO_CK57
VDDIO_CJ54
VDDIO_CG72
VDDIO_CG65
VDDIO_CG58
VDDIO_CF54
VDDIO_CD71
VDDIO_CD64
VDDIO_CD57
VDDIO_CB54
VDDIO_CA72
VDDIO_CA65
VDDIO_CA58
VDDIO_BV71
VDDIO_BV64
VDDIO_BV57
VDDIO_BV54
VDDIO_BR72
VDDIO_BR65
VDDIO_BR58
VDDIO_BN54
VDDIO_BM71
VDDIO_BM64
VDDIO_BM57
VDDIO_BM53
VDDIO_BM51
VDDIO_BL54
VDDIO_BL52
VDDIO_BL50
VDDIO_BK53
VDDIO_BK51
VDDIO_BJ72
VDDIO_BJ65
VDDIO_BJ58
VDDIO_BJ54
VDDIO_BJ52
VDDIO_BJ50
VDDIO_BH53
VDDIO_BH51
VDDIO_BG54
VDDIO_BG52
VDDIO_BG50
VDDIO_BF71
VDDIO_BF64
VDDIO_BF57
VDDIO_BF53
VDDIO_BF51
VDDIO_BD54
VDDIO_BD52
VDDIO_BD50
VDDIO_BA72
VDDIO_BA65
VDDIO_BA58
VDDIO_AV71
VDDIO_AV64
VDDIO_AV57
VDDIO_AR72
VDDIO_AR65
VDDIO_AR58
VDDIO_AM71
VDDIO_AM64
VDDIO_AM57
VDDIO_AM54
VDDIO_AJ72
VDDIO_AJ65
VDDIO_AJ58
VDDIO_AH54
VDDIO_AF71
VDDIO_AF64
VDDIO_AF57
VDDIO_AD54
VDDIO_AC72
VDDIO_AC65
VDDIO_AC58
VDDIO_AA54
VDDIO_Y71
VDDIO_Y64
VDDIO_Y57
VDDIO_V54
VDDIO_U72
VDDIO_U65
VDDIO_U58
VDDIO_P71
VDDIO_P64
VDDIO_P57
VDDIO_P54
VDDIO_L72
VDDIO_L65
VDDIO_L58
VDDIO_K54
VDDIO_H71
VDDIO_H64
VDDIO_H5725/40
VDDCR_CPU1_BN46
VDDCR_CPU1_BN35
VDDCR_CPU1_BN27
VDDCR_CPU1_BP32
VDDCR_CPU1_BP28
VDDCR_CPU1_BP24
VDDCR_CPU1_DH51
VDDCR_CPU1_DH50
VDDCR_CPU1_DH48
VDDCR_CPU1_DH47
VDDCR_CPU1_DH45
VDDCR_CPU1_DH57
VDDCR_CPU1_DH56
VDDCR_CPU1_DH54
VDDCR_CPU1_DH53
VDDCR_CPU1_DH44
VDDCR_CPU1_DH42
VDDCR_CPU1_DH41
VDDCR_CPU1_DH35
VDDCR_CPU1_DH34
VDDCR_CPU1_DH32
VDDCR_CPU1_DH31
VDDCR_CPU1_DH29
VDDCR_CPU1_DH28
VDDCR_CPU1_DH26
VDDCR_CPU1_DH25
VDDCR_CPU1_DH23
VDDCR_CPU1_DH22
VDDCR_CPU1_DH20
VDDCR_CPU1_DH19
VDDCR_CPU1_DG57
VDDCR_CPU1_DG19
VDDCR_CPU1_DE54
VDDCR_CPU1_DE51
VDDCR_CPU1_DE48
VDDCR_CPU1_DE45
VDDCR_CPU1_DE42
VDDCR_CPU1_DE41
VDDCR_CPU1_DE35
VDDCR_CPU1_DE34
VDDCR_CPU1_DE31
VDDCR_CPU1_DE28
VDDCR_CPU1_DE25
VDDCR_CPU1_DE22
VDDCR_CPU1_DD54
VDDCR_CPU1_DD51
VDDCR_CPU1_DD48
VDDCR_CPU1_DD45
VDDCR_CPU1_DD42
VDDCR_CPU1_DD34
VDDCR_CPU1_DD31
VDDCR_CPU1_DD28
VDDCR_CPU1_DD25
VDDCR_CPU1_DD22
VDDCR_CPU1_DC41
VDDCR_CPU1_DC40
VDDCR_CPU1_DC36
VDDCR_CPU1_DC35
VDDCR_CPU1_DB53
VDDCR_CPU1_DB52
VDDCR_CPU1_DB50
VDDCR_CPU1_DB49
VDDCR_CPU1_DB47
VDDCR_CPU1_DB46
VDDCR_CPU1_DB44
VDDCR_CPU1_DB43
VDDCR_CPU1_DB33
VDDCR_CPU1_DB32
VDDCR_CPU1_DB30
VDDCR_CPU1_DB29
VDDCR_CPU1_DB27
VDDCR_CPU1_DB26
VDDCR_CPU1_DB24
VDDCR_CPU1_DB23
VDDCR_CPU1_DA41
VDDCR_CPU1_DA40
VDDCR_CPU1_DA36
VDDCR_CPU1_DA35
VDDCR_CPU1_CV53
VDDCR_CPU1_CV52
VDDCR_CPU1_CV50
VDDCR_CPU1_CV49
VDDCR_CPU1_CV47
VDDCR_CPU1_CV46
VDDCR_CPU1_CV44
VDDCR_CPU1_CV43
VDDCR_CPU1_CV33
VDDCR_CPU1_CV32
VDDCR_CPU1_CV30
VDDCR_CPU1_CV29
VDDCR_CPU1_CV27
VDDCR_CPU1_CV26
VDDCR_CPU1_CV24
VDDCR_CPU1_CV23
VDDCR_CPU1_CU41
VDDCR_CPU1_CU40
VDDCR_CPU1_CU36
VDDCR_CPU1_CU35
VDDCR_CPU1_CP53
VDDCR_CPU1_CP52
VDDCR_CPU1_CP50
VDDCR_CPU1_CP49
VDDCR_CPU1_CP47
VDDCR_CPU1_CP46
VDDCR_CPU1_CP44
VDDCR_CPU1_CP43
VDDCR_CPU1_CP33
VDDCR_CPU1_CP32
VDDCR_CPU1_CP30
VDDCR_CPU1_CP29
VDDCR_CPU1_CP27
VDDCR_CPU1_CP26
VDDCR_CPU1_CP24
VDDCR_CPU1_CP23
VDDCR_CPU1_CN41
VDDCR_CPU1_CN40
VDDCR_CPU1_CN36
VDDCR_CPU1_CN35
VDDCR_CPU1_CL47
VDDCR_CPU1_CL46
VDDCR_CPU1_CL44
VDDCR_CPU1_CL43
VDDCR_CPU1_CL33
VDDCR_CPU1_CL32
VDDCR_CPU1_CL30
VDDCR_CPU1_CL29
VDDCR_CPU1_CK41
VDDCR_CPU1_CK40
VDDCR_CPU1_CK36
VDDCR_CPU1_CK35
VDDCR_CPU1_CH53
VDDCR_CPU1_CH52
VDDCR_CPU1_CH50
VDDCR_CPU1_CH49
VDDCR_CPU1_CH47
VDDCR_CPU1_CH46
VDDCR_CPU1_CH44
VDDCR_CPU1_CH43
VDDCR_CPU1_CH33
VDDCR_CPU1_CH32
VDDCR_CPU1_CH30
VDDCR_CPU1_CH29
VDDCR_CPU1_CH27
VDDCR_CPU1_CH26
VDDCR_CPU1_CH24
VDDCR_CPU1_CH23
VDDCR_CPU1_CG41
VDDCR_CPU1_CG40
VDDCR_CPU1_CG36
VDDCR_CPU1_CG35
VDDCR_CPU1_CD53
VDDCR_CPU1_CD52
VDDCR_CPU1_CD50
VDDCR_CPU1_CD49
VDDCR_CPU1_CD47
VDDCR_CPU1_CD46
VDDCR_CPU1_CD44
VDDCR_CPU1_CD43
VDDCR_CPU1_CD33
VDDCR_CPU1_CD32
VDDCR_CPU1_CD30
VDDCR_CPU1_CD29
VDDCR_CPU1_CD27
VDDCR_CPU1_CD26
VDDCR_CPU1_CD24
VDDCR_CPU1_CD23
VDDCR_CPU1_CC41
VDDCR_CPU1_CC40
VDDCR_CPU1_CC36
VDDCR_CPU1_CC35
VDDCR_CPU1_BY53
VDDCR_CPU1_BY52
VDDCR_CPU1_BY50
VDDCR_CPU1_BY49
VDDCR_CPU1_BY47
VDDCR_CPU1_BY46
VDDCR_CPU1_BY44
VDDCR_CPU1_BY43
VDDCR_CPU1_BY33
VDDCR_CPU1_BY32
VDDCR_CPU1_BY30
VDDCR_CPU1_BY29
VDDCR_CPU1_BY27
VDDCR_CPU1_BY26
VDDCR_CPU1_BY24
VDDCR_CPU1_BY23
VDDCR_CPU1_BW41
VDDCR_CPU1_BW40
VDDCR_CPU1_BW36
VDDCR_CPU1_BW35
VDDCR_CPU1_BT53
VDDCR_CPU1_BT52
VDDCR_CPU1_BT50
VDDCR_CPU1_BT49
VDDCR_CPU1_BT47
VDDCR_CPU1_BT46
VDDCR_CPU1_BT44
VDDCR_CPU1_BT43
VDDCR_CPU1_BT33
VDDCR_CPU1_BT32
VDDCR_CPU1_BT30
VDDCR_CPU1_BT29
VDDCR_CPU1_BT27
VDDCR_CPU1_BT26
VDDCR_CPU1_BT24
VDDCR_CPU1_BT23
VDDCR_CPU1_BR52
VDDCR_CPU1_BR50
VDDCR_CPU1_BR48
VDDCR_CPU1_BR46
VDDCR_CPU1_BR44
VDDCR_CPU1_BR42
VDDCR_CPU1_BR40
VDDCR_CPU1_BR35
VDDCR_CPU1_BR33
VDDCR_CPU1_BR31
VDDCR_CPU1_BR29
VDDCR_CPU1_BR27
VDDCR_CPU1_BR25
VDDCR_CPU1_BR23
VDDCR_CPU1_BP49
VDDCR_CPU1_BP47
VDDCR_CPU1_BP45
VDDCR_CPU1_BP43
VDDCR_CPU1_BP41
VDDCR_CPU1_BP39
VDDCR_CPU1_BP36
VDDCR_CPU1_BP34
VDDCR_CPU1_BP30
VDDCR_CPU1_BP26
VDDCR_CPU1_BN50
VDDCR_CPU1_BN42
VDDCR_CPU1_BN31
24/40
VDDCR_CPU0_AU33
VDDCR_CPU0_AU25
VDDCR_CPU0_AU48
VDDCR_CPU0_AU44
VDDCR_CPU0_AU29
VDDCR_CPU0_AT49
VDDCR_CPU0_AU46
VDDCR_CPU0_AU42
VDDCR_CPU0_Y35
VDDCR_CPU0_Y36
VDDCR_CPU0_Y40
VDDCR_CPU0_Y41
VDDCR_CPU0_AB23
VDDCR_CPU0_AB24
VDDCR_CPU0_AB26
VDDCR_CPU0_AB27
VDDCR_CPU0_AB29
VDDCR_CPU0_AB30
VDDCR_CPU0_AB32
VDDCR_CPU0_AB33
VDDCR_CPU0_AB43
VDDCR_CPU0_AB44
VDDCR_CPU0_AB46
VDDCR_CPU0_AB47
VDDCR_CPU0_AB49
VDDCR_CPU0_AB50
VDDCR_CPU0_AB52
VDDCR_CPU0_AB53
VDDCR_CPU0_AC35
VDDCR_CPU0_AC36
VDDCR_CPU0_AC40
VDDCR_CPU0_AC41
VDDCR_CPU0_AF23
VDDCR_CPU0_AF24
VDDCR_CPU0_AF26
VDDCR_CPU0_AF27
VDDCR_CPU0_AF29
VDDCR_CPU0_AF30
VDDCR_CPU0_AF32
VDDCR_CPU0_AF33
VDDCR_CPU0_AF43
VDDCR_CPU0_AF44
VDDCR_CPU0_AF46
VDDCR_CPU0_AF47
VDDCR_CPU0_AF49
VDDCR_CPU0_AF50
VDDCR_CPU0_AF52
VDDCR_CPU0_AF53
VDDCR_CPU0_AG35
VDDCR_CPU0_AG36
VDDCR_CPU0_AG40
VDDCR_CPU0_AG41
VDDCR_CPU0_AK23
VDDCR_CPU0_AK24
VDDCR_CPU0_AK26
VDDCR_CPU0_AK27
VDDCR_CPU0_AK29
VDDCR_CPU0_AK30
VDDCR_CPU0_AK32
VDDCR_CPU0_AK33
VDDCR_CPU0_AK43
VDDCR_CPU0_AK44
VDDCR_CPU0_AK46
VDDCR_CPU0_AK47
VDDCR_CPU0_AK49
VDDCR_CPU0_AK50
VDDCR_CPU0_AK52
VDDCR_CPU0_AK53
VDDCR_CPU0_AL35
VDDCR_CPU0_AL36
VDDCR_CPU0_AL40
VDDCR_CPU0_AL41
VDDCR_CPU0_AP23
VDDCR_CPU0_AP24
VDDCR_CPU0_AP26
VDDCR_CPU0_AP27
VDDCR_CPU0_AP29
VDDCR_CPU0_AP30
VDDCR_CPU0_AP32
VDDCR_CPU0_AP33
VDDCR_CPU0_AP43
VDDCR_CPU0_AP44
VDDCR_CPU0_AP46
VDDCR_CPU0_AP47
VDDCR_CPU0_AP49
VDDCR_CPU0_AP50
VDDCR_CPU0_AP52
VDDCR_CPU0_AP53
VDDCR_CPU0_AR23
VDDCR_CPU0_AR25
VDDCR_CPU0_AR27
VDDCR_CPU0_AR29
VDDCR_CPU0_AR31
VDDCR_CPU0_AR33
VDDCR_CPU0_AR35
VDDCR_CPU0_AR40
VDDCR_CPU0_AR42
VDDCR_CPU0_AR44
VDDCR_CPU0_AR46
VDDCR_CPU0_AR48
VDDCR_CPU0_AR50
VDDCR_CPU0_AT24
VDDCR_CPU0_AT26
VDDCR_CPU0_AT28
VDDCR_CPU0_AT30
VDDCR_CPU0_AT32
VDDCR_CPU0_AT34
VDDCR_CPU0_AT36
VDDCR_CPU0_AT39
VDDCR_CPU0_AT41
VDDCR_CPU0_AT43
VDDCR_CPU0_AT45
VDDCR_CPU0_AT47
VDDCR_CPU0_B19
VDDCR_CPU0_B20
VDDCR_CPU0_B22
VDDCR_CPU0_B23
VDDCR_CPU0_B25
VDDCR_CPU0_B26
VDDCR_CPU0_B28
VDDCR_CPU0_B29
VDDCR_CPU0_B31
VDDCR_CPU0_B32
VDDCR_CPU0_B34
VDDCR_CPU0_B35
VDDCR_CPU0_B41
VDDCR_CPU0_B42
VDDCR_CPU0_B44
VDDCR_CPU0_B45
VDDCR_CPU0_B47
VDDCR_CPU0_B48
VDDCR_CPU0_B50
VDDCR_CPU0_B51
VDDCR_CPU0_B53
VDDCR_CPU0_B54
VDDCR_CPU0_B56
VDDCR_CPU0_B57
VDDCR_CPU0_C20
VDDCR_CPU0_D55
VDDCR_CPU0_D56
VDDCR_CPU0_E22
VDDCR_CPU0_E25
VDDCR_CPU0_E28
VDDCR_CPU0_E31
VDDCR_CPU0_E34
VDDCR_CPU0_E35
VDDCR_CPU0_E42
VDDCR_CPU0_E45
VDDCR_CPU0_E48
VDDCR_CPU0_E51
VDDCR_CPU0_E54
VDDCR_CPU0_F22
VDDCR_CPU0_F25
VDDCR_CPU0_F28
VDDCR_CPU0_F31
VDDCR_CPU0_F34
VDDCR_CPU0_F42
VDDCR_CPU0_F45
VDDCR_CPU0_F48
VDDCR_CPU0_F51
VDDCR_CPU0_F54
VDDCR_CPU0_G35
VDDCR_CPU0_G36
VDDCR_CPU0_G40
VDDCR_CPU0_G41
VDDCR_CPU0_H23
VDDCR_CPU0_H24
VDDCR_CPU0_H26
VDDCR_CPU0_H27
VDDCR_CPU0_H29
VDDCR_CPU0_H30
VDDCR_CPU0_H32
VDDCR_CPU0_H33
VDDCR_CPU0_H43
VDDCR_CPU0_H44
VDDCR_CPU0_H46
VDDCR_CPU0_H47
VDDCR_CPU0_H49
VDDCR_CPU0_H50
VDDCR_CPU0_H52
VDDCR_CPU0_H53
VDDCR_CPU0_J35
VDDCR_CPU0_J36
VDDCR_CPU0_J40
VDDCR_CPU0_J41
VDDCR_CPU0_M23
VDDCR_CPU0_M24
VDDCR_CPU0_M26
VDDCR_CPU0_M27
VDDCR_CPU0_M29
VDDCR_CPU0_M30
VDDCR_CPU0_M32
VDDCR_CPU0_M33
VDDCR_CPU0_M43
VDDCR_CPU0_M44
VDDCR_CPU0_M46
VDDCR_CPU0_M47
VDDCR_CPU0_M49
VDDCR_CPU0_M50
VDDCR_CPU0_M52
VDDCR_CPU0_M53
VDDCR_CPU0_N35
VDDCR_CPU0_N36
VDDCR_CPU0_N40
VDDCR_CPU0_N41
VDDCR_CPU0_T23
VDDCR_CPU0_T24
VDDCR_CPU0_T26
VDDCR_CPU0_T27
VDDCR_CPU0_T29
VDDCR_CPU0_T30
VDDCR_CPU0_T32
VDDCR_CPU0_T33
VDDCR_CPU0_T43
VDDCR_CPU0_T44
VDDCR_CPU0_T46
VDDCR_CPU0_T47
VDDCR_CPU0_T49
VDDCR_CPU0_T50
VDDCR_CPU0_T52
VDDCR_CPU0_T53
VDDCR_CPU0_U35
VDDCR_CPU0_U36
VDDCR_CPU0_U40
VDDCR_CPU0_U41
VDDCR_CPU0_W29
VDDCR_CPU0_W30
VDDCR_CPU0_W32
VDDCR_CPU0_W33
VDDCR_CPU0_W43
VDDCR_CPU0_W44
VDDCR_CPU0_W46
VDDCR_CPU0_W47
SHEETDATE
DEPARTMENT
SIZE
PROJECT DOCUMENT NUMBER REV
REVIEWER
DESIGNER
123
7 3 2 1 6 5 4
E
A
B
C
E
D
C
B
A
7 6 5 4
D
C



Thu Sep 14 16:12:01 2023<NAME_2><NAME_1>MB FABCGT AMDV0258 OF 365
SOCKET6096_13568-001 SOCKET6096_13568-001 SOCKET6096_13568-001SOCKET6096_13568-001SOCKET6096_13568-001SOCKET6096_13568-001IOIOIOIOIOIO
CPU1 VSS 1/3
SMLFSMLFSMLFSMLFSMLFSMLF
T64
T61
T59
T57
T54
T51
T48
T45
T42
T39
T37
T34
T31
T28
T25
T22
T19
T17
T15
T12
T10
T8
T5
T3
R75
R72
R70
R68
R65
R63
R61
R58
R56
R54
R51
R48
R45
R42
R41
R40
R36
R35
R34
R31
R28
R25
R22
R20
R18
R15
R13
R11
R8
R6
R4
R1
P73
P66
P61
P59
P53
P52
P51
P50
P49
P48
P47
P46
P45
P44
P43
P42
P39
P37
P34
P33
P32
P31
P30
P29
P28
P27
P26
P24
P23
P17
P15
P10
P8
P3
N75
N72
N70
N68
N65
N63
N61
N58
N56
N54
N51
N48
N45
N42
N34
N31
N28
N25
N22
N20
N18
N15
N13
N11
N8
N6
N4
N1
M73
M71
M68
M66
M64
M61
M59
M57
M54
M51
M48
M45
M42
M39
M37
M34
M31
M28
M25
M22
M19
M17
M15
M12
M10
M8
M5
M3
L75
L70
L68
L63
L61
L56
L54
L51
L48
L45
L42
L41
L40
L36
L35
L34
L31
L28
L25
L22
L20
L15
L13
L8
L6
L1
K73
K71
K68
K66
K64
K61
K57
K53
K52
K51
K50
K49
K48
K47
K46
K45
K44
K43
K42
K39
K37
K34
K33
K32
K31
K30
K29
K28
K27
K26
K25
K24
K19
K17
K15
K12
K10
K8
K5
K3
J75
J72
J70
J68
J65
J63
J61
J58
J56
J54
J51
J48
J45
J42
J34
J31
J28
J25
J22
J20
J18
J15
U26
Y73
Y68
Y66
Y61
Y59
Y54
Y53
Y52
Y51
Y50
Y49
Y48
Y45
Y44
Y43
Y42
Y39
Y37
Y34
Y33
Y32
Y31
Y28
Y27
Y26
Y25
Y24
Y23
Y22
Y17
Y15
Y10
Y8
Y3
W75
W72
W70
W68
W65
W63
W61
W58
W56
W54
W51
W48
W45
W42
W41
W40
W36
W35
W34
W28
W25
W22
W20
W18
W15
W13
W11
W8
W6
W4
W1
V73
V71
V66
V64
V61
V59
V57
V53
V52
V51
V50
V49
V48
V47
V46
V45
V44
V43
V42
V39
V37
V34
V33
V32
V31
V30
V29
V28
V26
V25
V24
V23
V19
V17
V15
V12
V10
V8
V5
V3
U75
U70
U68
U63
U61
U56
U54
U51
U48
U45
U42
U34
U31
U28
U25
U22
U20
U15
U13
U8
U6
U1
T73
T71
T68
T66
AD48
AD47
AD46
AD45
AD44
AD43
AD42
AD39
AD37
AD34
AD33
AD32
AD30
AD29
AD28
AD27
AD26
AD25
AD24
AD23
AD19
AD17
AD15
AD12
AD10
AD8
AD5
AD3
AC75
AC70
AC68
AC63
AC61
AC56
AC54
AC51
AC48
AC45
AC42
AC34
AC31
AC28
AC25
AC22
AC20
AC15
AC13
AC8
AC6
AC1
AB73
AB71
AB68
AB66
AB64
AB61
AB59
AB57
AB54
AB51
AB48
AB45
AB42
AB39
AB37
AB34
AB31
AB28
AB25
AB22
AB19
AB17
AB15
AB12
AB10
AB8
AB5
AB3
AA75
AA70
AA68
AA65
AA63
AA61
AA58
AA56
AA45
AA41
AA40
AA36
AA35
AA34
AA31
AA20
AA18
AA15
AA13
AA11
AA8
AA6
AA4
AA1
U26
AM39
AM34
AM33
AM32
AM31
AM30
AM29
AM28
AM27
AM26
AM25
AM24
AM23
AM17
AM15
AM10
AM8
AM3
AL75
AL72
AL70
AL68
AL65
AL63
AL61
AL58
AL56
AL54
AL51
AL48
AL45
AL42
AL34
AL31
AL28
AL25
AL22
AL20
AL18
AL15
AL13
AL11
AL8
AL6
AL4
AL1
AK73
AK71
AK68
AK66
AK64
AK61
AK59
AK57
AK54
AK51
AK48
AK45
AK42
AK39
AK37
AK34
AK31
AK28
AK25
AK22
AK19
AK17
AK15
AK12
AK10
AK8
AK5
AK3
AJ75
AJ70
AJ68
AJ63
AJ61
AJ56
AJ54
AJ51
AJ48
AJ45
AJ42
AJ41
AJ40
AJ36
AJ35
AJ34
AJ31
AJ28
AJ25
AJ22
AJ20
AJ15
AJ8
AJ6
AJ1
AH73
AH71
AH68
AH66
AH64
AH61
AH59
AH57
AH53
AH52
AH51
AH50
AH49
AH48
AH47
AH46
AH45
AH44
AH43
AH42
AH39
AH37
AH34
AH32
AH31
AH30
AH29
AH28
AH27
AH26
AH25
AH24
AH23
AH19
AH17
AH15
AH12
AH10
AH8
AH5
AH3
AG75
AG72
AG70
AG68
AG65
AG63
AG61
AG58
AG56
AG54
AG51
AG48
AG45
AG42
AG34
AG31
AG28
AG25
AG22
AG20
AG18
AG15
AG13
AG11
AG8
AG6
AG4
AG1
AF73
AF68
AF66
AF61
AF59
AF54
AF51
AF48
AF45
AF42
AF39
AF37
AF34
AF31
AF28
AF25
AF22
AF17
AF15
AF10
AF8
AF3
AE75
AE72
AE70
AE68
AE65
AE63
AE61
AE58
AE56
AE54
AE51
AE48
AE45
AE42
AE41
AE40
AE36
AE35
AE34
AE31
AE28
AE25
AE22
AE20
AE18
AE15
AE13
AE11
AE8
AE6
AE1
AD73
AD71
AD68
AD66
AD64
AD61
AD59
AD57
AD53
AD52
AD51
AD50
AD49
U26
AW61
AW58
AW56
AW53
AW51
AW49
AW28
AW26
AW24
AW22
AW20
AW18
AW15
AW13
AW11
AW8
AW6
AW4
AW1
AV73
AV68
AV66
AV61
AV59
AV54
AV52
AV50
AV48
AV46
AV44
AV42
AV40
AV37
AV35
AV33
AV31
AV29
AV27
AV25
AV23
AV17
AV15
AV10
AV8
AV3
AU75
AU73
AU72
AU70
AU68
AU65
AU63
AU61
AU58
AU56
AU53
AU51
AU49
AU47
AU45
AU43
AU41
AU36
AU34
AU32
AU30
AU28
AU26
AU24
AU22
AU20
AU18
AU15
AU13
AU11
AU8
AU6
AU4
AU3
AU1
AT73
AT72
AT71
AT70
AT68
AT67
AT66
AT64
AT63
AT61
AT60
AT59
AT57
AT56
AT54
AT52
AT50
AT48
AT46
AT44
AT42
AT40
AT37
AT35
AT33
AT31
AT29
AT27
AT25
AT23
AT20
AT19
AT17
AT16
AT15
AT13
AT12
AT10
AT9
AT8
AT6
AT5
AT4
AT3
AR75
AR71
AR70
AR68
AR67
AR64
AR63
AR61
AR60
AR57
AR56
AR53
AR51
AR49
AR47
AR45
AR43
AR41
AR36
AR34
AR32
AR30
AR28
AR26
AR24
AR22
AR20
AR19
AR16
AR15
AR13
AR12
AR9
AR8
AR6
AR5
AR1
AP73
AP71
AP68
AP66
AP64
AP61
AP59
AP57
AP54
AP51
AP48
AP45
AP42
AP39
AP37
AP34
AP31
AP28
AP25
AP22
AP19
AP17
AP15
AP12
AP10
AP8
AP5
AP3
AN75
AN72
AN70
AN68
AN65
AN63
AN61
AN58
AN56
AN54
AN51
AN48
AN45
AN42
AN41
AN40
AN36
AN35
AN34
AN31
AN28
AN25
AN22
AN18
AN15
AN13
AN11
AN8
AN6
AN4
AN1
AM73
AM68
AM66
AM61
AM59
AM53
AM52
AM51
AM50
AM49
AM48
AM47
AM46
AM45
AM44
AM43
AM42
U26
BL24
BL22
BL20
BL18
BL15
BL13
BL11
BL8
BL6
BL4
BL1
BK73
BK71
BK68
BK66
BK64
BK61
BK59
BK57
BK54
BK52
BK50
BK48
BK27
BK25
BK23
BK19
BK17
BK15
BK12
BK10
BK8
BK5
BK3
BJ75
BJ70
BJ68
BJ63
BJ61
BJ56
BJ53
BJ51
BJ49
BJ28
BJ26
BJ24
BJ22
BJ20
BJ15
BJ13
BJ8
BJ6
BJ1
BH73
BH71
BH68
BH66
BH64
BH61
BH59
BH57
BH54
BH52
BH50
BH49
BH28
BH26
BH24
BH22
BH19
BH17
BH15
BH12
BH10
BH8
BH5
BH3
BG75
BG72
BG70
BG68
BG65
BG63
BG61
BG58
BG56
BG53
BG51
BG49
BG27
BG25
BG23
BG20
BG18
BG15
BG13
BG11
BG8
BG6
BG4
BG1
BF73
BF68
BF66
BF61
BF59
BF54
BF52
BF50
BF49
BF28
BF26
BF24
BF22
BF19
BF17
BF15
BF12
BF10
BF8
BF5
BF3
BD73
BD71
BD68
BD66
BD64
BD61
BD59
BD57
BD53
BD51
BD49
BD27
BD25
BD23
BD17
BD15
BD10
BD8
BD3
BC75
BC72
BC70
BC68
BC65
BC63
BC61
BC58
BC56
BC53
BC51
BC50
BC49
BC28
BC26
BC24
BC22
BC20
BC18
BC15
BC13
BC11
BC8
BC6
BC4
BC1
BB73
BB71
BB68
BB66
BB64
BB61
BB59
BB57
BB54
BB52
BB50
BB48
BB27
BB25
BB23
BB19
BB17
BB15
BB12
BB10
BB8
BB5
BB3
BA75
BA70
BA68
BA63
BA61
BA56
BA53
BA51
BA49
BA28
BA26
BA24
BA22
BA20
BA15
BA13
BA8
BA6
BA1
AY73
AY71
AY68
AY66
AY64
AY61
AY59
AY57
AY54
AY52
AY50
AY48
AY27
AY25
AY23
AY19
AY17
AY15
AY12
AY10
AY8
AY5
AY3
AW75
AW72
AW70
AW68
AW65
AW63
U26
J13
J11
J8
J6
J4
J1
H73
H68
H66
H61
H59
H54
H51
H48
H45
H42
H39
H37
H34
H31
H28
H25
H22
H17
H15
H10
H8
H3
G75
G72
G70
G68
G65
G63
G61
G58
G56
G54
G51
G48
G45
G42
G34
G31
G28
G25
G22
G20
G18
G15
G13
G11
G8
G6
G4
G1
F73
F71
F68
F66
F64
F61
F59
F57
F53
F52
F50
F49
F47
F46
F44
F43
F41
F40
F39
F37
F36
F35
F33
F32
F30
F29
F27
F26
F24
F23
F19
F17
F15
F12
F10
F8
F5
F3
E75
E73
E72
E70
E69
E68
E66
E65
E63
E62
E61
E59
E58
E56
E55
E53
E52
E21
E20
E18
E17
E15
E14
E13
E10
E8
E7
E6
E3
E1
D74
D73
D71
D70
D67
D66
D64
D63
D61
D60
D59
D57
D54
D53
D52
D51
D50
D49
D48
D47
D46
D45
D44
D43
D42
D41
D40
D39
D37
D35
D31
D30
D29
D28
D27
D26
D25
D24
D21
D20
D19
D17
D16
D13
D12
D10
D9
D6
D5
D3
D2
C75
C73
C71
C69
C67
C64
C61
C57
C56
C55
C52
C49
C46
C43
C40
C36
C30
C27
C24
C21
C15
C13
C11
C10
C8
C5
C1
B70
B68
B65
B62
B59
B55
B52
B49
B46
B43
B39
B37
B33
B30
B27
B24
B18
B13
B11
B10
B8
B7
A73
A72
A67
A61
A53
A49
A47
A44
A43
A27
A21
A15
A9
A3
U26
31/40
VSS_AK8
VSS_AK5
VSS_AK3
VSS_AJ75
VSS_AJ70
VSS_AJ68
VSS_AJ63
VSS_AJ61
VSS_AJ56
VSS_AJ54
VSS_AJ51
VSS_AJ48
VSS_AJ45
VSS_AJ42
VSS_AJ41
VSS_AJ40
VSS_AJ36
VSS_AJ35
VSS_AJ34
VSS_AJ31
VSS_AJ28
VSS_AJ25
VSS_AJ22
VSS_AJ20
VSS_AJ15
VSS_AJ8
VSS_AJ6
VSS_AJ1
VSS_AH73
VSS_AH71
VSS_AH68
VSS_AH66
VSS_AH64
VSS_AH61
VSS_AH59
VSS_AH57
VSS_AH53
VSS_AH52
VSS_AH51
VSS_AH50
VSS_AH49
VSS_AH48
VSS_AH47
VSS_AH46
VSS_AH45
VSS_AH44
VSS_AH43
VSS_AH42
VSS_AH39
VSS_AH37
VSS_AH34
VSS_AH32
VSS_AH31
VSS_AH30
VSS_AH29
VSS_AH28
VSS_AH27
VSS_AH26
VSS_AH25
VSS_AH24
VSS_AH23
VSS_AH19
VSS_AH17
VSS_AH15
VSS_AH12
VSS_AH10
VSS_AH8
VSS_AH5
VSS_AH3
VSS_AG75
VSS_AG72
VSS_AG70
VSS_AG68
VSS_AG65
VSS_AG63
VSS_AG61
VSS_AG58
VSS_AG56
VSS_AG54
VSS_AG51
VSS_AG48
VSS_AG45
VSS_AG42
VSS_AG34
VSS_AG31
VSS_AG28
VSS_AG25
VSS_AG22
VSS_AG20
VSS_AG18
VSS_AG15
VSS_AG13
VSS_AG11
VSS_AG8
VSS_AG6
VSS_AG4
VSS_AG1
VSS_AF73
VSS_AF68
VSS_AF66
VSS_AF61
VSS_AF59
VSS_AF54
VSS_AF51
VSS_AF48
VSS_AF45
VSS_AF42
VSS_AF39
VSS_AF37
VSS_AF34
VSS_AF31
VSS_AF28
VSS_AF25
VSS_AF22
VSS_AF17
VSS_AF15
VSS_AF10
VSS_AF8
VSS_AF3
VSS_AE75
VSS_AE72
VSS_AE70
VSS_AE68
VSS_AE65
VSS_AE63
VSS_AE61
VSS_AE58
VSS_AE56
VSS_AE54
VSS_AE51
VSS_AE48
VSS_AE45
VSS_AE42
VSS_AE41
VSS_AE40
VSS_AE36
VSS_AE35
VSS_AE34
VSS_AE31
VSS_AE28
VSS_AE25
VSS_AE22
VSS_AE20
VSS_AE18
VSS_AE15
VSS_AE13
VSS_AE11
VSS_AE8
VSS_AE6
VSS_AE1
VSS_AD73
VSS_AD71
VSS_AD68
VSS_AD66
VSS_AD64
VSS_AD61
VSS_AD59
VSS_AD57
VSS_AD53
VSS_AD52
VSS_AD51
VSS_AD50
VSS_AD49
VSS_AM39
VSS_AM34
VSS_AM33
VSS_AM32
VSS_AM31
VSS_AM30
VSS_AM29
VSS_AM28
VSS_AM27
VSS_AM26
VSS_AM25
VSS_AM24
VSS_AM23
VSS_AM17
VSS_AM15
VSS_AM10
VSS_AM8
VSS_AM3
VSS_AL75
VSS_AL72
VSS_AL70
VSS_AL68
VSS_AL65
VSS_AL63
VSS_AL61
VSS_AL58
VSS_AL56
VSS_AL54
VSS_AL51
VSS_AL48
VSS_AL45
VSS_AL42
VSS_AL34
VSS_AL31
VSS_AL28
VSS_AL25
VSS_AL22
VSS_AL20
VSS_AL18
VSS_AL15
VSS_AL13
VSS_AL11
VSS_AL8
VSS_AL6
VSS_AL4
VSS_AL1
VSS_AK73
VSS_AK71
VSS_AK68
VSS_AK66
VSS_AK64
VSS_AK61
VSS_AK59
VSS_AK57
VSS_AK54
VSS_AK51
VSS_AK48
VSS_AK45
VSS_AK42
VSS_AK39
VSS_AK37
VSS_AK34
VSS_AK31
VSS_AK28
VSS_AK25
VSS_AK22
VSS_AK19
VSS_AK17
VSS_AK15
VSS_AK12
VSS_AK10
32/40
VSS_AW61
VSS_AW58
VSS_AW56
VSS_AW53
VSS_AW51
VSS_AW49
VSS_AW28
VSS_AW26
VSS_AW24
VSS_AW22
VSS_AW20
VSS_AW18
VSS_AW15
VSS_AW13
VSS_AW11
VSS_AW8
VSS_AW6
VSS_AW4
VSS_AW1
VSS_AV73
VSS_AV68
VSS_AV66
VSS_AV61
VSS_AV59
VSS_AV54
VSS_AV52
VSS_AV50
VSS_AV48
VSS_AV46
VSS_AV44
VSS_AV42
VSS_AV40
VSS_AV37
VSS_AV35
VSS_AV33
VSS_AV31
VSS_AV29
VSS_AV27
VSS_AV25
VSS_AV23
VSS_AV17
VSS_AV15
VSS_AV10
VSS_AV8
VSS_AV3
VSS_AU75
VSS_AU73
VSS_AU72
VSS_AU70
VSS_AU68
VSS_AU65
VSS_AU63
VSS_AU61
VSS_AU58
VSS_AU56
VSS_AU53
VSS_AU51
VSS_AU49
VSS_AU47
VSS_AU45
VSS_AU43
VSS_AU41
VSS_AU36
VSS_AU34
VSS_AU32
VSS_AU30
VSS_AU28
VSS_AU26
VSS_AU24
VSS_AU22
VSS_AU20
VSS_AU18
VSS_AU15
VSS_AU13
VSS_AU11
VSS_AU8
VSS_AU6
VSS_AU4
VSS_AU3
VSS_AU1
VSS_AT73
VSS_AT72
VSS_AT71
VSS_AT70
VSS_AT68
VSS_AT67
VSS_AT66
VSS_AT64
VSS_AT63
VSS_AT61
VSS_AT60
VSS_AT59
VSS_AT57
VSS_AT56
VSS_AT54
VSS_AT52
VSS_AT50
VSS_AT48
VSS_AT46
VSS_AT44
VSS_AT42
VSS_AT40
VSS_AT37
VSS_AT35
VSS_AT33
VSS_AT31
VSS_AT29
VSS_AT27
VSS_AT25
VSS_AT23
VSS_AT20
VSS_AT19
VSS_AT17
VSS_AT16
VSS_AT15
VSS_AT13
VSS_AT12
VSS_AT10
VSS_AT9
VSS_AT8
VSS_AT6
VSS_AT5
VSS_AT4
VSS_AT3
VSS_AR75
VSS_AR71
VSS_AR70
VSS_AR68
VSS_AR67
VSS_AR64
VSS_AR63
VSS_AR61
VSS_AR60
VSS_AR57
VSS_AR56
VSS_AR53
VSS_AR51
VSS_AR49
VSS_AR47
VSS_AR45
VSS_AR43
VSS_AR41
VSS_AR36
VSS_AR34
VSS_AR32
VSS_AR30
VSS_AR28
VSS_AR26
VSS_AR24
VSS_AR22
VSS_AR20
VSS_AR19
VSS_AR16
VSS_AR15
VSS_AR13
VSS_AR12
VSS_AR9
VSS_AR8
VSS_AR6
VSS_AR5
VSS_AR1
VSS_AP73
VSS_AP71
VSS_AP68
VSS_AP66
VSS_AP64
VSS_AP61
VSS_AP59
VSS_AP57
VSS_AP54
VSS_AP51
VSS_AP48
VSS_AP45
VSS_AP42
VSS_AP39
VSS_AP37
VSS_AP34
VSS_AP31
VSS_AP28
VSS_AP25
VSS_AP22
VSS_AP19
VSS_AP17
VSS_AP15
VSS_AP12
VSS_AP10
VSS_AP8
VSS_AP5
VSS_AP3
VSS_AN75
VSS_AN72
VSS_AN70
VSS_AN68
VSS_AN65
VSS_AN63
VSS_AN61
VSS_AN58
VSS_AN56
VSS_AN54
VSS_AN51
VSS_AN48
VSS_AN45
VSS_AN42
VSS_AN41
VSS_AN40
VSS_AN36
VSS_AN35
VSS_AN34
VSS_AN31
VSS_AN28
VSS_AN25
VSS_AN22
VSS_AN18
VSS_AN15
VSS_AN13
VSS_AN11
VSS_AN8
VSS_AN6
VSS_AN4
VSS_AN1
VSS_AM73
VSS_AM68
VSS_AM66
VSS_AM61
VSS_AM59
VSS_AM53
VSS_AM52
VSS_AM51
VSS_AM50
VSS_AM49
VSS_AM48
VSS_AM47
VSS_AM46
VSS_AM45
VSS_AM44
VSS_AM43
VSS_AM42
33/40
VSS_BL24
VSS_BL22
VSS_BL20
VSS_BL18
VSS_BL15
VSS_BL13
VSS_BL11
VSS_BL8
VSS_BL6
VSS_BL4
VSS_BL1
VSS_BK73
VSS_BK71
VSS_BK68
VSS_BK66
VSS_BK64
VSS_BK61
VSS_BK59
VSS_BK57
VSS_BK54
VSS_BK52
VSS_BK50
VSS_BK48
VSS_BK27
VSS_BK25
VSS_BK23
VSS_BK19
VSS_BK17
VSS_BK15
VSS_BK12
VSS_BK10
VSS_BK8
VSS_BK5
VSS_BK3
VSS_BJ75
VSS_BJ70
VSS_BJ68
VSS_BJ63
VSS_BJ61
VSS_BJ56
VSS_BJ53
VSS_BJ51
VSS_BJ49
VSS_BJ28
VSS_BJ26
VSS_BJ24
VSS_BJ22
VSS_BJ20
VSS_BJ15
VSS_BJ13
VSS_BJ8
VSS_BJ6
VSS_BJ1
VSS_BH73
VSS_BH71
VSS_BH68
VSS_BH66
VSS_BH64
VSS_BH61
VSS_BH59
VSS_BH57
VSS_BH54
VSS_BH52
VSS_BH50
VSS_BH49
VSS_BH28
VSS_BH26
VSS_BH24
VSS_BH22
VSS_BH19
VSS_BH17
VSS_BH15
VSS_BH12
VSS_BH10
VSS_BH8
VSS_BH5
VSS_BH3
VSS_BG75
VSS_BG72
VSS_BG70
VSS_BG68
VSS_BG65
VSS_BG63
VSS_BG61
VSS_BG58
VSS_BG56
VSS_BG53
VSS_BG51
VSS_BG49
VSS_BG27
VSS_BG25
VSS_BG23
VSS_BG20
VSS_BG18
VSS_BG15
VSS_BG13
VSS_BG11
VSS_BG8
VSS_BG6
VSS_BG4
VSS_BG1
VSS_BF73
VSS_BF68
VSS_BF66
VSS_BF61
VSS_BF59
VSS_BF54
VSS_BF52
VSS_BF50
VSS_BF49
VSS_BF28
VSS_BF26
VSS_BF24
VSS_BF22
VSS_BF19
VSS_BF17
VSS_BF15
VSS_BF12
VSS_BF10
VSS_BF8
VSS_BF5
VSS_BF3
VSS_BD73
VSS_BD71
VSS_BD68
VSS_BD66
VSS_BD64
VSS_BD61
VSS_BD59
VSS_BD57
VSS_BD53
VSS_BD51
VSS_BD49
VSS_BD27
VSS_BD25
VSS_BD23
VSS_BD17
VSS_BD15
VSS_BD10
VSS_BD8
VSS_BD3
VSS_BC75
VSS_BC72
VSS_BC70
VSS_BC68
VSS_BC65
VSS_BC63
VSS_BC61
VSS_BC58
VSS_BC56
VSS_BC53
VSS_BC51
VSS_BC50
VSS_BC49
VSS_BC28
VSS_BC26
VSS_BC24
VSS_BC22
VSS_BC20
VSS_BC18
VSS_BC15
VSS_BC13
VSS_BC11
VSS_BC8
VSS_BC6
VSS_BC4
VSS_BC1
VSS_BB73
VSS_BB71
VSS_BB68
VSS_BB66
VSS_BB64
VSS_BB61
VSS_BB59
VSS_BB57
VSS_BB54
VSS_BB52
VSS_BB50
VSS_BB48
VSS_BB27
VSS_BB25
VSS_BB23
VSS_BB19
VSS_BB17
VSS_BB15
VSS_BB12
VSS_BB10
VSS_BB8
VSS_BB5
VSS_BB3
VSS_BA75
VSS_BA70
VSS_BA68
VSS_BA63
VSS_BA61
VSS_BA56
VSS_BA53
VSS_BA51
VSS_BA49
VSS_BA28
VSS_BA26
VSS_BA24
VSS_BA22
VSS_BA20
VSS_BA15
VSS_BA13
VSS_BA8
VSS_BA6
VSS_BA1
VSS_AY73
VSS_AY71
VSS_AY68
VSS_AY66
VSS_AY64
VSS_AY61
VSS_AY59
VSS_AY57
VSS_AY54
VSS_AY52
VSS_AY50
VSS_AY48
VSS_AY27
VSS_AY25
VSS_AY23
VSS_AY19
VSS_AY17
VSS_AY15
VSS_AY12
VSS_AY10
VSS_AY8
VSS_AY5
VSS_AY3
VSS_AW75
VSS_AW72
VSS_AW70
VSS_AW68
VSS_AW65
VSS_AW6329/40
VSS_R45
VSS_R42
VSS_R41
VSS_R40
VSS_R36
VSS_R35
VSS_R34
VSS_R31
VSS_R28
VSS_R25
VSS_R22
VSS_R20
VSS_R18
VSS_R15
VSS_R13
VSS_R11
VSS_R8
VSS_R6
VSS_R4
VSS_R1
VSS_P73
VSS_P66
VSS_P61
VSS_P59
VSS_P53
VSS_P52
VSS_P51
VSS_P50
VSS_P49
VSS_P48
VSS_P47
VSS_P46
VSS_P45
VSS_P44
VSS_P43
VSS_P42
VSS_P39
VSS_P37
VSS_P34
VSS_P33
VSS_P32
VSS_P31
VSS_P30
VSS_P29
VSS_P28
VSS_P27
VSS_P26
VSS_P24
VSS_P23
VSS_P17
VSS_P15
VSS_P10
VSS_P8
VSS_P3
VSS_N75
VSS_N72
VSS_N70
VSS_N68
VSS_N65
VSS_N63
VSS_N61
VSS_N58
VSS_N56
VSS_N54
VSS_N51
VSS_N48
VSS_N45
VSS_N42
VSS_N34
VSS_N31
VSS_N28
VSS_N25
VSS_N22
VSS_N20
VSS_N18
VSS_N15
VSS_N13
VSS_N11
VSS_N8
VSS_N6
VSS_N4
VSS_N1
VSS_M73
VSS_M71
VSS_M68
VSS_M66
VSS_M64
VSS_M61
VSS_M59
VSS_M57
VSS_M54
VSS_M51
VSS_M48
VSS_M45
VSS_M42
VSS_M39
VSS_M37
VSS_M34
VSS_M31
VSS_M28
VSS_M25
VSS_M22
VSS_M19
VSS_M17
VSS_M15
VSS_M12
VSS_M10
VSS_M8
VSS_M5
VSS_M3
VSS_L75
VSS_L70
VSS_L68
VSS_L63
VSS_L61
VSS_L56
VSS_L54
VSS_L51
VSS_L48
VSS_L45
VSS_L42
VSS_L41
VSS_L40
VSS_L36
VSS_L35
VSS_L34
VSS_L31
VSS_L28
VSS_L25
VSS_L22
VSS_L20
VSS_L15
VSS_L13
VSS_L8
VSS_L6
VSS_L1
VSS_K73
VSS_K71
VSS_K68
VSS_K66
VSS_K64
VSS_K61
VSS_K57
VSS_K53
VSS_K52
VSS_K51
VSS_K50
VSS_K49
VSS_K48
VSS_K47
VSS_K46
VSS_K45
VSS_K44
VSS_K43
VSS_K42
VSS_K39
VSS_K37
VSS_K34
VSS_K33
VSS_K32
VSS_K31
VSS_K30
VSS_K29
VSS_K28
VSS_K27
VSS_K26
VSS_K25
VSS_K24
VSS_K19
VSS_K17
VSS_K15
VSS_K12
VSS_K10
VSS_K8
VSS_K5
VSS_K3
VSS_J75
VSS_J72
VSS_J70
VSS_J68
VSS_J65
VSS_J63
VSS_J61
VSS_J58
VSS_J56
VSS_J54
VSS_J51
VSS_J48
VSS_J45
VSS_J42
VSS_J34
VSS_J31
VSS_J28
VSS_J25
VSS_J22
VSS_J20
VSS_J18
VSS_J15
VSS_T64
VSS_T61
VSS_T59
VSS_T57
VSS_T54
VSS_T51
VSS_T48
VSS_T45
VSS_T42
VSS_T39
VSS_T37
VSS_T34
VSS_T31
VSS_T28
VSS_T25
VSS_T22
VSS_T19
VSS_T17
VSS_T15
VSS_T12
VSS_T10
VSS_T8
VSS_T5
VSS_T3
VSS_R75
VSS_R72
VSS_R70
VSS_R68
VSS_R65
VSS_R63
VSS_R61
VSS_R58
VSS_R56
VSS_R54
VSS_R51
VSS_R48
30/40
VSS_AB66
VSS_AB64
VSS_AB61
VSS_AB59
VSS_AB57
VSS_AB54
VSS_AB51
VSS_AB48
VSS_AB45
VSS_AB42
VSS_AB39
VSS_AB37
VSS_AB34
VSS_AB31
VSS_AB28
VSS_AB25
VSS_AB22
VSS_AB19
VSS_AB17
VSS_AB15
VSS_AB12
VSS_AB10
VSS_AB8
VSS_AB5
VSS_AB3
VSS_AA75
VSS_AA70
VSS_AA68
VSS_AA65
VSS_AA63
VSS_AA61
VSS_AA58
VSS_AA56
VSS_AA45
VSS_AA41
VSS_AA40
VSS_AA36
VSS_AA35
VSS_AA34
VSS_AA31
VSS_AA20
VSS_AA18
VSS_AA15
VSS_AA13
VSS_AA11
VSS_AA8
VSS_AA6
VSS_AA4
VSS_AA1
VSS_Y73
VSS_Y68
VSS_Y66
VSS_Y61
VSS_Y59
VSS_Y54
VSS_Y53
VSS_Y52
VSS_Y51
VSS_Y50
VSS_Y49
VSS_Y48
VSS_Y45
VSS_Y44
VSS_Y43
VSS_Y42
VSS_Y39
VSS_Y37
VSS_Y34
VSS_Y33
VSS_Y32
VSS_Y31
VSS_Y28
VSS_Y27
VSS_Y26
VSS_Y25
VSS_Y24
VSS_Y23
VSS_Y22
VSS_Y17
VSS_Y15
VSS_Y10
VSS_Y8
VSS_Y3
VSS_W75
VSS_W72
VSS_W70
VSS_W68
VSS_W65
VSS_W63
VSS_W61
VSS_W58
VSS_W56
VSS_W54
VSS_W51
VSS_W48
VSS_W45
VSS_W42
VSS_W41
VSS_W40
VSS_W36
VSS_W35
VSS_W34
VSS_W28
VSS_W25
VSS_W22
VSS_W20
VSS_W18
VSS_W15
VSS_W13
VSS_W11
VSS_W8
VSS_W6
VSS_W4
VSS_W1
VSS_V73
VSS_V71
VSS_V66
VSS_V64
VSS_V61
VSS_V59
VSS_V57
VSS_V53
VSS_V52
VSS_V51
VSS_V50
VSS_V49
VSS_V48
VSS_V47
VSS_V46
VSS_V45
VSS_V44
VSS_V43
VSS_V42
VSS_V39
VSS_V37
VSS_V34
VSS_V33
VSS_V32
VSS_V31
VSS_V30
VSS_V29
VSS_V28
VSS_V26
VSS_V25
VSS_V24
VSS_V23
VSS_V19
VSS_V17
VSS_V15
VSS_V12
VSS_V10
VSS_V8
VSS_V5
VSS_V3
VSS_U75
VSS_U70
VSS_U68
VSS_U63
VSS_U61
VSS_U56
VSS_U54
VSS_U51
VSS_U48
VSS_U45
VSS_U42
VSS_U34
VSS_U31
VSS_U28
VSS_U25
VSS_U22
VSS_U20
VSS_U15
VSS_U13
VSS_U8
VSS_U6
VSS_U1
VSS_T73
VSS_T71
VSS_T68
VSS_T66
VSS_AD48
VSS_AD47
VSS_AD46
VSS_AD45
VSS_AD44
VSS_AD43
VSS_AD42
VSS_AD39
VSS_AD37
VSS_AD34
VSS_AD33
VSS_AD32
VSS_AD30
VSS_AD29
VSS_AD28
VSS_AD27
VSS_AD26
VSS_AD25
VSS_AD24
VSS_AD23
VSS_AD19
VSS_AD17
VSS_AD15
VSS_AD12
VSS_AD10
VSS_AD8
VSS_AD5
VSS_AD3
VSS_AC75
VSS_AC70
VSS_AC68
VSS_AC63
VSS_AC61
VSS_AC56
VSS_AC54
VSS_AC51
VSS_AC48
VSS_AC45
VSS_AC42
VSS_AC34
VSS_AC31
VSS_AC28
VSS_AC25
VSS_AC22
VSS_AC20
VSS_AC15
VSS_AC13
VSS_AC8
VSS_AC6
VSS_AC1
VSS_AB73
VSS_AB71
VSS_AB68
28/40
VSS_H34
VSS_H31
VSS_H28
VSS_H25
VSS_H22
VSS_H17
VSS_H15
VSS_H10
VSS_H8
VSS_H3
VSS_G75
VSS_G72
VSS_G70
VSS_G68
VSS_G65
VSS_G63
VSS_G61
VSS_G58
VSS_G56
VSS_G54
VSS_G51
VSS_G48
VSS_G45
VSS_G42
VSS_G34
VSS_G31
VSS_G28
VSS_G25
VSS_G22
VSS_G20
VSS_G18
VSS_G15
VSS_G13
VSS_G11
VSS_G8
VSS_G6
VSS_G4
VSS_G1
VSS_F73
VSS_F71
VSS_F68
VSS_F66
VSS_F64
VSS_F61
VSS_F59
VSS_F57
VSS_F53
VSS_F52
VSS_F50
VSS_F49
VSS_F47
VSS_F46
VSS_F44
VSS_F43
VSS_F41
VSS_F40
VSS_F39
VSS_F37
VSS_F36
VSS_F35
VSS_F33
VSS_F32
VSS_F30
VSS_F29
VSS_F27
VSS_F26
VSS_F24
VSS_F23
VSS_F19
VSS_F17
VSS_F15
VSS_F12
VSS_F10
VSS_F8
VSS_F5
VSS_F3
VSS_E75
VSS_E73
VSS_E72
VSS_E70
VSS_E69
VSS_E68
VSS_E66
VSS_E65
VSS_E63
VSS_E62
VSS_E61
VSS_E59
VSS_E58
VSS_E56
VSS_E55
VSS_E53
VSS_E52
VSS_E21
VSS_E20
VSS_E18
VSS_E17
VSS_E15
VSS_E14
VSS_E13
VSS_E10
VSS_E8
VSS_E7
VSS_E6
VSS_E3
VSS_E1
VSS_D74
VSS_D73
VSS_D71
VSS_D70
VSS_D67
VSS_D66
VSS_D64
VSS_D63
VSS_D61
VSS_D60
VSS_D59
VSS_D57
VSS_D54
VSS_D53
VSS_D52
VSS_D51
VSS_D50
VSS_D49
VSS_D48
VSS_D47
VSS_D46
VSS_D45
VSS_D44
VSS_D43
VSS_D42
VSS_D41
VSS_D40
VSS_D39
VSS_D37
VSS_D35
VSS_D31
VSS_D30
VSS_D29
VSS_D28
VSS_D27
VSS_D26
VSS_D25
VSS_D24
VSS_D21
VSS_D20
VSS_D19
VSS_D17
VSS_D16
VSS_D13
VSS_D12
VSS_D10
VSS_D9
VSS_D6
VSS_D5
VSS_D3
VSS_D2
VSS_C75
VSS_C73
VSS_C71
VSS_C69
VSS_C67
VSS_C64
VSS_C61
VSS_C57
VSS_C56
VSS_C55
VSS_C52
VSS_C49
VSS_C46
VSS_C43
VSS_C40
VSS_C36
VSS_C30
VSS_C27
VSS_C24
VSS_C21
VSS_C15
VSS_C13
VSS_C11
VSS_C10
VSS_C8
VSS_C5
VSS_C1
VSS_B70
VSS_B68
VSS_B65
VSS_B62
VSS_B59
VSS_B55
VSS_B52
VSS_B49
VSS_B46
VSS_B43
VSS_B39
VSS_B37
VSS_B33
VSS_B30
VSS_B27
VSS_B24
VSS_B18
VSS_B13
VSS_B11
VSS_B10
VSS_B8
VSS_B7
VSS_A73
VSS_A72
VSS_A67
VSS_A61
VSS_A53
VSS_A49
VSS_A47
VSS_A44
VSS_A43
VSS_A27
VSS_A21
VSS_A15
VSS_A9
VSS_A3
VSS_J13
VSS_J11
VSS_J8
VSS_J6
VSS_J4
VSS_J1
VSS_H73
VSS_H68
VSS_H66
VSS_H61
VSS_H59
VSS_H54
VSS_H51
VSS_H48
VSS_H45
VSS_H42
VSS_H39
VSS_H37
SHEETDATE
DEPARTMENT
SIZE
PROJECT DOCUMENT NUMBER REV
REVIEWER
DESIGNER
123
7 3 2 1 6 5 4
E
A
B
C
E
D
C
B
A
7 6 5 4
D
C



Thu Sep 14 16:12:02 2023<NAME_2><NAME_1>MB FABCGT AMDV0259 OF 365
SOCKET6096_13568-001SOCKET6096_13568-001SOCKET6096_13568-001SOCKET6096_13568-001IOIOIOIO
CPU1 VSS 2/3
SMLFSMLFSMLFSMLF
DA70
DA68
DA65
DA63
DA61
DA58
DA54
DA51
DA48
DA45
DA42
DA34
DA31
DA28
DA25
DA22
DA20
DA18
DA15
DA13
DA11
DA8
DA6
DA4
DA1
CY73
CY71
CY68
CY66
CY64
CY61
CY59
CY53
CY52
CY51
CY50
CY49
CY48
CY47
CY46
CY45
CY44
CY43
CY42
CY39
CY37
CY34
CY33
CY32
CY31
CY30
CY29
CY28
CY27
CY26
CY25
CY24
CY23
CY19
CY17
CY15
CY12
CY10
CY8
CY5
CY3
CW75
CW70
CW68
CW63
CW61
CW56
CW54
CW51
CW48
CW45
CW42
CW41
CW40
CW36
CW35
CW34
CW31
CW28
CW25
CW22
CW20
CW15
CW13
CW8
CW6
CW1
CV73
CV71
CV68
CV66
CV64
CV61
CV59
CV57
CV54
CV51
CV48
CV45
CV42
CV39
CV37
CV34
CV31
CV28
CV25
CV22
CV19
CV17
CV15
CV12
CV10
CV8
CV5
CV3
CU75
CU72
CU70
CU68
CU65
CU63
CU61
CU56
CU54
CU51
CU48
CU45
CU42
CU34
CU31
CU28
CU25
CU22
CU20
CU18
CU15
CU13
CU11
CU8
CU6
CU4
CU1
CT73
CT68
CT66
CT61
CT59
CT53
CT51
CT50
CT49
CT48
CT47
CT46
CT45
CT44
CT43
CT42
CT39
CT37
CT34
CT33
CT32
CT31
CT30
CT29
CT28
CT27
CT26
CT25
CT24
CT23
CT17
CT15
CT10
CT8
CT3
CR75
CR72
CR70
CR68
CR65
CR63
CR61
CR58
CR56
CR54
CR51
CR48
CR45
CR42
CR41
CR40
CR36
CR35
CR34
CR31
CR28
CR25
CR22
CR20
CR18
CR15
CR13
CR11
CR8
CR6
CR4
CR1
CP73
CP71
CP68
CP66
CP64
CP61
CP59
CP57
CP54
CP51
CP48
CP45
CP42
CP39
CP37
CP34
CP31
CP28
CP25
CP22
U26
CP19
CP17
CP15
CP12
CP10
CP8
CP5
CP3
CN75
CN70
CN68
CN63
CN61
CN56
CN51
CN48
CN45
CN42
CN34
CN31
CN28
CN25
CN22
CN20
CN15
CN13
CN8
CN6
CN1
CM73
CM71
CM68
CM66
CM64
CM61
CM59
CM57
CM53
CM52
CM51
CM49
CM48
CM47
CM46
CM45
CM44
CM43
CM42
CM39
CM37
CM34
CM33
CM32
CM31
CM30
CM29
CM28
CM27
CM26
CM25
CM24
CM23
CM19
CM17
CM15
CM12
CM10
CM8
CM5
CM3
CL75
CL72
CL70
CL68
CL65
CL63
CL61
CL58
CL56
CL54
CL51
CL48
CL45
CL42
CL41
CL40
CL36
CL35
CL34
CL31
CL28
CL25
CL22
CL20
CL18
CL15
CL13
CL11
CL8
CL6
CL4
CL1
CK73
CK68
CK66
CK61
CK59
CK54
CK53
CK52
CK51
CK50
CK49
CK48
CK45
CK44
CK43
CK42
CK39
CK37
CK34
CK33
CK32
CK28
CK27
CK26
CK25
CK24
CK23
CK22
CK17
CK15
CK8
CK3
CJ75
CJ72
CJ70
CJ68
CJ65
CJ63
CJ61
CJ58
CJ56
CJ45
CJ42
CJ41
CJ40
CJ36
CJ35
CJ34
CJ31
CJ23
CJ20
CJ18
CJ15
CJ13
CJ11
CJ8
CJ6
CJ4
CJ1
CH73
CH71
CH68
CH66
CH64
CH61
CH59
CH57
CH54
CH51
CH48
CH45
CH42
CH39
CH37
CH34
CH31
CH28
CH25
CH22
CH19
CH17
CH15
CH12
CH10
CH8
CH5
CH3
CG75
CG70
CG68
CG63
CG61
CG56
CG54
CG51
CG48
CG45
CG34
CG31
CG28
CG25
CG22
CG20
CG15
CG13
CG8
CG6
CG1
CF73
CF71
CF68
CF66
CF64
CF61
CF59
CF57
CF53
CF52
CF51
CF50
CF49
CF48
CF47
CF45
CF44
CF43
CF42
CF39
CF37
CF34
U26
CF33
CF32
CF31
CF30
CF29
CF28
CF27
CF26
CF25
CF24
CF23
CF19
CF17
CF15
CF12
CF10
CF8
CF5
CF3
CE75
CE72
CE70
CE68
CE65
CE63
CE61
CE58
CE56
CE54
CE51
CE48
CE45
CE42
CE41
CE40
CE36
CE35
CE34
CE31
CE28
CE25
CE22
CE20
CE18
CE15
CE13
CE11
CE8
CE6
CE4
CE1
CD73
CD68
CD66
CD61
CD59
CD54
CD51
CD48
CD45
CD42
CD39
CD37
CD34
CD31
CD28
CD25
CD22
CD17
CD15
CD10
CD8
CD3
CC75
CC72
CC70
CC68
CC65
CC63
CC61
CC58
CC56
CC54
CC51
CC48
CC45
CC42
CC34
CC31
CC28
CC25
CC20
CC18
CC15
CC13
CC11
CC8
CC6
CC4
CC1
CB73
CB71
CB68
CB66
CB64
CB61
CB59
CB57
CB53
CB52
CB51
CB50
CB49
CB48
CB47
CB46
CB45
CB43
CB42
CB39
CB37
CB34
CB33
CB32
CB31
CB30
CB29
CB28
CB27
CB26
CB25
CB24
CB23
CB19
CB17
CB15
CB12
CB10
CB8
CB5
CB3
CA75
CA70
CA68
CA63
CA61
CA56
CA54
CA51
CA48
CA45
CA42
CA41
CA40
CA36
CA35
CA34
CA31
CA28
CA25
CA22
CA20
CA15
CA13
CA8
CA6
CA1
BY73
BY71
BY68
BY66
BY64
BY61
BY59
BY57
BY54
BY51
BY48
BY45
BY42
BY39
BY37
BY34
BY31
BY28
BY25
BY22
BY19
BY17
BY15
BY12
BY10
BY8
BY5
BY3
BW75
BW72
BW70
BW68
BW65
BW63
BW61
BW58
BW56
BW54
BW51
BW48
BW45
BW42
BW34
BW31
BW28
BW22
BW20
BW18
BW15
BW13
BW11
BW8
BW6
BW4
BW1
BV73
BV68
BV66
BV61
BV59
BV53
BV52
BV51
BV50
BV49
BV48
BV47
BV46
U26
BV45
BV44
BV43
BV39
BV37
BV34
BV33
BV32
BV31
BV30
BV29
BV28
BV27
BV26
BV25
BV24
BV23
BV17
BV15
BV10
BV8
BV3
BU75
BU72
BU70
BU68
BU65
BU63
BU61
BU58
BU56
BU54
BU51
BU48
BU45
BU42
BU41
BU40
BU36
BU35
BU34
BU31
BU28
BU25
BU22
BU20
BU18
BU15
BU13
BU11
BU8
BU6
BU4
BU1
BT73
BT72
BT71
BT69
BT68
BT66
BT65
BT64
BT62
BT61
BT59
BT58
BT57
BT55
BT54
BT51
BT48
BT45
BT42
BT39
BT37
BT34
BT31
BT28
BT25
BT22
BT21
BT19
BT18
BT17
BT15
BT14
BT12
BT11
BT10
BT8
BT7
BT5
BT4
BT3
BR75
BR73
BR70
BR69
BR68
BR66
BR63
BR62
BR61
BR59
BR56
BR55
BR51
BR49
BR47
BR45
BR43
BR41
BR36
BR34
BR32
BR30
BR28
BR26
BR24
BR22
BR21
BR20
BR17
BR15
BR14
BR13
BR10
BR8
BR7
BR6
BR3
BR1
BP73
BP71
BP68
BP66
BP64
BP61
BP59
BP57
BP54
BP52
BP50
BP48
BP46
BP44
BP42
BP40
BP37
BP35
BP33
BP31
BP29
BP27
BP25
BP23
BP19
BP17
BP15
BP12
BP10
BP8
BP5
BP3
BN75
BN72
BN70
BN68
BN65
BN63
BN61
BN58
BN56
BN53
BN51
BN49
BN47
BN45
BN43
BN41
BN36
BN34
BN32
BN30
BN28
BN26
BN24
BN22
BN20
BN18
BN15
BN13
BN11
BN8
BN6
BN4
BN1
BM73
BM68
BM66
BM61
BM59
BM54
BM52
BM50
BM48
BM46
BM44
BM42
BM40
BM37
BM35
BM33
BM31
BM29
BM27
BM25
BM23
BM17
BM15
BM10
BM8
BM3
BL75
BL72
BL70
BL68
BL65
BL63
BL61
BL58
BL56
BL53
BL51
BL49
BL28
BL26
U26
39/40
VSS_DA70
VSS_DA68
VSS_DA65
VSS_DA63
VSS_DA61
VSS_DA58
VSS_DA42
VSS_DA34
VSS_DA31
VSS_DA28
VSS_DA25
VSS_DA22
VSS_DA11
VSS_DA8
VSS_DA6
VSS_DA4
VSS_DA1
VSS_CY73
VSS_CY71
VSS_CY61
VSS_CY59
VSS_CY53
VSS_CY52
VSS_CY51
VSS_CY50
VSS_CY49
VSS_CY46
VSS_CY45
VSS_CY44
VSS_CY43
VSS_CY42
VSS_CY39
VSS_CY37
VSS_CY34
VSS_CY33
VSS_CY31
VSS_CY30
VSS_CY29
VSS_CY28
VSS_CY27
VSS_CY26
VSS_CY25
VSS_CY24
VSS_CY23
VSS_CY19
VSS_CY17
VSS_CY15
VSS_CY12
VSS_CY10
VSS_CY8
VSS_CY5
VSS_CY3
VSS_CW75
VSS_CW70
VSS_CW68
VSS_CW63
VSS_CW61
VSS_CW56
VSS_CW54
VSS_CW51
VSS_CW48
VSS_CW45
VSS_CW42
VSS_CW41
VSS_CW40
VSS_CW36
VSS_CW35
VSS_CW20
VSS_CW15
VSS_CW13
VSS_CW8
VSS_CW6
VSS_CW1
VSS_CV61
VSS_CV59
VSS_CV57
VSS_CV54
VSS_CV51
VSS_CV48
VSS_CV31
VSS_CV28
VSS_CV25
VSS_CV22
VSS_CV19
VSS_CV17
VSS_CV3
VSS_CU75
VSS_CU72
VSS_CU70
VSS_CU68
VSS_CU65
VSS_CU54
VSS_CU51
VSS_CU48
VSS_CU45
VSS_CU42
VSS_CU34
VSS_CU31
VSS_CU20
VSS_CU18
VSS_CU15
VSS_CU13
VSS_CU11
VSS_CU8
VSS_CU6
VSS_CU4
VSS_CT68
VSS_CT66
VSS_CT61
VSS_CT59
VSS_CT53
VSS_CT51
VSS_CT50
VSS_CT49
VSS_CT47
VSS_CT46
VSS_CT45
VSS_CT44
VSS_CT43
VSS_CT42
VSS_CT39
VSS_CT37
VSS_CT34
VSS_CT33
VSS_CT32
VSS_CT31
VSS_CT30
VSS_CT29
VSS_CT28
VSS_CT27
VSS_CT26
VSS_CT25
VSS_CT24
VSS_CT23
VSS_CT17
VSS_CR72
VSS_CR70
VSS_CR68
VSS_CR65
VSS_CR63
VSS_CR61
VSS_CR45
VSS_CR42
VSS_CR41
VSS_CR40
VSS_CR36
VSS_CR35
VSS_CR20
VSS_CR18
VSS_CR15
VSS_CR13
VSS_CR11
VSS_CR8
VSS_CP68
VSS_CP66
VSS_CP64
VSS_CP61
VSS_CP59
VSS_CP57
VSS_CP39
VSS_CP37
VSS_CP34
VSS_CP31
VSS_CP28
VSS_CP25
VSS_DA54
VSS_DA51
VSS_DA48
VSS_DA45
VSS_DA20
VSS_DA18
VSS_DA15
VSS_DA13
VSS_CY68
VSS_CY66
VSS_CY64
VSS_CY48
VSS_CY47
VSS_CY32
VSS_CW34
VSS_CW31
VSS_CW28
VSS_CW25
VSS_CW22
VSS_CV73
VSS_CV71
VSS_CV68
VSS_CV66
VSS_CV64
VSS_CV45
VSS_CV42
VSS_CV39
VSS_CV37
VSS_CV34
VSS_CV15
VSS_CV12
VSS_CV10
VSS_CV8
VSS_CV5
VSS_CU63
VSS_CU61
VSS_CU56
VSS_CU28
VSS_CU25
VSS_CU22
VSS_CU1
VSS_CT73
VSS_CT48
VSS_CT15
VSS_CT10
VSS_CT8
VSS_CT3
VSS_CR75
VSS_CR58
VSS_CR56
VSS_CR54
VSS_CR51
VSS_CR48
VSS_CR34
VSS_CR31
VSS_CR28
VSS_CR25
VSS_CR22
VSS_CR6
VSS_CR4
VSS_CR1
VSS_CP73
VSS_CP71
VSS_CP54
VSS_CP51
VSS_CP48
VSS_CP45
VSS_CP42
VSS_CP22
38/40
VSS_CP19
VSS_CP17
VSS_CP15
VSS_CP12
VSS_CP10
VSS_CP8
VSS_CP5
VSS_CP3
VSS_CN75
VSS_CN70
VSS_CN68
VSS_CN63
VSS_CN61
VSS_CN51
VSS_CN48
VSS_CN45
VSS_CN42
VSS_CN34
VSS_CN31
VSS_CN28
VSS_CN25
VSS_CN15
VSS_CN13
VSS_CN8
VSS_CN6
VSS_CN1
VSS_CM73
VSS_CM71
VSS_CM68
VSS_CM59
VSS_CM57
VSS_CM53
VSS_CM52
VSS_CM51
VSS_CM49
VSS_CM48
VSS_CM47
VSS_CM46
VSS_CM45
VSS_CM44
VSS_CM33
VSS_CM32
VSS_CM31
VSS_CM30
VSS_CM29
VSS_CM28
VSS_CM23
VSS_CM19
VSS_CM17
VSS_CM15
VSS_CM12
VSS_CM10
VSS_CM8
VSS_CL72
VSS_CL70
VSS_CL68
VSS_CL65
VSS_CL63
VSS_CL61
VSS_CL58
VSS_CL56
VSS_CL48
VSS_CL45
VSS_CL42
VSS_CL41
VSS_CL40
VSS_CL36
VSS_CL35
VSS_CL34
VSS_CL31
VSS_CL25
VSS_CL22
VSS_CL20
VSS_CL18
VSS_CL15
VSS_CL13
VSS_CL11
VSS_CL8
VSS_CL6
VSS_CL4
VSS_CL1
VSS_CK73
VSS_CK68
VSS_CK66
VSS_CK61
VSS_CK59
VSS_CK54
VSS_CK53
VSS_CK52
VSS_CK51
VSS_CK50
VSS_CK49
VSS_CK48
VSS_CK45
VSS_CK44
VSS_CK43
VSS_CK42
VSS_CK39
VSS_CK37
VSS_CK34
VSS_CK32
VSS_CK28
VSS_CK27
VSS_CK26
VSS_CK25
VSS_CK24
VSS_CK23
VSS_CK22
VSS_CK8
VSS_CK3
VSS_CJ75
VSS_CJ72
VSS_CJ70
VSS_CJ68
VSS_CJ65
VSS_CJ56
VSS_CJ45
VSS_CJ42
VSS_CJ41
VSS_CJ40
VSS_CJ36
VSS_CJ35
VSS_CJ18
VSS_CJ15
VSS_CJ13
VSS_CJ11
VSS_CJ8
VSS_CJ6
VSS_CH66
VSS_CH64
VSS_CH61
VSS_CH59
VSS_CH57
VSS_CH54
VSS_CH37
VSS_CH34
VSS_CH31
VSS_CH28
VSS_CH25
VSS_CH22
VSS_CH8
VSS_CH5
VSS_CH3
VSS_CG75
VSS_CG70
VSS_CG68
VSS_CG63
VSS_CG61
VSS_CG56
VSS_CG54
VSS_CG51
VSS_CG48
VSS_CG45
VSS_CG34
VSS_CG31
VSS_CG28
VSS_CG25
VSS_CG22
VSS_CG20
VSS_CG15
VSS_CG13
VSS_CG8
VSS_CG6
VSS_CG1
VSS_CF73
VSS_CF71
VSS_CF68
VSS_CF66
VSS_CF64
VSS_CF61
VSS_CF59
VSS_CF57
VSS_CF53
VSS_CF52
VSS_CF51
VSS_CF50
VSS_CF49
VSS_CF48
VSS_CF47
VSS_CF45
VSS_CF44
VSS_CF43
VSS_CF42
VSS_CF39
VSS_CF37
VSS_CF34
VSS_CH19
VSS_CH51
VSS_CJ4
VSS_CL28
VSS_CL54
VSS_CM5
VSS_CM27
VSS_CM43
VSS_CH17
VSS_CH48
VSS_CJ1
VSS_CJ34
VSS_CL51
VSS_CM3
VSS_CM26
VSS_CM42
VSS_CH15
VSS_CH45
VSS_CH73
VSS_CJ31
VSS_CJ63
VSS_CL75
VSS_CM25
VSS_CM39
VSS_CM66
VSS_CH12
VSS_CH42
VSS_CH71
VSS_CJ23
VSS_CJ61
VSS_CK17
VSS_CM24
VSS_CM37
VSS_CM64
VSS_CN22
VSS_CH10
VSS_CH39
VSS_CH68
VSS_CJ20
VSS_CJ58
VSS_CK15
VSS_CK33
VSS_CM34
VSS_CM61
VSS_CN20
VSS_CN56
37/40
VSS_CF33
VSS_CF32
VSS_CF31
VSS_CF30
VSS_CF29
VSS_CF28
VSS_CF27
VSS_CF26
VSS_CF25
VSS_CF24
VSS_CF23
VSS_CF19
VSS_CF17
VSS_CF15
VSS_CF12
VSS_CF10
VSS_CF8
VSS_CF5
VSS_CF3
VSS_CE75
VSS_CE72
VSS_CE70
VSS_CE68
VSS_CE65
VSS_CE63
VSS_CE61
VSS_CE58
VSS_CE56
VSS_CE54
VSS_CE51
VSS_CE48
VSS_CE45
VSS_CE42
VSS_CE41
VSS_CE40
VSS_CE36
VSS_CE35
VSS_CE34
VSS_CE31
VSS_CE28
VSS_CE25
VSS_CE22
VSS_CE20
VSS_CE18
VSS_CE15
VSS_CE13
VSS_CE11
VSS_CE8
VSS_CE6
VSS_CE4
VSS_CE1
VSS_CD73
VSS_CD68
VSS_CD66
VSS_CD61
VSS_CD59
VSS_CD54
VSS_CD51
VSS_CD48
VSS_CD45
VSS_CD42
VSS_CD39
VSS_CD37
VSS_CD34
VSS_CD31
VSS_CD28
VSS_CD25
VSS_CD22
VSS_CD17
VSS_CD15
VSS_CD10
VSS_CD8
VSS_CD3
VSS_CC75
VSS_CC72
VSS_CC70
VSS_CC68
VSS_CC65
VSS_CC63
VSS_CC61
VSS_CC58
VSS_CC56
VSS_CC54
VSS_CC51
VSS_CC48
VSS_CC45
VSS_CC42
VSS_CC34
VSS_CC31
VSS_CC28
VSS_CC25
VSS_CC20
VSS_CC18
VSS_CC15
VSS_CC13
VSS_CC11
VSS_CC8
VSS_CC6
VSS_CC4
VSS_CC1
VSS_CB73
VSS_CB71
VSS_CB68
VSS_CB66
VSS_CB64
VSS_CB61
VSS_CB59
VSS_CB57
VSS_CB53
VSS_CB52
VSS_CB51
VSS_CB50
VSS_CB49
VSS_CB48
VSS_CB47
VSS_CB46
VSS_CB45
VSS_CB43
VSS_CB42
VSS_CB39
VSS_CB37
VSS_CB34
VSS_CB33
VSS_CB32
VSS_CB31
VSS_CB30
VSS_CB29
VSS_CB28
VSS_CB27
VSS_CB26
VSS_CB25
VSS_CB24
VSS_CB23
VSS_CB19
VSS_CB17
VSS_CB15
VSS_CB12
VSS_CB10
VSS_CB8
VSS_CB5
VSS_CB3
VSS_CA75
VSS_CA70
VSS_CA68
VSS_CA63
VSS_CA61
VSS_CA56
VSS_CA54
VSS_CA51
VSS_CA48
VSS_CA45
VSS_CA42
VSS_CA41
VSS_CA40
VSS_CA36
VSS_CA35
VSS_CA34
VSS_CA31
VSS_CA28
VSS_CA25
VSS_CA22
VSS_CA20
VSS_CA15
VSS_CA13
VSS_CA8
VSS_CA6
VSS_CA1
VSS_BY73
VSS_BY71
VSS_BY68
VSS_BY66
VSS_BY64
VSS_BY61
VSS_BY59
VSS_BY57
VSS_BY54
VSS_BY51
VSS_BY48
VSS_BY45
VSS_BY42
VSS_BY39
VSS_BY37
VSS_BY34
VSS_BY31
VSS_BY28
VSS_BY25
VSS_BY22
VSS_BY19
VSS_BY17
VSS_BY15
VSS_BY12
VSS_BY10
VSS_BY8
VSS_BY5
VSS_BY3
VSS_BW75
VSS_BW72
VSS_BW70
VSS_BW68
VSS_BW65
VSS_BW63
VSS_BW61
VSS_BW58
VSS_BW56
VSS_BW54
VSS_BW51
VSS_BW48
VSS_BW45
VSS_BW42
VSS_BW34
VSS_BW31
VSS_BW28
VSS_BW22
VSS_BW20
VSS_BW18
VSS_BW15
VSS_BW13
VSS_BW11
VSS_BW8
VSS_BW6
VSS_BW4
VSS_BW1
VSS_BV73
VSS_BV68
VSS_BV66
VSS_BV61
VSS_BV59
VSS_BV53
VSS_BV52
VSS_BV51
VSS_BV50
VSS_BV49
VSS_BV48
VSS_BV47
VSS_BV46
34/40
VSS_BV45
VSS_BV44
VSS_BV43
VSS_BV39
VSS_BV34
VSS_BV33
VSS_BV32
VSS_BV31
VSS_BV30
VSS_BV29
VSS_BV28
VSS_BV27
VSS_BV26
VSS_BV25
VSS_BV24
VSS_BV23
VSS_BV17
VSS_BV15
VSS_BV10
VSS_BV8
VSS_BV3
VSS_BU75
VSS_BU72
VSS_BU70
VSS_BU68
VSS_BU65
VSS_BU63
VSS_BU61
VSS_BU58
VSS_BU56
VSS_BU54
VSS_BU51
VSS_BU48
VSS_BU45
VSS_BU42
VSS_BU41
VSS_BU40
VSS_BU36
VSS_BU35
VSS_BU34
VSS_BU31
VSS_BU28
VSS_BU25
VSS_BU22
VSS_BU20
VSS_BU18
VSS_BU15
VSS_BU13
VSS_BU11
VSS_BU8
VSS_BU6
VSS_BU4
VSS_BU1
VSS_BT73
VSS_BT72
VSS_BT71
VSS_BT69
VSS_BT68
VSS_BT66
VSS_BT65
VSS_BT64
VSS_BT62
VSS_BT61
VSS_BT59
VSS_BT58
VSS_BT57
VSS_BT55
VSS_BT54
VSS_BT51
VSS_BT48
VSS_BT45
VSS_BT42
VSS_BT39
VSS_BT37
VSS_BT34
VSS_BT31
VSS_BT28
VSS_BT25
VSS_BT22
VSS_BT21
VSS_BT19
VSS_BT18
VSS_BT17
VSS_BT15
VSS_BT14
VSS_BT12
VSS_BT11
VSS_BT10
VSS_BT8
VSS_BT7
VSS_BT5
VSS_BT4
VSS_BT3
VSS_BR75
VSS_BR73
VSS_BR70
VSS_BR69
VSS_BR68
VSS_BR66
VSS_BR63
VSS_BR62
VSS_BR61
VSS_BR59
VSS_BR56
VSS_BR55
VSS_BR51
VSS_BR49
VSS_BR47
VSS_BR45
VSS_BR43
VSS_BR41
VSS_BR36
VSS_BR34
VSS_BR32
VSS_BR30
VSS_BR28
VSS_BR26
VSS_BR24
VSS_BR22
VSS_BR21
VSS_BR20
VSS_BR17
VSS_BR15
VSS_BR14
VSS_BR13
VSS_BR10
VSS_BR8
VSS_BR7
VSS_BR6
VSS_BR3
VSS_BR1
VSS_BP73
VSS_BP71
VSS_BP68
VSS_BP66
VSS_BP64
VSS_BP61
VSS_BP59
VSS_BP57
VSS_BP54
VSS_BP52
VSS_BP50
VSS_BP48
VSS_BP46
VSS_BP44
VSS_BP42
VSS_BP40
VSS_BP37
VSS_BP35
VSS_BP33
VSS_BP31
VSS_BP29
VSS_BP27
VSS_BP25
VSS_BP23
VSS_BP19
VSS_BP17
VSS_BP15
VSS_BP12
VSS_BP10
VSS_BP8
VSS_BP5
VSS_BP3
VSS_BN75
VSS_BN72
VSS_BN70
VSS_BN68
VSS_BN65
VSS_BN63
VSS_BN61
VSS_BN58
VSS_BN56
VSS_BN53
VSS_BN51
VSS_BN49
VSS_BN47
VSS_BN45
VSS_BN43
VSS_BN41
VSS_BN36
VSS_BN34
VSS_BN32
VSS_BN30
VSS_BN28
VSS_BN26
VSS_BN24
VSS_BN22
VSS_BN20
VSS_BN18
VSS_BN15
VSS_BN13
VSS_BN11
VSS_BN8
VSS_BN6
VSS_BN4
VSS_BN1
VSS_BM73
VSS_BM68
VSS_BM66
VSS_BM61
VSS_BM59
VSS_BM54
VSS_BM52
VSS_BM50
VSS_BM48
VSS_BM46
VSS_BM44
VSS_BM42
VSS_BM40
VSS_BM37
VSS_BM35
VSS_BM33
VSS_BM31
VSS_BM29
VSS_BM27
VSS_BM25
VSS_BM23
VSS_BM17
VSS_BM15
VSS_BM10
VSS_BM8
VSS_BM3
VSS_BL75
VSS_BL72
VSS_BL70
VSS_BL68
VSS_BL65
VSS_BL63
VSS_BL61
VSS_BL58
VSS_BL56
VSS_BL53
VSS_BL51
VSS_BL49
VSS_BL28
VSS_BL26
VSS_BV37
SHEETDATE
DEPARTMENT
SIZE
PROJECT DOCUMENT NUMBER REV
REVIEWER
DESIGNER
123
7 3 2 1 6 5 4
E
A
B
C
E
D
C
B
A
7 6 5 4
D
C



Thu Sep 14 16:12:02 2023<NAME_2><NAME_1>MB FABCGT AMDV0260 OF 365
SOCKET6096_13568-001IO
CPU1 VSS 3/3SMLF
V68V27P68P25K59K23DJ73DJ68DJ66DJ63DJ61DJ59DJ49DJ43DJ19DJ15DJ7DH70DH68DH66DH64DH63DH61DH59DH55DH52DH49DH46DH43DH39DH37DH18DH11DH5DG75DG74DG70DG69DG68DG67DG66DG65DG63DG62DG61DG60DG59DG56DG55DG52DG49DG46DG43DG41DG33DG30DG27DG24DG21DG20DG18DG16DG15DG14DG13DG9DG8DG7DG6DG2DG1DF73DF72DF71DF70DF68DF66DF65DF64DF63DF61DF59DF58DF57DF56DF54DF53DF52DF51DF50DF49DF48DF47DF46DF45DF44DF43DF42DF39DF37DF35DF32DF29DF26DF23DF22DF20
DF19DF18DF17DF15DF13DF12DF11DF10DF8DF6DF5DF4DF3DE75DE70DE68DE63DE61DE56DE33DE29DE26DE23DE20DE15DE13DE8DE6DE1DD73DD71DD68DD66DD64DD61DD59DD57DD53DD52DD50DD49DD47DD46DD44DD43DD41DD40DD39DD37DD36DD35DD33DD32DD30DD29DD27DD26DD24DD23DD19DD17DD15DD12DD10DD8DD5DD3DC75DC72DC70DC68DC65DC63DC61DC58DC56DC54DC51DC48DC45DC42DC34DC31DC28DC25DC22DC20DC18DC15DC13DC11DC8DC6DC4DC1DB73DB68DB66DB61DB59DB54DB51DB48DB45DB42DB39DB37DB34DB31DB28DB25DB22DB17DB15DB10DB8DB3DA75DA72
DA56CY57CU58CT52CN54CM50CK31CK10CG42CF46CC22CB44BW25BV42AN20AM37AJ13AH33AE4AD31AA72AA42
U2640/40
VSS_V68VSS_BV42VSS_CT52VSS_CM50VSS_K59VSS_DA56VSS_CG42VSS_AE4VSS_AH33VSS_BW25VSS_CU58VSS_P25VSS_P68VSS_AN20VSS_CC22VSS_CF46VSS_V27VSS_AA42VSS_AD31VSS_AJ13VSS_AA72VSS_CK10VSS_CN54VSS_K23VSS_AM37VSS_CB44VSS_CK31VSS_CY57VSS_DJ73VSS_DJ68VSS_DJ66VSS_DJ63VSS_DJ61VSS_DJ59VSS_DJ49VSS_DJ43VSS_DJ19VSS_DJ15VSS_DJ7VSS_DH70VSS_DH68VSS_DH59VSS_DH55VSS_DH52VSS_DH49VSS_DH46VSS_DH43VSS_DH39VSS_DG75VSS_DG74VSS_DG70VSS_DG69VSS_DG68VSS_DG67VSS_DG66VSS_DG60VSS_DG59VSS_DG56VSS_DG55VSS_DG52VSS_DG49VSS_DG46VSS_DG27VSS_DG24VSS_DG21VSS_DG20VSS_DG18VSS_DG16VSS_DG15VSS_DG7VSS_DG6VSS_DG2VSS_DG1VSS_DF73VSS_DF72VSS_DF71VSS_DF65VSS_DF64VSS_DF63VSS_DF61VSS_DF59VSS_DF58VSS_DF57VSS_DF56VSS_DF52VSS_DF51VSS_DF50VSS_DF49VSS_DF48VSS_DF47VSS_DF46VSS_DF45VSS_DF44VSS_DF42VSS_DF39VSS_DF37VSS_DF35VSS_DF32VSS_DF29VSS_DF26VSS_DF23VSS_DF22VSS_DF20
VSS_DF13VSS_DF12VSS_DF11VSS_DF10VSS_DF8VSS_DF6VSS_DF5VSS_DE68VSS_DE63VSS_DE61VSS_DE56VSS_DE33VSS_DE29VSS_DE26VSS_DE8VSS_DE6VSS_DE1VSS_DD73VSS_DD71VSS_DD68VSS_DD66VSS_DD53VSS_DD52VSS_DD50VSS_DD49VSS_DD47VSS_DD46VSS_DD44VSS_DD37VSS_DD36VSS_DD35VSS_DD33VSS_DD32VSS_DD30VSS_DD29VSS_DD19VSS_DD17VSS_DD15VSS_DD12VSS_DD10VSS_DD8VSS_DD5VSS_DC68VSS_DC65VSS_DC63VSS_DC61VSS_DC58VSS_DC56VSS_DC54VSS_DC42VSS_DC34VSS_DC31VSS_DC28VSS_DC25VSS_DC22VSS_DC20VSS_DC18VSS_DC11VSS_DC8VSS_DC6VSS_DC4VSS_DC1VSS_DB73VSS_DB68VSS_DB66VSS_DB61VSS_DB45VSS_DB42VSS_DB39VSS_DB37VSS_DB34VSS_DB31VSS_DB28VSS_DB10VSS_DB8VSS_DB3VSS_DA75VSS_DA72
VSS_DH66VSS_DH64VSS_DH63VSS_DH61VSS_DH37VSS_DH18VSS_DH11VSS_DH5VSS_DG65VSS_DG63VSS_DG62VSS_DG61VSS_DG43VSS_DG41VSS_DG33VSS_DG30VSS_DG14VSS_DG13VSS_DG9VSS_DG8VSS_DF70VSS_DF68VSS_DF66VSS_DF54VSS_DF53VSS_DF43
VSS_DF19VSS_DF18VSS_DF17VSS_DF15VSS_DF4VSS_DF3VSS_DE75VSS_DE70VSS_DE23VSS_DE20VSS_DE15VSS_DE13VSS_DD64VSS_DD61VSS_DD59VSS_DD57VSS_DD43VSS_DD41VSS_DD40VSS_DD39VSS_DD27VSS_DD26VSS_DD24VSS_DD23VSS_DD3VSS_DC75VSS_DC72VSS_DC70VSS_DC51VSS_DC48VSS_DC45VSS_DC15VSS_DC13VSS_DB59VSS_DB54VSS_DB51VSS_DB48VSS_DB25VSS_DB22VSS_DB17VSS_DB15
SHEETDATE
DEPARTMENT
SIZE
PROJECT DOCUMENT NUMBER REV
REVIEWER
DESIGNER
123
7 3 2 1 6 5 4
E
A
B
C
E
D
C
B
A
7 6 5 4
D
C



Thu Aug 24 10:13:55 2023<NAME_2><NAME_1>MB FABCGT AMDV0261 OF 365CPU1 GLUE LOGIC
SHEETDATE
DEPARTMENT
SIZE
PROJECT DOCUMENT NUMBER REV
REVIEWER
DESIGNER
123
7 3 2 1 6 5 4
E
A
B
C
E
D
C
B
A
7 6 5 4
D
C



Thu Aug 24 10:13:55 2023<NAME_2><NAME_1>MB FABCGT AMDV0262 OF 365Blank
SHEETDATE
DEPARTMENT
SIZE
PROJECT DOCUMENT NUMBER REV
REVIEWER
DESIGNER
123
7 3 2 1 6 5 4
E
A
B
C
E
D
C
B
A
7 6 5 4
D
C



CPU0 PCIE P0 TXCPU0 PCIE P1 TX63 OF 365V02GT AMDMB FABCThu Sep 14 16:12:28 2023<NAME_2><NAME_1>
P5E_CPU0_P1_TX_DN<15:8>P5E_CPU0_P0_TX_C_DN<15:8>DIFF BUS_0.22UFDIFF BUS_0.22UFDIFF BUS_0.22UF2842842842842424242424242427327327327324DIFF BUS_0.22UFDIFF BUS_0.22UFDIFF BUS_0.22UFDIFF BUS_0.22UFDIFF BUS_0.22UFDIFF BUS_0.22UFDIFF BUS_0.22UFDIFF BUS_0.22UFDIFF BUS_0.22UFDIFF BUS_0.22UFDIFF BUS_0.22UFDIFF BUS_0.22UFDIFF BUS_0.22UFDIFF BUS_0.22UFDIFF BUS_0.22UFDIFF BUS_0.22UFDIFF BUS_0.22UFDIFF BUS_0.22UFDIFF BUS_0.22UFDIFF BUS_0.22UFDIFF BUS_0.22UFDIFF BUS_0.22UFDIFF BUS_0.22UFDIFF BUS_0.22UFDIFF BUS_0.22UFDIFF BUS_0.22UFDIFF BUS_0.22UFDIFF BUS_0.22UFDIFF BUS_0.22UFC0201 6.3V20%X6S
DIFF BUS_0.22UFDIFF BUS_0.22UFDIFF BUS_0.22UFDIFF BUS_0.22UFDIFF BUS_0.22UFDIFF BUS_0.22UFDIFF BUS_0.22UFDIFF BUS_0.22UFDIFF BUS_0.22UFDIFF BUS_0.22UFDIFF BUS_0.22UFDIFF BUS_0.22UFDIFF BUS_0.22UFDIFF BUS_0.22UFDIFF BUS_0.22UFDIFF BUS_0.22UFDIFF BUS_0.22UFDIFF BUS_0.22UFDIFF BUS_0.22UFDIFF BUS_0.22UFDIFF BUS_0.22UFDIFF BUS_0.22UFDIFF BUS_0.22UFDIFF BUS_0.22UFDIFF BUS_0.22UFDIFF BUS_0.22UFDIFF BUS_0.22UFDIFF BUS_0.22UFC0201 6.3VX6SDIFF BUS_0.22UF20%DIFF BUS_0.22UFDIFF BUS_0.22UFDIFF BUS_0.22UFP5E_CPU0_P1_TX_C_DP<7:0>P5E_CPU0_P1_TX_C_DN<7:0>P5E_CPU0_P1_TX_C_DN<15:8>P5E_CPU0_P1_TX_C_DP<15:8>P5E_CPU0_P1_TX_DP<15:8>P5E_CPU0_P1_TX_DP<7:0>P5E_CPU0_P1_TX_DN<7:0>P5E_CPU0_P0_TX_DP<15:8>P5E_CPU0_P0_TX_DN<15:8>P5E_CPU0_P0_TX_DN<7:0>P5E_CPU0_P0_TX_C_DP<7:0>P5E_CPU0_P0_TX_C_DN<7:0>P5E_CPU0_P0_TX_C_DP<15:8>P5E_CPU0_P0_TX_DP<7:0>
PCIE AC-COUPLE CAPS 1/5
2 1
2 1
2 1
2 1
2 1
2 1
2 1
2 1
2 1
2 1
2 1
2 1
2 1
2 1
2 1
2 1
2 1
2 1
2 1
2 1
2 1
2 1
2 1
2 1
2 1
2 1
2 1
2 1
2 1
2 1
2 1
2 1
2 1
2 1
2 1
2 1
2 1
2 1
2 1
2 1
2 1
2 1
2 1
2 1
2 1
2 1
2 1
2 1
2 1
2 1
2 1
2 1
2 1
2 1
2 1
2 1
2 1
2 1
2 1
2 1
2 1
2 1
2 1
2 1
15
14
14
12
15
13
11
10
14
15
14
10
11
15
1010
9
10
10
11
12
15
9
14
8
0
2
5
8
0
1
2
0
1
0
1
2
3
4
2
3
6
4
5
6
7
7
8
9
8
11
12
10
13
15
13
14 14
11
13
12
9
7
5
6
3
4
2
1
0
1
3
4
5
6
7
11
12
13
14
15
1
3
2
6
5
4
7
0
1
3
5
4
6
7
9
8
12
11
13
15
8
9
10
11
12
13
1
2
3
0
2
3
4
5
4
6
7
5
6
7
8
9
8
9
12
13
0
C955
C956
C957
C934
C935
C936
C937
C938
C939
C940
C941
C942
C943
C944
C945
C946
C947
C948
C949
C950
C951
C952
C953
C954
C958
C959
C960
C961
C962
C963
C964
C965
C902
C903
C904
C905
C907
C906
C908
C909
C910
C911
C912
C913
C914
C915
C917
C916
C919
C918
C920
C921
C922
C923
C924
C925
C926
C927
C929
C928
C930
C931
C933
C932
2 1
2 12 1
2 12 1
2 12 1
2 12 1
2 12 1
2 12 1
2 12 1
2 12 1
2 12 1
2 12 1
2 12 1
2 1
2 12 1
2 12 1
2 12 1
2 12 1
2 12 1
2 12 1
2 12 1
2 12 1
2 12 1
2 12 1
2 12 1
2 12 1
2 12 1
2 12 1
2 12 1
2 12 1
2 12 1
2 12 1
2 12 1
2 12 1
SHEETDATE
DEPARTMENT
SIZE
PROJECT DOCUMENT NUMBER REV
REVIEWER
DESIGNER
123
7 3 2 1 6 5 4
E
A
B
C
E
D
C
B
A
7 6 5 4
D
ININOUTOUT
ININ OUTOUT
IN OUT OUT
ININOUTOUT
IN
C



CPU0 PCIE P2 TX CPU0 PCIE P3 TXThu Sep 14 16:12:29 2023MB FABCGT AMD64 OF 365V02<NAME_2><NAME_1>
DIFF BUS_0.22UF3063063063062525252529529525252525295295
DIFF BUS_0.22UFDIFF BUS_0.22UFDIFF BUS_0.22UFDIFF BUS_0.22UFDIFF BUS_0.22UFDIFF BUS_0.22UFDIFF BUS_0.22UFDIFF BUS_0.22UFDIFF BUS_0.22UFDIFF BUS_0.22UFDIFF BUS_0.22UFDIFF BUS_0.22UFDIFF BUS_0.22UFDIFF BUS_0.22UFDIFF BUS_0.22UFDIFF BUS_0.22UFDIFF BUS_0.22UFDIFF BUS_0.22UFDIFF BUS_0.22UFDIFF BUS_0.22UFDIFF BUS_0.22UFDIFF BUS_0.22UFDIFF BUS_0.22UFDIFF BUS_0.22UFDIFF BUS_0.22UFDIFF BUS_0.22UFDIFF BUS_0.22UFDIFF BUS_0.22UFDIFF BUS_0.22UF6.3VX6S20%C0201DIFF BUS_0.22UFDIFF BUS_0.22UF
DIFF BUS_0.22UFDIFF BUS_0.22UFDIFF BUS_0.22UFDIFF BUS_0.22UFDIFF BUS_0.22UFDIFF BUS_0.22UFDIFF BUS_0.22UFDIFF BUS_0.22UFDIFF BUS_0.22UFDIFF BUS_0.22UFDIFF BUS_0.22UFDIFF BUS_0.22UFDIFF BUS_0.22UFDIFF BUS_0.22UFDIFF BUS_0.22UFDIFF BUS_0.22UFDIFF BUS_0.22UFDIFF BUS_0.22UFDIFF BUS_0.22UFDIFF BUS_0.22UFDIFF BUS_0.22UFDIFF BUS_0.22UFDIFF BUS_0.22UFDIFF BUS_0.22UFDIFF BUS_0.22UFDIFF BUS_0.22UFDIFF BUS_0.22UFDIFF BUS_0.22UFDIFF BUS_0.22UFDIFF BUS_0.22UFC020120%6.3VDIFF BUS_0.22UFX6S
DIFF BUS_0.22UFP5E_CPU0_P3_TX_C_DP<7:0>P5E_CPU0_P3_TX_C_DN<7:0>P5E_CPU0_P3_TX_C_DP<15:8>P5E_CPU0_P3_TX_C_DN<15:8>P5E_CPU0_P3_TX_DN<7:0>P5E_CPU0_P3_TX_DP<7:0>P5E_CPU0_P3_TX_DP<15:8>P5E_CPU0_P3_TX_DN<15:8>P5E_CPU0_P2_TX_C_DN<7:0>P5E_CPU0_P2_TX_C_DP<7:0>
PCIE AC-COUPLE CAPS 2/5
P5E_CPU0_P2_TX_DN<7:0>P5E_CPU0_P2_TX_DP<7:0>P5E_CPU0_P2_TX_DN<15:8>P5E_CPU0_P2_TX_DP<15:8>P5E_CPU0_P2_TX_C_DN<15:8>P5E_CPU0_P2_TX_C_DP<15:8>
2 1
2 1
2 1
2 1
2 1
2 1
2 1
2 1
2 1
2 1
2 1
2 1
2 1
2 1
2 1
2 1
2 1
2 1
2 1
2 1
2 1
2 1
2 1
2 1
2 1
2 1
2 1
2 1
2 1
2 1
2 1
2 1
2 1
2 1
2 1
2 1
2 1
2 1
2 1
2 1
2 1
2 1
2 1
2 1
2 1
2 1
2 1
2 1
2 1
2 1
2 1
2 1
2 1
2 1
2 1
2 1
2 1
2 1
2 1
2 1
2 1
2 1
2 1
2 1
8
12
7
7
5
4
15
14
13
14
15
13
11
10
9
8
12
11
10
9
8
7
6
5
7
6
5
4
3
2
1
0
3
4
2
1
0
15
14
13
12
11
10
9
15
14
13
12
11
10
9
8
7
6
5
3
2
1
0
7
6
4
3
2
1
0
15
14
13
11
10
9
8
6
3
2
1
0
13
14
15
11
10
9
8
15
14
13
13
14
15
12
11
10
8
12
11
10
9
8
6
4
3
2
1
0
7
6
5
7
6
5
4
3
2
1
0
4
3
2
1
0
5
5
12
12
4
9
C898
C870
C871
C872
C873
C874
C875
C876
C877
C879
C878
C880
C881
C882
C883
C885
C884
C886
C887
C888
C889
C890
C891
C893
C892
C894
C895
C896
C897
C899
C900
C901
C839
C838
C840
C841
C843
C842
C844
C845
C846
C847
C848
C849
C850
C851
C853
C852
C854
C855
C856
C857
C858
C859
C860
C861
C862
C863
C865
C864
C866
C867
C868
C869
2 1
2 12 1
2 12 1
2 12 1
2 12 1
2 12 1
2 12 1
2 12 1
2 12 1
2 12 1
2 12 1
2 12 1
2 12 1
2 12 1
2 12 1
2 1
2 12 1
2 12 1
2 12 1
2 12 1
2 12 1
2 12 1
2 12 1
2 12 1
2 12 1
2 12 1
2 12 1
2 12 1
2 12 1
2 12 1
2 12 1
2 12 1
2 12 1
SHEETDATE
DEPARTMENT
SIZE
PROJECT DOCUMENT NUMBER REV
REVIEWER
DESIGNER
123
7 3 2 1 6 5 4
E
A
B
C
E
D
C
B
A
7 6 5 4
D
ININOUTOUT
ININ OUTOUT
IN OUTOUT
ININOUTOUT
IN
C



CPU1 PCIE P0 TXCPU0 PCIE G3 TXThu Sep 14 16:12:29 2023MB FABC<NAME_2><NAME_1>GT AMDV0265 OF 365
3173173173175151515123232323131131131131DIFF BUS_0.22UFDIFF BUS_0.22UFDIFF BUS_0.22UFDIFF BUS_0.22UFDIFF BUS_0.22UFDIFF BUS_0.22UFDIFF BUS_0.22UFDIFF BUS_0.22UFDIFF BUS_0.22UFDIFF BUS_0.22UFDIFF BUS_0.22UFDIFF BUS_0.22UFDIFF BUS_0.22UFDIFF BUS_0.22UFDIFF BUS_0.22UFDIFF BUS_0.22UFDIFF BUS_0.22UFDIFF BUS_0.22UFDIFF BUS_0.22UFDIFF BUS_0.22UFDIFF BUS_0.22UFDIFF BUS_0.22UFDIFF BUS_0.22UFDIFF BUS_0.22UFDIFF BUS_0.22UFDIFF BUS_0.22UFDIFF BUS_0.22UFDIFF BUS_0.22UF20%6.3VC0201X6SDIFF BUS_0.22UFDIFF BUS_0.22UFDIFF BUS_0.22UFDIFF BUS_0.22UFDIFF BUS_0.22UFDIFF BUS_0.22UFDIFF BUS_0.22UFDIFF BUS_0.22UFDIFF BUS_0.22UFDIFF BUS_0.22UFDIFF BUS_0.22UFDIFF BUS_0.22UFDIFF BUS_0.22UFDIFF BUS_0.22UFDIFF BUS_0.22UFDIFF BUS_0.22UFDIFF BUS_0.22UFDIFF BUS_0.22UFDIFF BUS_0.22UFDIFF BUS_0.22UFDIFF BUS_0.22UFDIFF BUS_0.22UFDIFF BUS_0.22UFDIFF BUS_0.22UFDIFF BUS_0.22UFDIFF BUS_0.22UFDIFF BUS_0.22UFDIFF BUS_0.22UFDIFF BUS_0.22UFDIFF BUS_0.22UFDIFF BUS_0.22UFDIFF BUS_0.22UF20%X6S6.3VDIFF BUS_0.22UFC0201DIFF BUS_0.22UF
DIFF BUS_0.22UFDIFF BUS_0.22UFP5E_CPU1_P0_TX_C_DP<7:0>P5E_CPU1_P0_TX_C_DN<7:0>P5E_CPU1_P0_TX_C_DP<15:8>P5E_CPU1_P0_TX_C_DN<15:8>P5E_CPU1_P0_TX_DP<7:0>P5E_CPU1_P0_TX_DN<7:0>P5E_CPU1_P0_TX_DP<15:8>P5E_CPU1_P0_TX_DN<15:8>P5E_CPU0_G3_TX_DN<7:0>
PCIE AC-COUPLE CAPS 3/5
P5E_CPU0_G3_TX_DN<15:8>P5E_CPU0_G3_TX_DP<15:8>P5E_CPU0_G3_TX_DP<7:0>P5E_CPU0_G3_TX_C_DN<15:8>P5E_CPU0_G3_TX_C_DP<15:8>P5E_CPU0_G3_TX_C_DN<7:0>P5E_CPU0_G3_TX_C_DP<7:0>
2 1
2 1
2 1
2 1
2 1
2 1
2 1
2 1
2 1
2 1
2 1
2 1
2 1
2 1
2 1
2 1
2 1
2 1
2 1
2 1
2 1
2 1
2 1
2 1
2 1
2 1
2 1
2 1
2 1
2 1
2 1
2 1
2 1
2 1
2 1
2 1
2 1
2 1
2 1
2 1
2 1
2 1
2 1
2 1
2 1
2 1
2 1
2 1
2 1
2 1
2 1
2 1
2 1
2 1
2 1
2 1
2 1
2 1
2 1
2 1
2 1
2 1
2 1
2 1
11
13
10
5
0
1
0
1
3
2
4
2
3
4
5
6
5
6
7
7
8
9
10
9
11
12
11
10
12
13
15
13
15
14
0
0
1
1
2
2
3
4
3
4
5
5
6
6
8
8
9
9
10
10
11
12
12
13
14
13
14
15
15
8
4
15
14
15
14
13
13
12
12
11
10
9
10
9
8
8
7
7
6
6
5
5
4
3
2
2
1
1
0
0
15
14
13
15
14
12
11
12
11
9
8
10
9
8
7
7
6
5
6
4
3
2
4
3
2
1
0
1
0
3
7
14
11
7
C824
C825
C807
C806
C808
C809
C810
C811
C813
C812
C814
C815
C816
C817
C819
C818
C821
C820
C823
C822
C826
C827
C829
C830
C828
C833
C832
C831
C835
C834
C837
C836
C1576
C1577
C1549
C1548
C1550
C1792
C1552
C1553
C41
C1555
C1557
C1556
C1558
C1559
C1560
C1793
C1794
C44
C46
C1565
C1566
C47
C1568
C1569
C1571
C1570
C1572
C1573
C1574
C1575
C1578
C1579
2 12 1
2 12 1
2 12 1
2 12 1
2 12 1
2 12 1
2 12 1
2 12 1
2 12 1
2 12 1
2 12 1
2 1
2 1
2 1
2 12 1
2 1
2 12 1
2 12 1
2 12 1
2 12 1
2 12 1
2 12 1
2 12 1
2 12 1
2 12 1
2 12 1
2 12 1
2 12 1
2 12 1
2 12 1
2 12 1
2 12 1
2 12 1
2 12 1
SHEETDATE
DEPARTMENT
SIZE
PROJECT DOCUMENT NUMBER REV
REVIEWER
DESIGNER
123
7 3 2 1 6 5 4
E
A
B
C
E
D
C
B
A
7 6 5 4
D
OUTOUT
OUTOUT
ININ
ININ
OUTOUT
OUTOUT
ININ
ININ
C



CPU1 PCIE P1 TXCPU1 PCIE P2 TXThu Sep 14 16:12:29 2023V02GT AMDMB FABC66 OF 365<NAME_2><NAME_1>
DIFF BUS_0.22UF3393393393395252525232832832832851515151 DIFF BUS_0.22UFDIFF BUS_0.22UFDIFF BUS_0.22UFDIFF BUS_0.22UFDIFF BUS_0.22UFDIFF BUS_0.22UFDIFF BUS_0.22UFDIFF BUS_0.22UFDIFF BUS_0.22UFDIFF BUS_0.22UFDIFF BUS_0.22UFDIFF BUS_0.22UFDIFF BUS_0.22UFDIFF BUS_0.22UFDIFF BUS_0.22UFDIFF BUS_0.22UFDIFF BUS_0.22UFDIFF BUS_0.22UFDIFF BUS_0.22UFDIFF BUS_0.22UFDIFF BUS_0.22UFDIFF BUS_0.22UFDIFF BUS_0.22UFDIFF BUS_0.22UFDIFF BUS_0.22UFDIFF BUS_0.22UFDIFF BUS_0.22UFDIFF BUS_0.22UFDIFF BUS_0.22UFDIFF BUS_0.22UFDIFF BUS_0.22UFDIFF BUS_0.22UFC0201X6S20%6.3V
DIFF BUS_0.22UFDIFF BUS_0.22UFDIFF BUS_0.22UFDIFF BUS_0.22UFDIFF BUS_0.22UFDIFF BUS_0.22UFDIFF BUS_0.22UFDIFF BUS_0.22UFDIFF BUS_0.22UFDIFF BUS_0.22UFDIFF BUS_0.22UFDIFF BUS_0.22UFDIFF BUS_0.22UFDIFF BUS_0.22UFDIFF BUS_0.22UFDIFF BUS_0.22UFDIFF BUS_0.22UFDIFF BUS_0.22UFDIFF BUS_0.22UFDIFF BUS_0.22UFDIFF BUS_0.22UFDIFF BUS_0.22UFDIFF BUS_0.22UFDIFF BUS_0.22UFDIFF BUS_0.22UFDIFF BUS_0.22UFDIFF BUS_0.22UFDIFF BUS_0.22UFDIFF BUS_0.22UFX6SC0201DIFF BUS_0.22UF20%6.3VDIFF BUS_0.22UFP5E_CPU1_P2_TX_C_DP<7:0>P5E_CPU1_P2_TX_C_DN<7:0>P5E_CPU1_P2_TX_C_DP<15:8>P5E_CPU1_P2_TX_C_DN<15:8>P5E_CPU1_P2_TX_DN<7:0>P5E_CPU1_P2_TX_DP<7:0>P5E_CPU1_P2_TX_DP<15:8>P5E_CPU1_P2_TX_DN<15:8>P5E_CPU1_P1_TX_C_DP<7:0>P5E_CPU1_P1_TX_C_DN<7:0>P5E_CPU1_P1_TX_C_DP<15:8>P5E_CPU1_P1_TX_C_DN<15:8>
PCIE AC-COUPLE CAPS 4/5
P5E_CPU1_P1_TX_DN<15:8>P5E_CPU1_P1_TX_DP<15:8>P5E_CPU1_P1_TX_DN<7:0>P5E_CPU1_P1_TX_DP<7:0>
2 1
2 1
2 1
2 1
2 1
2 1
2 1
2 1
2 1
2 1
2 1
2 1
2 1
2 1
2 1
2 1
2 1
2 1
2 1
2 1
2 1
2 1
2 1
2 1
2 1
2 1
2 1
2 1
2 1
2 1
2 1
2 1
2 1
2 1
2 1
2 1
2 1
2 1
2 1
2 1
2 1
2 1
2 1
2 1
2 1
2 1
2 1
2 1
2 1
2 1
2 1
2 1
2 1
2 1
2 1
2 1
2 1
2 1
2 1
2 1
2 1
2 1
2 1
2 1
13
12
0 0
1
2
4
5
6
7
0
1
2
3
4
5
6
7
8
9
10
11
12
13
14
15
8
9
10
14
15
0
1
2
4
3
0
1
3
4
5
6
7
5
6
7
8
9
10
11
12
8
9
10
11
13
15
14
13
14
15
2
3
12
12
11
5
4
15
15
14
13
14
13
11
10
11
12
10
9
8
9
8
15
14
13
15
14
13
12
11
10
12
10
11
9
8
9
8
7
7
6
5
6
4
3
2
3
2
1
0
1
0
7
7
6
4
5
6
3
2
4
3
2
1
1
0
5
C726
C710
C711
C713
C712
C714
C715
C716
C717
C718
C719
C720
C721
C723
C722
C724
C725
C727
C728
C729
C730
C731
C732
C733
C735
C734
C736
C737
C738
C739
C741
C740
C742
C743
C744
C745
C746
C747
C748
C749
C751
C750
C752
C753
C754
C755
C757
C756
C758
C759
C760
C761
C762
C763
C765
C764
C766
C767
C768
C769
C770
C771
C772
C773
2 1
2 12 1
2 12 1
2 12 1
2 12 1
2 12 1
2 12 1
2 12 1
2 12 1
2 1
2 12 1
2 12 1
2 12 1
2 12 1
2 12 1
2 12 1
2 12 1
2 12 1
2 12 1
2 12 1
2 12 1
2 12 1
2 12 1
2 12 1
2 12 1
2 12 1
2 12 1
2 12 1
2 12 1
2 12 1
2 12 1
2 12 1
2 12 1
SHEETDATE
DEPARTMENT
SIZE
PROJECT DOCUMENT NUMBER REV
REVIEWER
DESIGNER
123
7 3 2 1 6 5 4
E
A
B
C
E
D
C
B
A
7 6 5 4
D
ININ
OUTOUT
OUTOUT
ININ
ININ
OUTOUT
OUTOUT
ININ
C



CPU0 PCIE P4 TXCPU1 PCIE P3 TXCPU1 PCIE P4 TXCPU1 PCIE G1 TXThu Sep 14 16:12:36 2023MB FABC<NAME_2><NAME_1>GT AMDV0267 OF 365262652525252350350350350
14514549495353
4949137137
144144137137DIFF BUS_0.22UFDIFF BUS_0.22UFDIFF BUS_0.22UFDIFF BUS_0.22UFDIFF BUS_0.22UFDIFF BUS_0.22UFDIFF BUS_0.22UFDIFF BUS_0.22UFDIFF BUS_0.22UFDIFF BUS_0.22UFDIFF BUS_0.22UFDIFF BUS_0.22UFDIFF BUS_0.22UFDIFF BUS_0.22UFDIFF BUS_0.22UFDIFF BUS_0.22UFDIFF BUS_0.22UFDIFF BUS_0.22UFDIFF BUS_0.22UFDIFF BUS_0.22UFDIFF BUS_0.22UFDIFF BUS_0.22UFDIFF BUS_0.22UFDIFF BUS_0.22UFDIFF BUS_0.22UFDIFF BUS_0.22UFDIFF BUS_0.22UFDIFF BUS_0.22UFDIFF BUS_0.22UFDIFF BUS_0.22UF20%6.3VC0201X6SDIFF BUS_0.22UF
DIFF BUS_0.22UFDIFF BUS_0.22UFDIFF BUS_0.22UFDIFF BUS_0.22UFDIFF BUS_0.22UFDIFF BUS_0.22UFDIFF BUS_0.22UFDIFF BUS_0.22UFDIFF BUS_0.22UFDIFF BUS_0.22UFDIFF BUS_0.22UFDIFF BUS_0.22UFDIFF BUS_0.22UFDIFF BUS_0.22UFDIFF BUS_0.22UFDIFF BUS_0.22UFDIFF BUS_0.22UFDIFF BUS_0.22UFDIFF BUS_0.22UFDIFF BUS_0.22UFDIFF BUS_0.22UFDIFF BUS_0.22UFDIFF BUS_0.22UFDIFF BUS_0.22UFDIFF BUS_0.22UFDIFF BUS_0.22UFDIFF BUS_0.22UFDIFF BUS_0.22UFDIFF BUS_0.22UFDIFF BUS_0.22UFDIFF BUS_0.22UFC0201X6S20%6.3VDIFF BUS_0.22UFDIFF BUS_0.22UFP3E_CPU0_P4_TX_DN<3:0>P3E_CPU0_P4_TX_DP<3:0>P5E_CPU1_P3_TX_DN<7:0>P5E_CPU1_P3_TX_DP<7:0>P5E_CPU1_P3_TX_DP<15:8>P5E_CPU1_P3_TX_DN<15:8>P5E_CPU1_P3_TX_C_DP<7:0>P5E_CPU1_P3_TX_C_DN<7:0>P5E_CPU1_P3_TX_C_DP<15:8>P5E_CPU1_P3_TX_C_DN<15:8>
P3E_CPU0_P4_TX_C_DP<3:0>P3E_CPU0_P4_TX_C_DN<3:0>P5E_CPU1_G1_TX_DP<7:0>P5E_CPU1_G1_TX_DN<7:0>P3E_CPU1_P4_TX_DN<3:0>P3E_CPU1_P4_TX_DP<3:0>
P5E_CPU1_G1_TX_DN<15:8>P5E_CPU1_G1_TX_DP<15:8>P5E_CPU1_G1_TX_C_DN<15:8>P5E_CPU1_G1_TX_C_DP<15:8>
P3E_CPU1_P4_TX_C_DP<3:0>P3E_CPU1_P4_TX_C_DN<3:0>P5E_CPU1_G1_TX_C_DP<7:0>P5E_CPU1_G1_TX_C_DN<7:0>
DIFF BUS_0.22UFDIFF BUS_0.22UFDIFF BUS_0.22UFDIFF BUS_0.22UFDIFF BUS_0.22UFDIFF BUS_0.22UFDIFF BUS_0.22UFX6S20%C0201 6.3VDIFF BUS_0.22UFDIFF BUS_0.22UFDIFF BUS_0.22UFDIFF BUS_0.22UFDIFF BUS_0.22UFDIFF BUS_0.22UFDIFF BUS_0.22UFDIFF BUS_0.22UFC020120%X6S6.3VDIFF BUS_0.22UFPCIE AC-COUPLE CAPS 5/5
2 1
2 1
2 1
2 1
2 1
2 1
2 1
2 1
2 1
2 1
2 1
2 1
2 1
2 1
2 1
2 1
2 1
2 1
2 1
2 1
2 1
2 1
2 1
2 1
2 1
2 1
2 1
2 1
2 1
2 1
2 1
2 1
2 1
2 1
2 1
2 1
2 1
2 1
2 1
2 1
2 1
2 1
2 1
2 1
2 1
2 1
2 1
2 1
2 1
2 1
2 1
2 1
2 1
2 1
2 1
2 1
2 1
2 1
2 1
2 1
2 1
2 1
2 1
2 1
2 1
2 1
2 1
2 1
2 1
2 1
2 1
2 1
2 1
2 1
2 1
2 1
2 1
2 1
2 1
2 1
2 1
2 1
2 1
2 1
2 1
2 1
2 1
2 1
2 1
2 1
2 1
2 1
2 1
2 1
2 1
2 1
0
3
1
2
3
2
1
3
2
1
3
2
1
0
0
0
1
2
1
2
3
4
5
3
4
5
6
7
6
7
8
9
10
8
9
10
11
12
11
12
0
0
0
0
1
2
1
2
3
5
4
3
4
5
6
7
6
7
8
10
9
8
9
10
11
12
11
12
14
13
15
13
15
14
13
15
14
13
14
15
3
2
1
3
2
1
3
3
2
1
2
1
0
0
0
1
2
0
1
2
0
0
0
0
1
2
1
2
3
5
4
3
4
6
7
6
5
7
8
9
10
8
9
10
11
12
11
12
3
4
4
5
6
5
7
6
7
8
9
10
9
8
10
11
12
11
12
14
13
15
13
15
14
13
15
14
14
13
15
3
C678
C679
C680
C681
C682
C683
C684
C685
C686
C687
C689
C688
C690
C691
C692
C56
C694
C695
C696
C697
C699
C698
C700
C701
C703
C702
C704
C705
C707
C706
C708
C709
C9104
C9105
C9102
C9103
C1100
C1101
C1098
C1099
C49
C48
C50
C51
C52
C53
C54
C55
C1524
C1525
C1527
C1526
C1528
C1529
C1530
C1531
C1532
C1533
C1534
C1535
C1536
C1537
C1538
C1539
C1540
C1541
C1542
C1543
C1545
C1544
C1546
C1547
C1995
C1996
C1993
C1994
C1991
C1992
C1989
C1990
2 12 1
2 12 1
2 12 1
2 12 1
2 12 1
2 12 1
2 12 1
2 12 1
2 12 1
2 12 1
2 12 1
2 12 1
2 12 1
2 12 1
2 12 1
2 12 1
2 12 1
2 12 1
2 12 1
2 12 1
2 12 1
2 12 1
2 12 1
2 12 1
2 12 1
2 12 1
2 12 1
2 12 1
2 12 1
2 12 1
2 12 1
2 12 1
SHEETDATE
DEPARTMENT
SIZE
PROJECT DOCUMENT NUMBER REV
REVIEWER
DESIGNER
123
7 3 2 1 6 5 4
E
A
B
C
E
D
C
B
A
7 6 5 4
D
ININ
OUTOUT
OUTOUT
OUTOUT
ININOUTOUT
ININ
ININOUTOUT
ININ
OUTOUT
ININ
C



5
1055
101055PVDDCR_SOC_P0: 22PCS 22UF ON TOPPVDDIO_P0: 7PCS 22UF ON TOPPVDD18_S5_P0: 3PCS 22UF ON TOPPVDD11_S3_P0: 16PCS 22UF ON TOPThu Sep 14 16:12:02 2023<NAME_2><NAME_1>MB FABCGT AMDV0268 OF 365
PVDDCR_SOC_P0PVDDCR_SOC_P0PVDDCR_SOC_P0PVDDIO_P0PVDD18_S5_P0PVDD11_S3_P0PVDD11_S3_P0
C0402C0402C0402C0402C0402C0402C0402C0402C0402C0402C0402C0402C0402C0402C0402C0402C0402C0402C0402C0402C0402C0402C0402C0402C0402C0402C0402C0402C0402C0402C0402C0402C0402C0402C0402C0402C0402C0402C0402C0402
C0402 C0402C0402C0402C0402C0402C0402C04024V4V4V4V4V4V4V4V4V4V4V4V4V4V 4V4V4V4V4V4V4V4V4V4V4V4V4V4V4V4V4V4V4V4V4V4V4V4V4V4V
4V 4V4V4V4V4V4V4V22UF22UF22UF22UF22UF22UF22UF22UF22UF22UF22UF22UF22UF22UF22UF22UF22UF22UF22UF22UF22UF22UF22UF22UF22UF22UF22UF22UF22UF22UF22UF22UF22UF22UF22UF22UF22UF22UF22UF22UF
22UF 22UF22UF22UF22UF22UF22UF22UF20%20%20%20%20%20%20%20%20%20%20%20%20%20%20%20%20%20%20%20%20%20%20%20%20%20%20%20%20%20%20%20%20%20%20%20%20%20%20%20%
20%20%20%20%20%20%20%20%X6SX6SX6SX6SX6SX6SX6SX6SX6SX6SX6SX6SX6SX6SX6SX6SX6SX6SX6SX6SX6SX6SX6SX6SX6SX6SX6SX6SX6SX6SX6SX6SX6SX6SX6SX6SX6SX6SX6SX6S
X6SX6SX6SX6SX6SX6SX6SX6S
CPU0 CAVITY TOP DECOUPLING CAPS
2
1 C3899
2
1 C3898
2
1 C2149
2
1 C2145
2
1 C2141
2
1 C2136
2
1 C2131
2
1 C3897
2
1 C2164
2
1 C2163
2
1 C2162
2
1 C2160
2
1 C2158
2
1 C2156
2
1 C2153
2
1 C2150
2
1 C2146
2
1 C2142
2
1 C3893
2
1 C3892
2
1 C3891
2
1 C3890
2
1 C2137
2
1 C2132
2
1 C2138
2
1 C2133
2
1 C2147
2
1 C2161
2
1 C3896
2
1 C2159
2
1 C2157
2
1 C3895
2
1 C3894
2
1 C2154
2
1 C2151
2
1 C2155
2
1 C2152
2
1 C2143
2
1 C2139
2
1 C2148
2
1 C2144
2
1 C2140
2
1 C2134
2
1 C2129
2
1 C2135
2
1 C3889
2
1 C2130
2
1 C3888
SHEETDATE
DEPARTMENT
SIZE
PROJECT DOCUMENT NUMBER REV
REVIEWER
DESIGNER
123
7 3 2 1 6 5 4
E
A
B
C
E
D
C
B
A
7 6 5 4
D
C



PVDDCR_CPU1_P0: 45PCS 22UF ON BOTPVDDCR_CPU0_P0: 45PCS 22UF ON BOT5
5
51010
Thu Sep 14 16:12:03 2023<NAME_2><NAME_1>MB FABCGT AMDV0269 OF 365
PVDDCR_CPU0_P0PVDDCR_CPU1_P0PVDDCR_CPU1_P0PVDDCR_CPU0_P0PVDDCR_CPU1_P0PVDDCR_CPU1_P0PVDDCR_CPU1_P0PVDDCR_CPU0_P0
PVDDCR_CPU0_P0PVDDCR_CPU0_P0X6SX6S20%
C0402C0402C0402C0402C0402C0402C0402C0402C0402C0402 C0402C0402C0402C0402C0402C0402C0402C0402C0402C0402C0402C0402C0402C0402C0402C0402C0402C0402C0402C0402C0402C0402C0402
C0402C0402C0402C0402C0402C0402C0402C0402C0402C0402C0402C0402C0402C0402C0402C0402C0402C0402C0402C0402C0402 C0402C0402C0402C0402C0402C0402C0402C0402C0402C0402C0402C0402C0402C0402C0402C0402C0402C0402 C0402C0402C0402
C0402C0402C0402C0402 C0402C0402C0402C0402C0402C0402C0402C0402C0402C0402C0402
4V4V4V4V4V4V4V4V4V4V 4V4V4V4V4V4V4V4V4V4V4V4V4V4V4V4V4V4V4V 4V4V4V4V
4V4V4V4V4V4V4V4V4V4V4V4V4V4V4V4V4V4V4V4V4V 4V4V4V4V4V4V4V4V4V4V4V4V4V4V4V4V4V4V4V4V4V
4V4V4V4V 4V4V4V4V4V4V4V4V4V4V4V
22UF22UF22UF22UF22UF22UF22UF22UF22UF22UF 22UF22UF22UF22UF22UF22UF22UF22UF22UF22UF22UF22UF22UF22UF22UF22UF22UF22UF22UF22UF22UF22UF22UF
22UF22UF22UF22UF22UF22UF22UF22UF22UF22UF22UF22UF22UF22UF22UF22UF22UF22UF22UF22UF22UF 22UF22UF22UF22UF22UF22UF22UF22UF22UF22UF22UF22UF22UF22UF22UF22UF22UF22UF 22UF22UF22UF
22UF22UF22UF22UF 22UF22UF22UF22UF22UF22UF22UF22UF22UF22UF22UF
20%20%20%20%20%20%20%20%20%20% 20%20%20%20%20%20%20%20%20%20%20%20%20%20%20%20%20%20%20%20%20%20%20%
20%20%20%20%20%20%20%20%20%20%20%20%20%20%20%20%20%20%20%20%20%20%20%20%20%20%20%20%20%20%20%20%20%20%20%20%20%20%20% 20%20%20%
20%20%20%20%20%20%20%20%20%20%20%20%20%20%X6SX6SX6SX6SX6SX6SX6SX6SX6SX6S X6SX6SX6SX6SX6SX6SX6SX6SX6SX6SX6SX6SX6SX6SX6SX6SX6SX6SX6SX6SX6SX6SX6S
X6SX6SX6SX6SX6SX6SX6SX6SX6SX6SX6SX6SX6SX6SX6SX6SX6SX6SX6SX6SX6SX6SX6SX6SX6SX6SX6SX6SX6SX6SX6SX6SX6SX6SX6SX6SX6SX6SX6S X6SX6S
X6SX6SX6SX6SX6SX6SX6SX6SX6SX6SX6SX6SX6SX6S
CPU0 CAVITY BOT DECOUPLING CAPS 1/3
2
1 C272
2
1 C2253
2
1 C2248
2
1 C2254
2
1 C2249
2
1 C2243
2
1 C2237
2
1 C2244
2
1 C2238
2
1 C2231
2
1 C2225
2
1 C2219
2
1 C2232
2
1 C2226
2
1 C2220
2
1 C2213
2
1 C2207
2
1 C2214
2
1 C2208
2
1 C2255
2
1 C2250
2
1 C2256
2
1 C2251
2
1 C2245
2
1 C2239
2
1 C2246
2
1 C2240
2
1 C2233
2
1 C2227
2
1 C2221
2
1 C2234
2
1 C2228
2
1 C2222
2
1 C2215
2
1 C2209
2
1 C2216
2
1 C2210
2
1 C2229
2
1 C2223
2
1 C2217
2
1 C2211
2
1 C2201
2
1 C278
2
1 C2202
2
1 C279
2
1 C276
2
1 C274
2
1 C277
2
1 C275
2
1 C270
2
1 C273
2
1 C271
2
1 C267
2
1 C268
2
1 C4179
2
1 C4178
2
1 C263
2
1 C1922
2
1 C2203
2
1 C2198
2
1 C2204
2
1 C2199
2
1 C2195
2
1 C2192
2
1 C2196
2
1 C2193
2
1 C2205
2
1 C2189
2
1 C2185
2
1 C2190
2
1 C2186
2
1 C2181
2
1 C2182
2
1 C2177
2
1 C2173
2
1 C2178
2
1 C2174
2
1 C2183
2
1 C10179
2
1 C2175
2
1 C251
2
1 C245
2
1 C252
2
1 C246
2
1 C2169
2
1 C2165
2
1 C2170
2
1 C2166
2
1 C2171
2
1 C2167
SHEETDATE
DEPARTMENT
SIZE
PROJECT DOCUMENT NUMBER REV
REVIEWER
DESIGNER
123
7 3 2 1 6 5 4
E
A
B
C
E
D
C
B
A
7 6 5 4
D
C



51010105510101010555
PVDDIO_P0: 24PCS 22UF ON BOT1010551010101055555
PVDDCR_SOC_P0: 77PCS 22UF ON BOT5PVDD11_S3_P0: 42PCS 22UF ON BOT
Thu Sep 14 16:12:03 2023<NAME_2><NAME_1>MB FABCGT AMDV0270 OF 365PVDDCR_SOC_P0PVDD11_S3_P0PVDD11_S3_P0PVDD11_S3_P0PVDD11_S3_P0PVDD11_S3_P0PVDDCR_SOC_P0
PVDDCR_SOC_P0PVDDCR_SOC_P0
PVDDCR_SOC_P0
PVDDCR_SOC_P0PVDDCR_SOC_P0PVDDCR_SOC_P0PVDDIO_P0PVDDIO_P0PVDDIO_P0C0402C0402C0402C0402C0402C0402C0402C0402C0402C0402C0402C0402C0402C0402C0402C0402C0402C0402C0402C0402C0402C0402C0402C0402C0402C0402C0402C0402C0402C0402C0402C0402C0402C0402C0402C0402C0402C0402C0402C0402C0402C0402C0402C0402C0402C0402C0402C0402C0402C0402C0402C0402C0402C0402C0402C0402C0402C0402C0402C0402C0402C0402C0402C0402C0402C0402C0402C0402C0402
C0402C0402C0402C0402C0402C0402C0402C0402C0402C0402C0402C0402C0402C0402C0402C0402C0402C0402C0402C0402C0402C0402C0402C0402C0402C0402C0402C0402C0402C0402C0402C0402C0402C0402C0402C0402C0402C0402C0402C0402C0402C0402C0402C0402C0402C0402C0402C0402C0402C0402C0402C0402C0402C0402C0402C0402C0402C0402C0402C0402C0402C0402C0402C0402C0402C0402C0402C0402C0402C0402C0402C0402C0402C0402
4V4V4V4V4V4V4V4V4V4V4V4V4V4V4V4V4V4V4V4V4V4V4V4V4V4V4V4V4V4V4V4V4V4V4V4V4V4V4V4V4V4V4V4V4V4V4V4V4V4V4V4V4V4V4V4V4V4V4V4V4V4V4V4V4V4V4V4V4V
4V4V4V4V4V 4V4V4V4V4V4V4V4V4V4V4V4V4V4V4V 4V4V4V4V4V4V4V4V4V4V 4V4V4V4V4V4V4V4V4V4V4V4V4V4V4V4V4V4V 4V4V4V4V4V4V4V4V4V4V4V4V4V4V4V4V4V4V4V4V4V4V4V4V4V4V
22UF22UF22UF22UF22UF22UF22UF22UF22UF22UF22UF22UF22UF22UF22UF22UF22UF22UF22UF22UF22UF22UF22UF22UF22UF22UF22UF22UF22UF22UF22UF22UF22UF22UF22UF22UF22UF22UF22UF22UF22UF22UF22UF22UF22UF22UF22UF22UF22UF22UF22UF22UF22UF22UF22UF22UF22UF22UF22UF22UF22UF22UF22UF22UF22UF22UF22UF22UF22UF
22UF22UF22UF22UF22UF22UF22UF22UF22UF22UF22UF22UF22UF22UF22UF22UF22UF22UF22UF22UF22UF22UF22UF22UF22UF22UF22UF22UF22UF22UF22UF22UF22UF22UF22UF22UF22UF22UF22UF22UF22UF22UF22UF22UF22UF22UF22UF22UF22UF22UF22UF22UF22UF22UF22UF22UF22UF22UF22UF22UF22UF22UF22UF22UF22UF22UF22UF22UF22UF22UF22UF22UF22UF22UF
20%20%20%20%20%20%20%20%20%20%20%20%20%20%20%20%20%20%20%20%20%20%20%20%20%20%20%20%20%20%20%20%20%20%20%20%20%20%20%20%20%20%20%20%20%20%20%20%20%20%20%20%20%20%20%20%20%20%20%20%20%20%20%20%20%20%20%20%20%
20%20%20%20%20% 20%20%20%20%20%20%20%20%20%20%20%20%20%20%20%20%20%20%20%20%20%20%20%20%20% 20%20%20%20%20%20%20%20%20%20%20%20%20%20%20%20%20%20%20%20%20%20%20%20%20%20%20%20%20%20%20%20%20%20%20%20%20%20%20%20%20%20%20%20%
X6SX6SX6SX6SX6SX6SX6SX6SX6SX6SX6SX6SX6SX6SX6SX6SX6SX6SX6SX6SX6SX6SX6SX6SX6SX6SX6SX6SX6SX6SX6SX6SX6SX6SX6SX6SX6SX6SX6SX6SX6SX6SX6SX6SX6SX6SX6SX6SX6SX6SX6SX6SX6SX6SX6SX6SX6SX6SX6SX6SX6SX6SX6SX6SX6SX6SX6SX6SX6S
X6SX6SX6SX6SX6S X6SX6SX6SX6SX6SX6SX6SX6SX6SX6SX6SX6SX6SX6SX6SX6SX6SX6SX6SX6SX6SX6SX6SX6SX6S X6SX6SX6SX6SX6SX6SX6SX6SX6SX6SX6SX6SX6SX6SX6SX6SX6SX6SX6SX6SX6SX6SX6SX6SX6SX6SX6SX6SX6SX6SX6SX6SX6SX6SX6SX6SX6SX6SX6SX6SX6SX6SX6SX6SCPU0 CAVITY BOT DECOUPLING CAPS 2/3
2
1 C2654
2
1 C2649
2
1 C2655
2
1 C2650
2
1 C2643
2
1 C2637
2
1 C2644
2
1 C2638
2
1 C2631
2
1 C2625
2
1 C2632
2
1 C2626
2
1 C2620
2
1 C2618
2
1 C2611
2
1 C2604
2
1 C2619
2
1 C2612
2
1 C2613
2
1 C2605
2
1 C2606
2
1 C2656
2
1 C2651
2
1 C2657
2
1 C2652
2
1 C2645
2
1 C2639
2
1 C2646
2
1 C2640
2
1 C2658
2
1 C3935
2
1 C2653
2
1 C3934
2
1 C2647
2
1 C2648
2
1 C2641
2
1 C2642
2
1 C2633
2
1 C2627
2
1 C2634
2
1 C2628
2
1 C2621
2
1 C2622
2
1 C2614
2
1 C2607
2
1 C2615
2
1 C2608
2
1 C2635
2
1 C2636
2
1 C2629
2
1 C2630
2
1 C2623
2
1 C2624
2
1 C2616
2
1 C2617
2
1 C2609
2
1 C2610
2
1 C3933
2
1 C2597
2
1 C2590
2
1 C2598
2
1 C2599
2
1 C2591
2
1 C2592
2
1 C2583
2
1 C2576
2
1 C2584
2
1 C2585
2
1 C2577
2
1 C2578
2
1 C2569
2
1 C2562
2
1 C2570
2
1 C2571
2
1 C2563
2
1 C2564
2
1 C2555
2
1 C2548
2
1 C2541
2
1 C2556
2
1 C2557
2
1 C2549
2
1 C2550
2
1 C2542
2
1 C2543
2
1 C2600
2
1 C2593
2
1 C2601
2
1 C2594
2
1 C2595
2
1 C2586
2
1 C2579
2
1 C2587
2
1 C2588
2
1 C2580
2
1 C2581
2
1 C2602
2
1 C2603
2
1 C2596
2
1 C3932
2
1 C2589
2
1 C2582
2
1 C2572
2
1 C2565
2
1 C2573
2
1 C2574
2
1 C2566
2
1 C2567
2
1 C2558
2
1 C2551
2
1 C2544
2
1 C2559
2
1 C2552
2
1 C2560
2
1 C2553
2
1 C2545
2
1 C2546
2
1 C2575
2
1 C2568
2
1 C3931
2
1 C3930
2
1 C2561
2
1 C2554
2
1 C2547
2
1 C3929
2
1 C3928
2
1 C3927
2
1 C2534
2
1 C2527
2
1 C2535
2
1 C2536
2
1 C2528
2
1 C2529
2
1 C2537
2
1 C2530
2
1 C2538
2
1 C2539
2
1 C2531
2
1 C2532
2
1 C2540
2
1 C2533
2
1 C3926
2
1 C3925
SHEETDATE
DEPARTMENT
SIZE
PROJECT DOCUMENT NUMBER REV
REVIEWER
DESIGNER
123
7 3 2 1 6 5 4
E
A
B
C
E
D
C
B
A
7 6 5 4
D
C



510PVDD33_S5: 2PCS 22UF ON BOTPVDD18_S5_P0: 12PCS 22UF ON BOT
Thu Sep 14 16:12:03 2023<NAME_2><NAME_1>MB FABCGT AMDV0271 OF 365
PVDD_33_S5PVDD18_S5_P0PVDD18_S5_P0X6S6.3V10UFC040220%X6S6.3V10UF20%C0402
CPU0 CAVITY BOT DECOUPLING CAPS 3/3X6SX6S X6S X6S X6SX6S X6SX6S X6SX6SX6SX6S20%20% 20% 20% 20%20% 20%20% 20%20%20%20%22UF22UF 22UF 22UF 22UF 22UF 22UF 22UF 22UF22UF22UF22UF4V4V4V 4V 4V 4V 4V4V 4V4V4V4VC0402C0402 C0402 C0402 C0402 C0402 C0402 C0402 C0402C0402C0402C0402
2
1 C2526
2
1 C2525
2
1 C2524
2
1 C2523
2
1 C2522
2
1 C2521
2
1 C2520
2
1 C2518
2
1 C2516
2
1 C2517
2
1 C2513
2
1 C2514
C2512 C2515
2
1
2
1
SHEETDATE
DEPARTMENT
SIZE
PROJECT DOCUMENT NUMBER REV
REVIEWER
DESIGNER
123
7 3 2 1 6 5 4
E
A
B
C
E
D
C
B
A
7 6 5 4
D
C



PVDDIO_P1: 7PCS 22UF ON TOP5PVDD18_S5_P1: 3PCS 22UF ON TOP1010551055
PVDDCR_SOC_P1: 22PCS 22UF ON TOP
PVDD11_S3_P1: 16PCS 22UF ON TOPThu Sep 14 16:12:03 2023<NAME_2><NAME_1>MB FABCGT AMDV0272 OF 365
PVDDCR_SOC_P1PVDDCR_SOC_P1PVDDIO_P1PVDD18_S5_P1PVDD11_S3_P1PVDD11_S3_P1
PVDDCR_SOC_P1C0402C0402C0402C0402C0402C0402C0402C0402C0402C0402C0402C0402C0402 C0402C0402C0402C0402C0402C0402C0402C0402C0402C0402C0402C0402C0402C0402C0402C0402C0402C0402C0402 C0402C0402C0402C0402C0402C0402C0402C0402C0402C0402C0402C0402C0402C0402C0402C0402
4V4V4V 4V4V4V4V4V4V4V4V4V4V4V4V4V4V4V4V4V4V4V4V4V4V4V4V4V4V4V4V4V 4V4V4V4V4V4V4V4V4V4V4V4V4V4V4V4V
22UF22UF22UF22UF22UF22UF22UF22UF22UF22UF22UF22UF22UF 22UF22UF22UF22UF22UF22UF22UF22UF22UF22UF22UF22UF22UF22UF22UF22UF22UF22UF22UF 22UF22UF22UF22UF22UF22UF22UF22UF22UF22UF22UF22UF22UF22UF22UF22UF
20%20%20%20%20%20%20%20%20%20%20%20%20% 20%20%20%20%20%20%20%20%20%20%20%20%20%20%20%20%20%20%20%20%20%20%20%20%20%20%20%20%20%20%20%20%20%20%20%
X6SX6SX6SX6SX6SX6SX6SX6SX6SX6SX6SX6SX6S X6SX6SX6SX6SX6SX6SX6SX6SX6SX6SX6SX6SX6SX6SX6SX6SX6SX6SX6SX6SX6SX6SX6SX6SX6SX6SX6SX6SX6SX6SX6SX6SX6SX6SX6SCPU1 CAVITY TOP DECOUPLING CAPS
2
1 C2276
2
1 C3911
2
1 C3910
2
1 C2278
2
1 C2274
2
1 C2270
2
1 C2265
2
1 C2260
2
1 C3909
2
1 C2293
2
1 C2292
2
1 C2290
2
1 C3908
2
1 C2288
2
1 C3907
2
1 C2286
2
1 C3906
2
1 C2283
2
1 C2284
2
1 C2280
2
1 C2281
2
1 C2277
2
1 C2273
2
1 C2272
2
1 C2268
2
1 C2269
2
1 C2263
2
1 C2264
2
1 C2291
2
1 C2289
2
1 C2287
2
1 C2285
2
1 C3901
2
1 C2282
2
1 C2279
2
1 C2275
2
1 C3905
2
1 C3904
2
1 C3903
2
1 C2271
2
1 C2266
2
1 C3902
2
1 C2267
2
1 C2258
2
1 C2259
2
1 C3900
2
1 C2261
2
1 C2262
SHEETDATE
DEPARTMENT
SIZE
PROJECT DOCUMENT NUMBER REV
REVIEWER
DESIGNER
123
7 3 2 1 6 5 4
E
A
B
C
E
D
C
B
A
7 6 5 4
D
C



PVDDCR_CPU1_P1: 45PCS 22UF ON BOT105
5
105
5
PVDDCR_CPU0_P1: 45PCS 22UF ON BOT
Thu Sep 14 16:12:04 2023<NAME_2><NAME_1>MB FABCGT AMDV0273 OF 365
C0402PVDDCR_CPU0_P1PVDDCR_CPU1_P1PVDDCR_CPU1_P1PVDDCR_CPU0_P1PVDDCR_CPU1_P1PVDDCR_CPU1_P1PVDDCR_CPU1_P1PVDDCR_CPU0_P1
PVDDCR_CPU0_P1PVDDCR_CPU0_P1C0402C0402C0402C0402C0402C0402C0402C0402C0402C0402C0402C0402C0402C0402C0402C0402C0402C0402C0402C0402C0402C0402C0402C0402C0402C0402C0402C0402C0402C0402C0402C0402C0402C0402C0402C0402C0402C0402C0402C0402C0402C0402C0402C0402C0402C0402C0402C0402C0402C0402C0402C0402C0402C0402C0402C0402C0402C0402C0402C0402C0402C0402C0402C0402C0402C0402C0402C0402C0402
C0402C0402C0402C0402C0402C0402C0402C0402C0402C0402C0402C0402C0402C0402C0402C0402C0402C0402C0402C04024V4V4V4V4V4V4V4V 4V4V4V4V4V4V4V4V4V4V4V4V4V4V4V4V4V4V4V4V4V4V4V4V4V4V4V4V4V4V4V4V4V4V4V4V4V4V4V4V4V4V4V4V4V4V4V4V4V4V4V4V4V4V4V4V4V4V4V4V4V4V
4V4V4V4V4V4V4V4V4V 4V4V4V4V4V4V4V4V4V4V4V 22UF22UF22UF22UF22UF22UF22UF22UF22UF22UF22UF22UF22UF22UF22UF22UF22UF22UF22UF22UF22UF22UF22UF22UF22UF22UF22UF22UF22UF22UF22UF22UF22UF22UF22UF22UF22UF22UF22UF22UF22UF22UF22UF22UF22UF22UF22UF22UF22UF22UF22UF22UF22UF22UF22UF22UF22UF22UF22UF22UF22UF22UF22UF22UF22UF22UF22UF22UF22UF22UF
22UF22UF22UF22UF22UF22UF22UF22UF22UF22UF22UF22UF22UF22UF22UF22UF22UF22UF22UF22UF20%20%20%20%20%20%20%20%20%20%20%20%20%20%20%20%20%20%20%20%20%20%20%20%20%20%20%20%20%20%20%20%20%20%20%20%20%20%20%20%20%20%20%20%20%20%20%20%20%20%20%20%20%20%20%20%20%20%20%20%20%20%20%20%20%20%20%20%20%20%
20%20%20%20%20%20%20%20%20%20%20%20%20%20%20%20%20%20%20%20% X6SX6SX6SX6SX6SX6SX6SX6S X6SX6SX6SX6SX6SX6SX6SX6SX6SX6SX6SX6SX6SX6SX6SX6SX6SX6SX6SX6SX6SX6SX6SX6SX6SX6SX6SX6SX6SX6SX6SX6SX6SX6SX6SX6SX6SX6SX6SX6SX6SX6SX6SX6SX6SX6SX6SX6SX6SX6SX6SX6SX6SX6SX6SX6SX6SX6SX6SX6SX6SX6S
X6SX6SX6SX6SX6SX6SX6SX6SX6S X6SX6SX6SX6SX6SX6SX6SX6SX6SX6SX6SCPU1 CAVITY BOT DECOUPLING CAPS 1/3
2
1 C2350
2
1 C2402
2
1 C2397
2
1 C2392
2
1 C2386
2
1 C2380
2
1 C2374
2
1 C2368
2
1 C2362
2
1 C2403
2
1 C2404
2
1 C2405
2
1 C2398
2
1 C2399
2
1 C2393
2
1 C2394
2
1 C2400
2
1 C2395
2
1 C2387
2
1 C2388
2
1 C2381
2
1 C2375
2
1 C2382
2
1 C2389
2
1 C2383
2
1 C2377
2
1 C2376
2
1 C2369
2
1 C2370
2
1 C2363
2
1 C2364
2
1 C2371
2
1 C2365
2
1 C2378
2
1 C2372
2
1 C2366
2
1 C2356
2
1 C2345
2
1 C2340
2
1 C2335
2
1 C2330
2
1 C2324
2
1 C2318
2
1 C2312
2
1 C2357
2
1 C2358
2
1 C2351
2
1 C2352
2
1 C2359
2
1 C2353
2
1 C2346
2
1 C2347
2
1 C2341
2
1 C2342
2
1 C2348
2
1 C2343
2
1 C2360
2
1 C2354
2
1 C2336
2
1 C2337
2
1 C2331
2
1 C2332
2
1 C2338
2
1 C2333
2
1 C2325
2
1 C2319
2
1 C2326
2
1 C2320
2
1 C2313
2
1 C2314
2
1 C2327
2
1 C2321
2
1 C2315
2
1 C2322
2
1 C2316
2
1 C2306
2
1 C2300
2
1 C2294
2
1 C2307
2
1 C2308
2
1 C2301
2
1 C2302
2
1 C2309
2
1 C2303
2
1 C2295
2
1 C2296
2
1 C2297
2
1 C2310
2
1 C2304
2
1 C2298
SHEETDATE
DEPARTMENT
SIZE
PROJECT DOCUMENT NUMBER REV
REVIEWER
DESIGNER
123
7 3 2 1 6 5 4
E
A
B
C
E
D
C
B
A
7 6 5 4
D
C



PVDDIO_P1: 24PCS 22UF ON BOT1010101010PVDD11_S3_P1: 42PCS 22UF ON BOT55101010105555101010
55555555
PVDDCR_SOC_P1: 77PCS 22UF ON BOT
Thu Sep 14 16:12:04 2023<NAME_2><NAME_1>MB FABCGT AMDV0274 OF 365
PVDD11_S3_P1PVDD11_S3_P1PVDD11_S3_P1PVDD11_S3_P1PVDD11_S3_P1
PVDDCR_SOC_P1PVDDCR_SOC_P1PVDDCR_SOC_P1PVDDCR_SOC_P1PVDDCR_SOC_P1PVDDCR_SOC_P1PVDDIO_P1PVDDIO_P1PVDDIO_P1PVDDCR_SOC_P1PVDDCR_SOC_P1C0402C0402C0402C0402C0402C0402C0402C0402C0402C0402C0402C0402C0402C0402C0402
C0402C0402C0402C0402C0402C0402C0402C0402
C0402C0402C0402C0402C0402C0402C0402C0402C0402
C0402
C0402C0402C0402C0402C0402C0402C0402C0402C0402C0402C0402C0402C0402C0402C0402C0402C0402C0402C0402C0402C0402C0402C0402C0402C0402C0402C0402C0402C0402 C0402C0402C0402C0402C0402C0402C0402C0402C0402C0402C0402C0402C0402 C0402 C0402 C0402C0402C0402C0402C0402C0402C0402C0402C0402C0402C0402C0402C0402C0402
C0402C0402C0402C0402C0402C0402C0402C0402C0402C0402C0402C0402C0402C0402C0402C0402C0402C0402C0402C0402C0402C0402C0402C0402C0402C0402C0402C0402C0402C0402C0402C0402C0402C0402C0402C0402C0402C0402C0402C0402C0402C0402C0402C0402C0402C0402C0402C0402C0402C0402C0402C04024V4V4V4V4V4V4V4V4V4V4V4V4V4V4V
4V4V4V4V4V4V4V4V
4V4V4V4V4V4V4V4V4V
4V
4V4V4V4V4V4V4V4V4V4V4V4V4V4V4V4V4V4V4V4V4V4V4V4V4V4V4V4V4V 4V4V4V4V4V4V4V4V4V4V4V4V4V4V 4V 4V4V4V 4V4V4V4V4V4V4V4V 4V4V4V
4V4V4V4V4V4V4V4V4V4V4V4V4V4V4V4V4V4V4V4V4V4V4V4V4V4V4V4V4V4V4V4V4V4V4V4V4V4V4V4V4V 4V4V4V4V4V4V4V4V4V4V4V22UF22UF22UF22UF22UF22UF22UF22UF22UF22UF22UF22UF22UF22UF22UF
22UF22UF22UF22UF22UF22UF22UF22UF
22UF22UF22UF22UF22UF22UF22UF22UF22UF
22UF
22UF22UF22UF22UF22UF22UF22UF22UF22UF22UF22UF22UF22UF22UF22UF22UF22UF22UF22UF22UF22UF22UF22UF22UF22UF22UF22UF22UF22UF 22UF22UF22UF22UF22UF22UF22UF22UF22UF22UF22UF22UF22UF 22UF 22UF 22UF22UF22UF22UF22UF22UF22UF22UF22UF22UF22UF22UF22UF22UF
22UF22UF22UF22UF22UF22UF22UF22UF22UF22UF22UF22UF22UF22UF22UF22UF22UF22UF22UF22UF22UF22UF22UF22UF22UF22UF22UF22UF22UF22UF22UF22UF22UF22UF22UF22UF22UF22UF22UF22UF22UF22UF22UF22UF22UF22UF22UF22UF22UF22UF22UF22UF20%20%20%20%20%20%20%20%20%20%20%20%20%20%20%
20%20%20%20%20%20%20%20%
20%20%20%20%20%20%20%20%20%
20%
20%20%20%20%20%20%20%20%20%20%20%20%20%20%20%20%20%20%20%20%20%20%20%20%20%20%20%20%20% 20%20%20%20%20%20%20%20%20%20%20%20%20% 20% 20% 20%20%20%20%20%20%20%20%20%20%20% 20%20%20%
20%20%20%20%20%20%20%20%20%20%20%20%20%20%20%20%20%20%20%20%20%20%20%20%20%20%20%20%20%20%20%20%20%20%20%20%20%20%20%20%20%20%20%20%20%20%20%20%20%20%20%20%X6SX6SX6SX6SX6SX6SX6SX6SX6SX6SX6SX6SX6SX6SX6S
X6SX6SX6SX6SX6SX6SX6SX6S
X6SX6SX6SX6SX6SX6SX6SX6SX6S
X6S
X6SX6SX6SX6SX6SX6SX6SX6SX6SX6SX6SX6SX6SX6SX6SX6SX6SX6SX6SX6SX6SX6SX6SX6SX6SX6SX6SX6SX6S X6SX6SX6SX6SX6SX6SX6SX6SX6SX6SX6SX6SX6S X6S X6S X6SX6SX6S X6SX6SX6SX6SX6SX6SX6SX6S X6SX6SX6S
X6SX6SX6SX6SX6SX6SX6SX6SX6SX6SX6SX6SX6SX6SX6SX6SX6SX6SX6SX6SX6SX6SX6SX6SX6SX6SX6SX6SX6SX6SX6SX6SX6SX6SX6SX6SX6SX6SX6SX6SX6S X6SX6SX6SX6SX6SX6SX6SX6SX6SX6SX6SCPU1 CAVITY BOT DECOUPLING CAPS 2/3
2
1 C2428
2
1 C2435
2
1 C2442
2
1 C2127
2
1 C2509
2
1 C2122
2
1 C2123
2
1 C2128
2
1 C2124
2
1 C2510
2
1 C2511
2
1 C2125
2
1 C2126
2
1 C3922
2
1 C3921
2
1 C2116
2
1 C2117
2
1 C2507
2
1 C2110
2
1 C2112
2
1 C2111
2
1 C2109
2
1 C2498
2
1 C2493
2
1 C2107
2
1 C2108
2
1 C2104
2
1 C2105
2
1 C2102
2
1 C2484
2
1 C2106
2
1 C2103
2
1 C2477
2
1 C2478
2
1 C2470
2
1 C2471
2
1 C24792
1 C2472
2
1 C2118
2
1 C2508
2
1 C2503
2
1 C2119
2
1 C2120
2
1 C2114
2
1 C2113
2
1 C2504
2
1 C2505
2
1 C2499
2
1 C2494
2
1 C2500
2
1 C2501
2
1 C2495
2
1 C2496
2
1 C2121
2
1 C2115
2
1 C2506
2
1 C2502
2
1 C2497
2
1 C2489
2
1 C2485
2
1 C2490
2
1 C2491
2
1 C2486
2
1 C2487
2
1 C2480
2
1 C2473
2
1 C2474
2
1 C2481
2
1 C2482
2
1 C2475
2
1 C2492
2
1 C2488
2
1 C3920
2
1 C2483
2
1 C2476
2
1 C3919
2
1 C2463
2
1 C2464
2
1 C2456
2
1 C2457
2
1 C2465
2
1 C2458
2
1 C2451
2
1 C2450
2
1 C2449
2
1 C2443
2
1 C2436
2
1 C2444
2
1 C2437
2
1 C2429
2
1 C2421
2
1 C2422
2
1 C2430
2
1 C2423
2
1 C2414
2
1 C2415
2
1 C2407
2
1 C2408
2
1 C2416
2
1 C2409
2
1 C2466
2
1 C2467
2
1 C2459
2
1 C2460
2
1 C2468
2
1 C2461
2
1 C2454
2
1 C2453
2
1 C2452
2
1 C2445
2
1 C2446
2
1 C2438
2
1 C2439
2
1 C2447
2
1 C2440
2
1 C2469
2
1 C2462
2
1 C3918
2
1 C2455
2
1 C2448
2
1 C3917
2
1 C2441
2
1 C3916
2
1 C2431
2
1 C2432
2
1 C2424
2
1 C2425
2
1 C2433
2
1 C2426
2
1 C2417
2
1 C2418
2
1 C2410
2
1 C2411
2
1 C2419
2
1 C2412
2
1 C2434
2
1 C3915
2
1 C2427
2
1 C3914
2
1 C2420
2
1 C3913
2
1 C2413
2
1 C3912
SHEETDATE
DEPARTMENT
SIZE
PROJECT DOCUMENT NUMBER REV
REVIEWER
DESIGNER
123
7 3 2 1 6 5 4
E
A
B
C
E
D
C
B
A
7 6 5 4
D
C



510PVDD18_S5_P1: 12PCS 22UF ON BOTPVDD33_S5: 2PCS 22UF ON BOT
Thu Sep 14 16:12:04 2023<NAME_2><NAME_1>MB FABCGT AMDV0275 OF 365
PVDD_33_S5PVDD18_S5_P1PVDD18_S5_P1X6S6.3V10UF20%C0402X6S6.3V10UF20%C0402
CPU1 CAVITY BOT DECOUPLING CAPS 3/3X6SX6S X6S X6SX6S X6SX6S X6S X6SX6SX6SX6S20%20% 20% 20%20% 20%20% 20% 20%20%20%20%22UF22UF 22UF 22UF 22UF 22UF 22UF 22UF 22UF22UF22UF22UF4V4V 4V 4V 4V 4V4V 4V 4V4V4V4VC0402C0402 C0402 C0402 C0402 C0402 C0402 C0402 C0402C0402C0402C0402
2
1 C2673
2
1 C2672
2
1 C2671
2
1 C2670
2
1 C2669
2
1 C2668
2
1 C2667
2
1 C2665
2
1 C2663
2
1 C2664
2
1 C2660
2
1 C2661
C2659 C2662
2
1
2
1
SHEETDATE
DEPARTMENT
SIZE
PROJECT DOCUMENT NUMBER REV
REVIEWER
DESIGNER
123
7 3 2 1 6 5 4
E
A
B
C
E
D
C
B
A
7 6 5 4
D
C



UART_CPU0_SCM_UART1_TXCLK_CPU1_RTCCLK0: NORMAL MODE, 32KHZ XTAL AS SOURCEBYPASS RTC1: RTCCLK IS INPUT & USED AS BYPASS CLK1: TOP HALF 64MB ROM0: BOTTOM HALF 64MB ROMALTERNATE IMAGE01: SPI ROM(DEFAULT)1: INTERNAL CLKGEN MODE0: EXTERNAL CLKGEN MODECLKGEN SELECTIONCPU1 NET NAMESPI_CPU0_CLK0PD_ESPI_CPU1_CLK2000: RSVDROMTYPECPU0_ROM_TYPE_SELECT0RTCCLK1CPU0 NET NAMEPU/PD(DEFAULT)CPU0ESPI_CLK2||AGPIO74ESPI_CLK150K PDAGPIO109UART1_TXD||AGPIO142CPUX PIN NAME0DESCRIPTION1(DEFAULT)SPI_CPU1_CLK1X: ESPI0PDPD50K PU1
CPU1 STRAP
50K PD50K PUESPI_CLK0
CPU0 STRAP
INTERNALPD_ESPI_CPU0_CLK2RSVD0CLK_ESPI_CPU0_CLK1CLK_CPU0_RTCCLKCPU1Thu Sep 14 16:12:04 2023<NAME_2><NAME_1>MB FABCGT AMDV0276 OF 365
PVDD18_S5_P1PVDD18_S5_P056 7676 5676 5655 7629 768115076 2976 2827 76 16428 76 5529 76 7728 76 5576 2876 2929 76 7756 7629 768115027 76 16455 76SPI_CPU1_CLKPD_ESPI_CPU1_CLK2PD_ESPI_CPU1_CLK2CLK_CPU1_RTCCLKEMPTY
CPU HW STRAP PIN
EMPTY5%10KCLK_ESPI_CPU0_CLK1EMPTY5%10KPD_ESPI_CPU0_CLK2EMPTYCPU0_ROM_TYPE_SELECTEMPTY5%10KUART_CPU0_SCM_UART1_TXEMPTY5%10KCLK_CPU0_RTCCLK5%10KEMPTYEMPTY5%10K0402LF10K1/16WEMPTY5%10KSPI_CPU0_CLKCHIP5%CLK_CPU0_RTCCLK10K 5%CHIPCPU0_ROM_TYPE_SELECT5%CHIP10KPD_ESPI_CPU0_CLK210KCHIP5%SPI_CPU0_CLKCHIP5%10K5%10KCHIPSPI_CPU1_CLKCHIP5%10KCHIP1K 1%10KCLK_ESPI_CPU0_CLK1CHIP1%30KUART_CPU0_SCM_UART1_TX5%10K5%CLK_CPU1_RTCCLK
21R6098
21R743
21R1502
21R760
21R754
21R1501
21R736
21
R730
21R753
21R750
21R742
21R739
21R740
21R737
21R729
21R751
21R748
21R747
SHEETDATE
DEPARTMENT
SIZE
PROJECT DOCUMENT NUMBER REV
REVIEWER
DESIGNER
123
7 3 2 1 6 5 4
E
A
B
C
E
D
C
B
A
7 6 5 4
D
OUT
OUT
OUT
OUT
OUT
OUT
OUT
OUT
OUT
OUT
OUT
OUT
OUT
OUT
OUT
OUT
OUT
OUT
C



CPU0 QSPI0 TO SCM QSPI0
Thu Sep 14 16:12:04 2023<NAME_2><NAME_1>MB FABCGT AMDV0277 OF 365
PVDD18_S5_P0PVDD18_S5_P0PVDD18_S5_P0P3V3_AUXP3V3_AUXP3V3_AUXPVDD18_S5_P077 1507729 7729 7729 7729 7729 7729 77817729 7777150771507729772977297729767715077150771507715077150
77 15077 15077 15077 15077 15077 1508177812977297729772977SPI_CPU0_LVC3_TPM_CS_NSPI_CPU0_LVC3_SCM_CS1_N1/16WEMPTY10%25VSMLF040225VICSPI_CPU0_D3SPI_CPU0_D2SPI_CPU0_D110%X7RSPI_CPU0_CS1_NSPI_CPU0_TPM_CS_NSPI_CPU0_CS0_N0402X7RX7R10K1%CHIPROM_LS_ENSPI_CPU0_D0
CPU SPI LEVEL SHIFTX7R0.1UF25V10%SPI_CPU0_LVC3_SCM_D3SPI_CPU0_LVC3_TPM_CS_NSPI_CPU0_LVC3_SCM_CS1_NSPI_CPU0_CS1_N0.1UFSPI_CPU0_TPM_CS_NSPI_CPU0_CS0_NSPI_CPU0_CLK0.1UFSPI_CPU0_LVC3_SCM_D2SPI_CPU0_LVC3_SCM_D1SPI_CPU0_LVC3_SCM_D0SPI_CPU0_LVC3_SCM_CLKSPI_CPU0_LVC3_SCM_CS0_N
SPI_CPU0_LVC3_SCM_D133.2SPI_CPU0_LVC3_SCM_D010%25V49.9
4.7K5%1/16WCHIP4.7K5%CHIP
0SPI_CPU0_LVC3_SCM_D30SPI_CPU0_LVC3_CS0_NSPI_CPU0_LVC3_SCM_CS0_NSPI_CPU0_LVC3_CS1_N0SPI_CPU0_LVC3_SCM_D2
EMPTY1K1%EMPTY1K1%EMPTY1K1/16W1%1K1%EMPTY1/16W1K1%1KEMPTY1/16W1% EMPTY1K1%EMPTY1K1%EMPTY1K1%1KEMPTY1%1K1/16WCHIP1%1KCHIP1/16W1%1K1/16WCHIP1%SPI_CPU0_LVC3_CLKSPI_CPU0_LVC3_SCM_CLK0.1UF0402SPI_CPU0_LVC3_D1SPI_CPU0_LVC3_D0SPI_CPU0_LVC3_D2SPI_CPU0_LVC3_D3PI4ULS3V304AZMAEXICROM_SD_LS_OESMLF5%1/16W330402LF3333SPI_CPU0_R1_D1SPI_CPU0_R1_D3SPI_CPU0_R1_D2SPI_CPU0_R1_D033ROM_LS_ENCHIPSPI_CPU0_D1SPI_CPU0_D0SPI_CPU0_D2SPI_CPU0_D30SN74AVC4T774PWR33SPI_CPU0_LVC3_R_TPM_CS_N330402
U54
R608
21 R602
21 R603
21 R604
21 R605
21 R607
21 R606
R1655
21 R600
2
1
R1529
2
1
R1530
2
1
R1531
2
1
R1532
2
1
R129
2
1
R128
2
1
R127
2
1
R21
2
1
R20
2
1
R601
2
1
R659
2
1
R811
2
1
R610
2
1C1103
2
1 C1105
2
1C1102
2
1 C1104
R1547
U53
R1567
111
612
7
8
9
10
5
4
3
2
1516
9
10
8
7
2
1
11
12
13
14
6
5
4
3
GND
B4
B3
B2
B1
VCCA
A4
EN
VCCB
A3
A2
A1
VCCA VCCB
B1
B2
B3
B4
GND
OE
DIR4
DIR3
A4
A3
A2
A1
DIR2
DIR1
21
21R8008
21R8007
21R8006
21R8005
2
1
2
1
2
1
SHEETDATE
DEPARTMENT
SIZE
PROJECT DOCUMENT NUMBER REV
REVIEWER
DESIGNER
123
7 3 2 1 6 5 4
E
A
B
C
E
D
C
B
A
7 6 5 4
D
OUT
BIBIBIBI
ININ OUTOUT
BIBI
BIBI
OUT
IN
IN OUTOUTIN
OUT
OUT
IN
OUTOUTOUTOUTOUTOUTOUT
BIBI
OUTOUT
OUT
C



PWROK TO VR RSTVID:VDDCR_CPU*/VDDCR_SOC/VDDIO
Thu Sep 14 16:12:05 2023<NAME_2><NAME_1>MB FABCGT AMDV0278 OF 365
P1V8_AUXP1V8_AUX558185288185200193210217PWRGD_CPU1_PWROK1/16WEMPTY5%10K0402LFPWRGD_CPU0_PWROK1/16WEMPTY5%10K0402LFPVDDCR_CPU1_P0_RESET_NPVDDCR_CPU0_P0_RESET_N0.1UF25V0402SMLF0402SMLF25VSN74LVC2G07DCKR0.1UFSN74LVC2G07DCKR10%10%ICX7RICX7RPVDDCR_CPU0_P1_RESET_NPVDDCR_CPU1_P1_RESET_NCPU PWROK
52
43
61
U40 2
1
C224
52
43
61
U29 2
1
C223
2
1
R703
2
1
R702
VCCGND
2Y
1Y
2A
1A
VCCGND
2Y
1Y
2A
1A
SHEETDATE
DEPARTMENT
SIZE
PROJECT DOCUMENT NUMBER REV
REVIEWER
DESIGNER
123
7 3 2 1 6 5 4
E
A
B
C
E
D
C
B
A
7 6 5 4
D
IN
IN
OUT
OUT
OUT
OUT
C



Thu Aug 24 10:14:00 2023<NAME_2><NAME_1>MB FABCGT AMDV0279 OF 365Blank
SHEETDATE
DEPARTMENT
SIZE
PROJECT DOCUMENT NUMBER REV
REVIEWER
DESIGNER
123
7 3 2 1 6 5 4
E
A
B
C
E
D
C
B
A
7 6 5 4
D
C



BANK0 P3V3_AUX
TBCTBCTBC
Thu Sep 14 16:12:38 2023<NAME_2><NAME_1>MB FABCGT AMDV0280 OF 365
FM_BOARD_BMC_SKU_ID1150151142142150150257193150257257210257257132 139 241246251253234150151151361137137151151137137150151150125125246142362140263 268188150249159831592541501511711598315915115015115015015115015115984848313313915223483159159831591711458314582 137 1388385 17185 1711508385 17185 17117224115115183 15085150151841501512698313413524826926326834348484145831341351361511508513613713113113113114415015121033333333330000000 00000CHIPEMPTY033333333333333333333333333333333
00 10000CLK_GEN2_BMC_RC_OE_R_NP1V8_RETIMER_CPU1_R_ENSGPIO_SCM_CLK_<1>FM_OCP_V3_2_AUX_PWR_R_ENFM_OCP_V3_2_AUX_PWR_ENOCP_V3_2_P3V3_PLD_R_PWRGDCLK_GEN2_GPU_FPGA_OE_R_NFM_SOL_UART_CH_SELFM_UARTSW_LSB_NFM_LED_PWRGD_PVDD18_S5_P1PVDDCR_CPU0_P0_ENFPGA_IO3V3_RSVD_1FM_LED_PWRGD_PVDDCR_CPU1_P1FM_LED_PWRGD_PVDD11_S3_P1PWRGD_PVDDCR_SOC_P1FM_LED_PWRGD_PVDDCR_SOC_P1FM_LED_PWRGD_PVDDIO_P1RST_SMB_SWITCH_NCLK_GEN2_BMC_RC_OE_NSMB_1_PLD_3V3AUX_SDA_R2PRSNT_CABLE_GPU_B3_ISO_R_NFM_UARTSW_MSB_NSMB_2_PLD_3V3AUX_SCL_R1SMB_2_PLD_3V3AUX_SDA_R1P1V8_RETIMER_CPU0_ENP1V8_RETIMER_CPU0_R_ENSGPIO_OCP_V3_2_LD_NSGPIO_OCP_V3_2_CLKSCM_SPARE_0SCM_SPARE_1SGPIO_OCP_V3_2_DATAOUTSGPIO_OCP_V3_2_DATAINRST_MB_STBY_NSCM_ROT_CPU_RST_R_NGPU_3V3IO_RSVD3_FFU_ISOPRSNT_CABLE_GPU_B3_ISO_NP12V_OCP_V3_2_PLD_PWRGDP1V8_RETIMER_CPU1_ENHP_LVC3_OCP_V3_2_PRSNT2_PLD_NIRQ_SML1_PMBUS_ALERT_NPWRGD_P5V_R2RST_SRST_PLD_BMC_NRST_SRST_PLD_BMC_R_NPRSNT_OCP_V3_2_NPWRGD_P5VSCM_SYS_PWROKSMB_BMC_SWB_ENSMB_2_PLD_3V3AUX_SCL_R2FM_I3C_CPU0_MUX1_SELFM_I3C_CPU1_MUX0_OE_NPWRGD_PS_PWROK_PLD_ISO_RFM_UV_ADR_TRIGGER_R_NFM_I3C_CPU0_MUX0_OE_R_NFM_I3C_CPU1_MUX0_R_SELFM_I3C_CPU1_MUX1_OE_R_NFM_I3C_CPU0_MUX1_R_SELSCM_JTAG_MUX_R_S1FM_I3C_CPU0_MUX1_OE_R_NSCM_JTAG_MUX_R_S0SGPIO_SCM_DI_R<0>SGPIO_SCM_INTR_R_NFM_I3C_CPU1_MUX1_R_SELSGPIO_SCM_LD_<1>SCM_JTAG_MUX_S1FM_I3C_CPU0_MUX0_SELFM_I3C_CPU0_MUX1_OE_NSGPIO_SCM_DI_<0>SGPIO_SCM_INTR_NSGPIO_SCM_DO_<1>SGPIO_SCM_RESET_NFM_I3C_CPU1_MUX1_SELFM_BOARD_BMC_SKU_ID3FM_BOARD_BMC_SKU_ID4FM_SYS_THROTTLE_NFM_I3C_CPU0_MUX0_R_SEL
VIRTUAL_RESEAT_FPGA_R_N VIRTUAL_RESEAT_FPGA_NCLK_GEN2_GPU_FPGA_OE_NFM_I3C_CPU0_MUX0_OE_NFM_I3C_CPU1_MUX0_SELFM_I3C_CPU1_MUX1_OE_NFM_I3C_CPU1_MUX0_OE_R_NSCM_JTAG_MUX_S0E1S_0_PERST1_CLKREQ_NE1S_0_PRSNT_NFM_OCP_V3_2_PWR_GOODCPLD_JTAG_ENJTAG_SCM_PLD_TDOJTAG_SCM_PLD_TDILCMXO3LF-9400C-5BG484CICSMLF
IC
FPGA 1/6VIRTUAL_RESEATCPLD_PROGRAMNJTAG_SCM_PLD_TMSJTAG_SCM_PLD_TCK
LCMXO3LF-9400C-5BG484CSMLFJTAG_SCM_TRST_N JTAG_SCM_TRST_R_N33.2FM_FAN_PWR_EN33.2SMB_1_PLD_3V3AUX_SCL_R1SMB_1_PLD_3V3AUX_SDA_R1SCM_SYS_PWRBTN_NHP_LVC3_OCP_V3_2_P12V_PWRGD_RGPU_3V3IO_RSVD3_FFU_ISO_RSMB_2_PLD_3V3AUX_SDA_R2SMB_1_PLD_3V3AUX_SCL_R2SCM_SYS_PWROK_RSGPIO_SCM_CLK_<0>FM_BOARD_BMC_SKU_ID0SGPIO_SCM_DO_<0>FM_UV_ADR_TRIGGER_NSGPIO_SCM_DI_R<1>SMB_CPU0_4_XLTR_R_SDAFM_SYS_THROTTLE_R_NSMB_CPU0_4_XLTR_R_SCLOC_ALERT_NUV_ALERT_NIRQ_HSC_FAULT_BUF_R_NP3V3_OCP_SFF_EN_RIRQ_UV_DETECT_NHSC_D_OCSMB_CPU0_4_XLTR_SDASMB_CPU0_4_XLTR_SCLFM_BOARD_BMC_SKU_ID2FM_LED_ACTIVE_E1S_0P3V3_OCP_SFF_ENP12V_OCP_SFF_EN_RP12V_OCP_SFF_ENSGPIO_SCM_DI_<1>IRQ_HSC_FAULT_BUF_NE1S_0_PERST1_CLKREQ_R_NOCP_V3_1_P3V3_PLD_R_PWRGDOCP_V3_2_MAIN_PWR_ENSGPIO_OCP_SFF_CLKSGPIO_OCP_SFF_DATAOUTSGPIO_OCP_SFF_DATAINSGPIO_OCP_SFF_LD_NPCIE_M2_SSD0_PRSNT_NSGPIO_SCM_LD_<0>0PVDDCR_SOC_P1_EN
R1179
R152
R6851
R6850
R419
R407
2 1R6117
2 1
R6116
2 1
R6094
2 1R6096
2 1R6095
2 1R51
R6029
R6031
2 1R56
2 1R210
2 1R211
2 1R63
R6030
2 1R163
2 1R170
2 1R171
2 1R166
2 1R164
2 1R50
2 1R169
2 1R165
2 1R49
2 1R167
2 1R58
2 1R172
2 1R168
2 1R23
2 1R6038
2 1R6039
2 1R70
2 1R493
2 1R992
2 1R160
21R4146
21R4145
21R439
B22
A21
C20
C19
B21
A20
G15
F15
B20
A19
D18
C18
B19
A18
D17
E16
B18
A17
D16
C17
B17
A16
D15
C15
B15
A15
F14
G14
D14
C14
B14
A14
D13
C13
B13
A13
F13
E13
F12
G12
A12
B12
E12
D12
D11
E11
A11
B11
F11
G11
A10
B10
E10
F10
G9
F9
A9
B9
D9
C9
A8
B8
D8
C8
D7
C6
A7
B6
E7
D6
A6
B5
C5
D5
A5
B4
G8
F8
A4
B3
C4
C3
A3
B2
F7
E6
A2
B1
E17
F16
E15
E14
C10
D10
E9
E8
U18
U18
3/7
BANK 0
PT43D
PT43C
PT42D
PT42C
PT42B
PT42A
PT41D
PT41C
PT40D
PT40C
PT40B
PT40A
PT39D
PT39C
PT39B
PT39A
PT38D
PT38C
PT38B
PT38A
PT30D
PT30C
PT30B
PT30A
PT29D
PT29C
PT29B
PT29A
PT28D
PT28C
PT27B
PT27A
PT24D
PT24C
PT24B
PT24A
PT23D
PT23C
PT21D
PT21C
PT21B
PT21A
PT20D
PT20C
PT20B
PT20A
PT14D
PT14C
PT14B
PT14A
PT13D
PT13C
PT13B
PT13A
PT12D
PT12C
PT12B
PT12A
PT10D
PT10C
PT10B
PT10A
PT11D
PT11C
PT22B
PT22A
PT11B
PT11A
PT15A
PT9A||L_GPLLT
PT9C
PT9B||L_GPLLC
PT9D
PT15B
PT23A||PCLKT0_1
PT23B||PCLKC0_1
PT44A||R_GPLLT
PT44B||R_GPLLC
PT27C||SCL||PCLKT0_0
PT27D||SDA||PCLKC0_0
PT28A
PT28B
PT31A
PT31B
PT41A
PT41B
PT43A||R_GPLLT
PT43B||R_GPLLC
4/7
BANK 0
PT31C||JTAGENB
PT44D||DONE
PT44C||INITN
PT31D||PROGRAMN
PT22D||TMS
PT22C||TCK
PT15D||TDI
PT15C||TDO
2 1
2 1
2 1
2 1
2 1
2 1
2 1
2 1
2 1
SHEETDATE
DEPARTMENT
SIZE
PROJECT DOCUMENT NUMBER REV
REVIEWER
DESIGNER
123
7 3 2 1 6 5 4
E
A
B
C
E
D
C
B
A
7 6 5 4
D
IN
OUTININBI
OUT
OUT
BIIN
ININ
OUT
OUT
OUT
OUT
IN
OUT
IN
OUT
IN
IN
IN
OUTOUT
OUTIN
OUTIN
ININ
OUT
IN
ININ
OUT
IN
OUTOUT
OUT
IN
OUT
OUTOUT
OUT
OUTOUT
OUTINOUT
IN
BI
IN
IN
OUT
IN
OUT
OUT
IN
OUT
OUT
IN
IN
OUT
IN
IN
ININ
ININ
IN
BI
OUT
IN
ININ
OUT
IN
OUTOUT
OUTOUT
ININ
ININ
IN
IN
OUT
OUTOUTOUTIN
OUTOUTOUT
IN
OUT
C



BANK1 P1V8_AUX
BANK2 P3V3_AUXTBC
Thu Sep 14 16:12:34 2023<NAME_2><NAME_1>MB FABCGT AMDV0281 OF 365P3V3_AUX3632562562562428585 83 1401412488314014114213812812712713421716412324683193207152129200200210831461478385146147 18836519219085270 12783 144127127
2855555536336532132155835528 15128855553543542772772883322885558528167558578835427129130 12512524612512524612512612612612612612624612612583 14534383545483291732878855522428 282855
24312712712883 8583 17214213683 8518883146147132271255 12412412412412415021728257210128185 1861845516720734383278327 2883 1531672816529 1501662915029 1505517229 15029 1502976150151188260166310771677716717417383 2929928174843103417215329150167172
3621292261921301302242242261673611672755299
270148255271209209217242146147
282828832825555833322883
256 127P0V9_RETIMER_CPU0_ENFM_LED_PWRGD_PVDD33_S5FM_LED_PWRGD_PVDD18_S5_P0FM_LED_PWRGD_PVDD11_S3_P0HPDB_HSC_PWRGD_ISOP3V3_E1S_0_EN_RHPDB_HSC_PWRGD_ISO_RP12V_E1S_0_ENBMC_FPGA_LED1P0V9_RETIMER_CPU0_EN_R2BMC_FPGA_LED2FM_PLD_OCP_SFF_PWR_GOOD_RP12V_E1S_0_PWRGDFM_GPU_HSC_EN_RFM_PWRGD_PVDDIO_P1FM_PVDDIO_P1_ENFM_CPU0_PWR_GOODFM_PVDD33_S5_ENFM_FPGA_DEBUG_SW_SPAREGPU_FPGA_RST_NFM_GPU_PWR_ENP12V_SCM_PWRGD_RFM_PWRGD_PVDDCR_CPU0_P1GPU_FPGA_EROT_RECOV_R_NFM_PWRGD_PVDDCR_CPU1_P1PRSNT_SWB_ISO_R_NGPU_FPGA_EROT_RST_R_NFM_PVDDCR_CPU0_P1_R_ENFM_PWRGD_PVDD11_S3_P033.2000 00000000 0000100003333333333
3333333333333333333333
33333333333333333333333333333333333333333333
33333333EMPTY00
00
000000000000
0
000000000 3333000 00000000333333CHIPCHIPCHIP1%33.233.2PU_SPI_PLD_CS_NP3V3_OCP_V3_2_EN_RP12V_OCP_V3_2_EN_RFM_NCSI_OCP_V3_2_R_OEGPU_FPGA_BOOT_ENP0V9_RETIMER_CPU1_EN_R2FM_SMB_2_ALERT_GPU_ISO_NGPU_FPGA_READY_ISOHP_LVC3_OCP_SFF_PRSNT2_PLD_NPWRGD_PVDDCR_CPU1_P1UART_LS_ENPRSNT_SWB_ISO_NPVDDCR_CPU0_P0_PMALERTPWRGD_PVDD11_S3_P0HP_LVC3_SCM_HSC_PWRGDGPU_FPGA_EROT_RST_NPVDDIO_P0_ENPWRGD_PVDDIO_P0PVDDCR_CPU0_P1_EN1%1%GPU_BASE_STBY_EN_RE1S_0_P3V3_ENRST_PERST_CPU1_SWB_1_NP3V3_E1S_PWRGD_0_RFM_SMB_2_ALERT_GPU_ISO_R_NFM_P5V_EN33.21%33.233.2GPU_FPGA_EROT_FATALERR_ISO_R_NGPU_3V3IO_RSVD1_FFU_ISO_RGPU_3V3IO_RSVD0_FFU_ISO_R33.233.21%1%1%CHIPCHIPCHIPCHIPCHIPCHIPCHIPCHIPCHIPP0V9_RETIMER_CPU1_ENPRSNT_CABLE_GPU_A2_ISO_R_NPVDD33_S5_ENPWRGD_P3V3_AUXFM_SWB_PWRGD_ISORST_PERST_M2_0_NFM_SMB_1_ALERT_GPU_ISO_NFM_SWB_BIC_READY_ISO_NFM_UART_LS_ENCHIP1%PVDD18_S5_P1_R_ENFM_PWRGD_PVDD11_S3_P1FM_PVDD11_S3_P1_ENGPU_3V3IO_RSVD5_FFU_ISO_RPRSNT_CABLE_GPU_A1_ISO_R_N33.233.233.233.233.233.233.233.233.2
PWRGD_P0V9_RETIMER_CPU1_R2FM_CPU0_RSMRST_NFM_CPU1_RSMRST_NRST_CPU1_PERST0_R_NPWRGD_P0V9_RETIMER_CPU0_R2RST_RT_CPU1_P0_RESET_R2_NRST_RT_CPU1_P0_PERST_R2_NTP_SLOT1_CLKREQ_0_R_NRST_CPU0_SYS_NRST_CPU1_SYS_NFM_CPU1_SLP_S5_NFM_CPU1_SLP_S3_NPWRGD_P0V9_RETIMER_CPU0PWRGD_P0V9_RETIMER_CPU1RST_RT_CPU1_P0_PERST_R_NRST_RT_CPU1_P0_RESET_R_NRST_CPU1_PERST0_NRST_CPU1_RSMRST_NCPU0_NV_SAVE_NRST_CPU0_PERST1_R_NRST_CPU1_PERST1_R_NRST_CPU0_PERST0_R_NLCMXO3LF-9400C-5BG484CP12V_ALL_PWROK_RCPU0_SPD_HOST_CTRL_R1_NFM_ROM_LS_EN33RST_RT_CPU0_P1_RESET_R2_NRST_RT_CPU1_P3_PERST_R2_NSMB_CPU_5_R1_SCLRST_RT_CPU0_P1_RESET_R_NRST_RT_CPU1_P3_RESET_R2_NRST_SMB_RT_ROM_R2_NTP_FM_CLK_BUFFER_EN_RCPU1_PWRGD_OUTCPU1_SPD_HOST_CTRL_NRST_RT_CPU1_P3_PERST_R_NRST_RT_CPU1_P3_RESET_R_NRST_RT_CPU0_P0_PERST_R_NRST_RT_CPU0_P0_RESET_R_NRST_RT_CPU0_P1_PERST_R_NFM_P0_PCC0_R_NFM_P0_PCC1_R_NRST_RT_CPU1_P2_RESET_R2_NRST_RT_CPU1_P1_RESET_R_NRST_CPU0_RESETL_NRST_CPU1_RESETL_N33CPU0_NMI_SYNC_FLOOD_NFPGA_DEBUG_LED_CTRLPWRGD_CPU1_PWROKFM_P1_PCC1_NAPML_CPU0_ALERT_R_NGPU_NVS_PWR_BRAKE_NBMC_MONITER_RGPU_BASE_HMC_READY_ISO_RGPU_FPGA_THERM_OVERT_ISO_R_N1%SWB_HSC_PWRGD_ISOPRSNT_CABLE_GPU_A1_ISO_NGPU_3V3IO_RSVD5_FFU_ISOPRSNT_CABLE_GPU_A2_ISO_NGPU_3V3IO_RSVD1_FFU_ISOGPU_FPGA_OVERT_ISO_R_N1%CHIP1%CHIPCHIP1%GPU_FPGA_THERM_OVERT_ISO_NGPU_BASE_HMC_READY_ISOGPU_HMC_PRSNT_ISO_NGPU_FPGA_OVERT_ISO_NGPU_WP_HW_CTRL_NGPU_PRSNT_N_ISOGPU_FPGA_EROT_FATALERR_ISO_NCHIP1%1%33.233.2SWB_HSC_PWRGD_ISO_R1%33.2GPU_3V3IO_RSVD0_FFU_ISORST_PERST_E1S_0_N1%33.2CHIPCHIP1%33.21%RST_RT_CPU1_P2_PERST_R_NTP_SLOT2_CLKREQ_0_R_NFM_P1_PCC0_NAPML_CPU1_ALERT_R_NFM_FPGA_DEBUG_LED_CTRLRST_CPU0_KBRST_R_NCPU0_JTAG_BUF_OEPWRGD_CPU0_PWROKCPU1_NV_SAVE_NPVDD11_S3_P1_RESET_NCPU0_PWR_BTN_NRST_CPU0_KBRST_NFM_P1_PCC1_R_NCPU0_FORCE_SELFREFRESHCPU1_PWR_GD_IN
FM_AC_PWR_BTN_PLD_ISO_N0402LF1%RST_BMC_FROM_SWB_ISO_NBIC_MONITER_ISOGPU_BASE_STBY_ENSWB_HSC_EN_RRST_PERST_CPU0_SWB_N1%PRSNT_HDT_NRST_PERST_OCP_V3_2_NRST_PERST_OCP_SFF_NFM_GPU_PWRGD_ISO_RRST_PERST_M2_0_R_NRST_PERST_CPU1_SWB_NGPU_3V3IO_RSVD4_ISO_RGPU_HMC_PRSNT_ISO_R_NRST_BMC_FROM_SWB_ISO_R_NFM_SMB_1_ALERT_GPU_ISO_R_NFM_SWB_BIC_READY_ISO_R_NBIC_MONITER_ISO_RGPU_PRSNT_N_ISO_RFM_RST_PERST_SCM_R_N33.21%SW_P3V3_ENCHIPE1S_0_P12V_ENFM_NCSI_OCP_SFF_R_OEPWRGD_P1V2_AUX_R33.233.21%33.21%1%CHIPCHIP1%33.21%1%FPGA 2/6
ICSMLF
1%33.233.21%33.210K1%CHIP1/16W1%33.233.2FM_CPU1_PWR_GD_INSWB_HSC_ENCHIPGPU_3V3IO_RSVD4_ISOGPU_3V3IO_RSVD3_ISOGPU_3V3IO_RSVD1_ISOHGX_DETECT_NFM_RST_PERST_SCM_N1%CHIPCHIPCHIP1%PVDDIO_P1_ENCPU0_PWR_GOODGPU_FPGA_BOOT_EN_RFM_SWB_PWRGD_ISO_RHGX_DETECT_N_RGPU_FPGA_READY_ISO_RICSMLFFM_LED_PWRGD_PVDDCR_CPU0_P11%CHIP1%33.2CHIPGPU_NVS_PWR_BRAKE_R_NCHIP1%PWRGD_PVDDCR_CPU0_P1FM_SWB_PWR_EN_RFM_PVDDIO_P0_EN33.2FM_SWB_PWR_ENRST_SMB_RT_ROM_R1_NRST_SMB_RT_R1_NCPU1_FORCE_SELFREFRESHFM_FORCE_ALL_PWRONPVDD11_S3_P0_RESET_NRST_RT_CPU1_P2_PERST_R2_NRST_RT_CPU1_P2_RESET_R_NFM_P0_PCC1_NFM_P0_PCC0_N3333FM_SMERR_LED_R_NFM_CPU0_SMERR_N CPU0_SMERR_NFM_ESPI_CPU0_ALERT_R_SELBIOS_DEBUG_MODEESPI_CPU0_D0RST_ESPI_CPU0_RSTOUT_R_NFM_SMERR_LED_NBIOS_DEBUG_MODE_RESPI_CPU0_R1_D1RST_ESPI_CPU0_RSTOUT_NESPI_CPU0_D1FM_PLD_CPU1_PRSNT_HDTCPU1_JTAG_BUF_R_OEBMC_JTAG_SEL_RSCM_IRQ_1V8_R_NSCM_USB_OC_R_NCPU1_NMI_SYNC_FLOOD_NHDT_HDR_PWROKESPI_CPU0_D3ESPI_CPU0_D2CLK_ESPI_CPU0_CLK1SMB_CPU_5_R1_SDAPWRGD_P3V3_R2FM_CPU1_SMERR_NESPI_CPU0_ALERT_R_NESPI_CPU0_R1_D0ESPI_CPU0_R1_D2ESPI_CPU0_R1_D3FM_HDT_HDR_PWROKRST_RT_CPU0_P1_PERST_R2_NRST_RT_CPU0_P0_RESET_R2_NRST_RT_CPU0_P0_PERST_R2_NCPU1_SPD_HOST_CTRL_R1_NESPI_CPU0_CS1_R_NPWRGD_P12V_MEM_RP12V_ALL_PWROKRST_RT_CPU0_P3_PERST_R_NROM_LS_ENBMC_JTAG_SELROM_SD_LS_OEFM_SPD_CPU0_SWITCH_CTRL_NCPU0_HDT_BYPASS_SELCPU1_JTAG_BUF_OESCM_USB_OC_NRST_RT_CPU0_P2_RESET_R_NCPU0_SPD_HOST_CTRL_NCPU1_HDT_BYPASS_SELSCM_IRQ_1V8_NRST_RT_CPU0_P3_RESET_R_NFM_BIOS_POST_CMPLT_BUF_NHDT_HDR_RESET_NESPI_CPU0_ALERT_PLD_NESPI_CPU0_CS1_NFM_JTAG_BMC_R_OECPU0_HDT_CONN_TESTENFM_JTAG_BMC_OECLK_ESPI_CPU0_R1_CLK1FM_RST_CPU0_RESETL_NRST_RT_CPU1_P1_RESET_R2_NRST_RT_CPU1_P1_PERST_R2_NFM_CPU0_NV_SAVE_NFM_CPU1_SYS_RESET_NFM_RST_CPU1_RESETL_NCPU0_JTAG_BUF_R_OEFM_PWRGD_CPU0_PWROKFM_CPU1_NV_SAVE_NFM_CPU0_NMI_SYNC_FLOOD_NFM_PWRGD_CPU1_PWROKFM_P1_PCC0_R_NFM_CPU0_PWR_BTN_NFM_ROM_SD_LS_OERST_RT_CPU0_P3_RESET_R2_NFM_SPD_CPU0_SWITCH_CTRL_R_NFM_PLD_CPU0_PRSNT_HDTFM_CPU1_PWRGD_OUTFM_CPU0_FORCE_SELFREFRESHFM_FORCE_ALL_PWRON_RRST_SMB_RT_R2_NRST_PERST_E1S_0_R_NLCMXO3LF-9400C-5BG484CGPU_3V3IO_RSVD3_ISO_RGPU_3V3IO_RSVD1_ISO_RCHIPCHIPGPU_WP_HW_CTRL_R_NFM_PVDD18_S5_P0_ENCHIP33.2CHIPBMC_MONITER33.2FM_PWRGD_P1V8_RETIMER_CPU1GPU_FPGA_EROT_RECOV_NPWRGD_PVDD18_S5_R_P1FM_PWRGD_PVDD33_S5FM_GPU_PWR_EN_RGPU_FPGA_RST_R_NPVDD11_S3_P1_ENPWRGD_PVDD11_S3_P1PVDD18_S5_P1_ENFPGA_DEBUG_SW_SPAREFM_PWRGD_P1V8_RETIMER_CPU0FM_CPU1_FORCE_SELFREFRESHRST_RT_CPU0_P3_PERST_R2_NFM_BIOS_USB_RECOVERYFM_BIOS_POST_CMPLT_BUF_R_NFM_HDT_HDR_RESET_NFM_ESPI_CPU0_ALERT_SELCPU1_SMERR_NRST_RT_CPU0_P2_PERST_R_NRST_RT_CPU0_P2_PERST_R2_NFM_CPU0_HDT_CONN_TESTENTP_PWRGD_P12V_FAN_DR_R33FM_CPU1_NMI_SYNC_FLOOD_NRST_RT_CPU0_P2_RESET_R2_NFM_PWRGD_PVDDIO_P01%1%CHIPCHIPPRSNT_OCP_SFF_NPWRGD_P1V8_AUX_RFM_PWRGD_PVDD18_S5_P0PVDD18_S5_P0_ENPWRGD_PVDDIO_P1FM_GPU_HSC_ENHP_LVC3_E1S_0_HSC_PWRGD33.233.2
FM_CPU0_SLP_S5_NFM_CPU0_SLP_S3_NRST_CPU0_PERST0_NRST_CPU0_RSMRST_NRST_CPU1_PERST1_NFM_CPU0_SYS_RESET_NRST_RT_CPU1_P1_PERST_R_NRST_CPU0_PERST1_N
1%PWRGD_P3V3_AUX_RCHIPFM_LED_PWRGD_PVDDIO_P0FM_GPU_PWRGD_ISOCHIP
1
R6855
R6854
R6853
R6852
R6826
R6825
R6824
R6823
R6807
R6806
R6805
R6804
R6799
R6798
R6793
R6792
R6781
R6777
R6741
R6740
R6711
R6710
R8032
R8021
21 R195
21 R933
21 R250
21 R193
21 R1203
21 R258
21 R685
21 R254
21 R229
21 R230
21 R198
21 R255
21 R197
21 R273
21 R217
21 R216
21 R253
21 R272
21 R241
21 R57
21 R463
21 R159
21 R242
21 R196
21 R219
21 R371
21 R203
21 R1278
21 R215
21 R1279
21 R1280
21 R1281
21 R194
21 R228
21 R208
21 R6046
R1563
21 R286
21 R209
21 R6055
21 R280
21 R279
21 R289
21 R1282
21 R6048
21 R648
21 R199
R1553
R1549
R1552
R1551
21 R708
21 R856
21 R937
21 R277
21 R588
21 R173
21 R251
21 R161
21 R174
21 R372
21 R1359
R1616
R1564
21 R395
21 R158
21 R957
21 R186
R252
21 R1202
21 R265
21 R798
21 R224
21 R5099
21 R6047
21 R176
21 R218
21 R282
21 R283
R8000
R2939
R4557
R4608
R2262
R2845
R3483
R3478
R3477
R2261
R1556
R1557
21
2
R1558
21 R1550
21
21
PR30D
PR30C
PR28D
PR28C
PR28B
PR28A
PR27D
PR27C
PR27B
PR27A
PR26D
PR26C
PR26B
PR26A
PR25D
PR25C
PR24D
PR24C
PR24B
PR24A
PR21D
PR21C
PR21B
PR21A
PR20D
PR20C
PR19D
PR19C
PR18D
PR18C
PR18B
PR18A
PR17D
PR17C
PR16D
PR16C
PR14D
PR14C
PR13D
PR13C
PR13B
PR13A
PR12D
PR12C
PR12B
PR12A
PR11D
PR11C
PR11B
PR11A
PR10D
PR10C
PR10B
PR10A
PR7D
PR7C
PR6D
PR6C
PR6B
PR6A
PR5D
PR5C
PR5B
PR5A
PR4B
PR4A
PR4D
PR4C
PR3D
PR3C
PR2D
PR2C
PR2A||R_GPLLT_FB
PR2B||R_GPLLC_FB
PR3A||R_GPLLT_IN
PR3B||R_GPLLC_IN
PR7A
PR7B
PR14A
PR14B
PR16A
PR16B
PR17A||PCLKT1_0
PR17B||PCLKC1_0
PR19A
PR19B
PR20A
PR20B
PR25A
PR25B
PR29A
PR29C
PR29B
PR29D
PR30A
PR30B
21
21
R6085
21
21
21
21
21
21
21
Y20
W19
W20
V18
V19
U17
Y21
AA22
U18
U19
W21
Y22
U20
T17
T18
T19
T20
R16
R17
R18
R19
R20
W22
V22
U21
U22
P16
P17
P18
P19
T21
T22
P20
P22
R21
R22
N19
N20
P21
N22
N18
N17
N16
M16
M19
M20
M21
M22
M17
L22
L21
K22
L20
L19
L16
L17
K16
K17
K18
K19
K20
J20
J22
J21
J19
J18
J17
J16
H16
H17
H18
H19
H20
G17
H21
H22
G18
G19
G20
G21
F19
F18
G22
F22
E20
E19
E21
E22
D20
D19
D21
D22
G16
F17
C22
C21
T16
V17
AA21
AB21
W18
Y19
AA20
AB20
U16
T15
AA19
AB19
W17
Y18
AA18
AB18
V16
Y17
AA17
AB17
U15
V15
AA16
AB16
W15
Y15
AA15
AB15
W14
Y14
AA14
AB14
V14
U14
T14
T13
W13
Y13
AA13
AB13
U13
V13
AA12
AB12
V12
U12
T12
Y12
Y11
V11
AB11
AA11
U11
T11
AB10
AA10
Y10
Y9
W10
V10
U10
T10
AB9
AA9
W9
Y8
AB8
AA8
W8
V9
U9
T9
U8
V8
AB7
AA7
V7
W6
AB6
AA6
Y6
Y5
AB5
AA5
T8
U7
AB4
AA4
W5
Y4
AB3
AA3
U6
V6
AB2
AA2
U18
U18
7/7
BANK 1
2/7
BANK 2
PB21D
PB21C
PB46D
PB46C
PB44D
PB44C
PB43D
PB43C
PB41D
PB41C
PB41B
PB41A
PB40D
PB40C
PB40B
PB40A
PB38D
PB38C
PB38B
PB38A
PB35D
PB35C
PB32D
PB32C
PB32B
PB32A
PB33D
PB33C
PB30D
PB30C
PB29D
PB29C
PB27D
PB27C
PB27B
PB27A
PB22D
PB22C
PB19D
PB19C
PB19B
PB19A
PB18D
PB18C
PB16D
PB16C
PB13B
PB13A
PB11D
PB11C
PB11B
PB11A
PB35B
PB35A
PB46B||SI||SISPI
PB46A||SN
PB44B
PB44A
PB43B
PB43A
PB33B
PB33A
PB30B
PB30A
PB29B||PCLKC2_1
PB29A||PCLKT2_1
PB24D
PB24C
PB24B
PB24A
PB22B||PCLKC2_0
PB22A||PCLKT2_0
PB21B
PB21A
PB18B
PB18A
PB16B||SO||SPISO
PB16A||MCLK||CCLK
PB13D
PB13C
PB10D
PB10C
PB10B
PB10A
PB8B
PB8A
PB8D
PB8C
PB7D
PB7C
PB7B
PB7A||CSSPIN
PB5D
PB5C
PB5B
PB5A
21
21
21
21
21
21
21
21
21 21 21 21 21 21
21 21
21
21
21 21
21 21
21
21
21
2
1
21R3479
21R3482
21R3324
21R11667
21R2664
21R2663
21R3066
21R2847 21R2844
21R2846
21R3505
21R3486
21R3485
21R3484
21R3481
21R3476 21R3480
21R4157 21R4563
21R4148
21R4147
21R4144
21R4143
21R4558
21R4556
21R4172
21R4171
21R4170
21
21
21
21
21 21
21
SHEETDATE
DEPARTMENT
SIZE
PROJECT DOCUMENT NUMBER REV
REVIEWER
DESIGNER
123
7 3 2 1 6 5 4
E
A
B
C
E
D
C
B
A
7 6 5 4
D
INININININ
IN
IN
OUTOUT
OUT
IN
INOUT
BIBI
OUTOUT
INBI
OUTOUTOUT
BIIN
OUT
OUTOUT
OUTOUT
ININ
IN
IN
OUT
OUT
OUT
INININ
OUT
IN
IN
OUT
ININININ
IN
OUT
OUT
IN
IN
ININ
OUT
OUT
OUT
OUT
OUTOUTOUTOUTOUTOUT
OUTOUT
OUT
OUT
OUTOUT
OUTOUT
IN
OUT
OUT
IN
OUT
IN
OUT
OUT
OUT
OUT
OUTOUT
OUT
IN
OUTOUT
OUTOUT
OUT
OUTOUT
OUT
OUT
IN
IN
ININ
INININ
ININ
OUTIN
ININ
ININ
ININ
ININ
OUTIN
OUTIN
OUTINININ
IN
OUT
OUTININBIIN
OUT
IN
INOUT
ININ
ININBI
OUT
OUT
BIBIBIOUTOUT
ININ
OUT
OUT
IN
OUT
OUTOUTOUT
OUT
INOUTOUTINOUT
OUT
IN
OUT
OUTOUT
IN
OUTOUT
OUT
OUT
OUTINOUT
IN
OUT
IN
INOUT
OUTIN
IN
IN
OUT
OUT
OUT
IN
C



TBCBANK3 P3V3_AUXBANK5 P1V8_AUXTBCBANK4 P3V3_AUX
Thu Sep 14 16:12:39 2023<NAME_2><NAME_1>MB FABCGT AMDV0282 OF 365P3V3_AUXP3V3_AUXP3V3_AUXP1V8_AUXP1V8_AUX
2827545527172272828281935527172555520020025654272682754217278321783200237 358256136193193922078625621783145 80985427 84167548316183161542492784832242754 275427542754271725422427 54841935427272072721028359359200545424110483210167858316185150152852682373588316123883207 238136272785187131132131238 35814400 00000000000000000000000000000000 000000 00000333333333333333333333333330000 00IRQ_BMC_SMI_NCPU1_XTRIG_L7IRQ_CPU_BMC_NMI_NCPU0_XTRIG_L5CPU0_XTRIG_L4IRQ_SMI_ACTIVE_NIRQ_TPM_SPI_R_NFM_SMM_CRASHDUMPFM_CPU1_BMC_RST_R_NPVDDCR_CPU0_P0_OCP_NFM_BMC_TPM_PRES_NFM_BMC_READY_R_NFM_CPU0_XTRIG_L7CPU0_XTRIG_L7FM_BMC_READY_NFM_CPU1_BMC_RST_NPVDDCR_CPU1_P0_OCP_NFM_PVDDCR_CPU1_P0_ENFM_LED_PWRGD_PVDDCR_CPU1_P0CPU1_SP5R2CPU0_CORETYPE1P12V_HSC_TEMP_ALERT_R_NCPU0_SP5R2CPU1_CORETYPE0IRQ_TPM_SPI_R1_NIRQ_SMI_ACTIVE_N_RFM_CPU0_XTRIG_L4FM_CPU0_XTRIG_L5IRQ_CPU_BMC_NMI_R_NFM_CPU1_XTRIG_L7PVDDCR_CPU1_P1_OCP_NCPU0_SP5R1FM_SEC_MUX_R_SELFM_SEC_MUX_OE_R_NPVDDCR_CPU1_P1_SMB_ALERTPVDDCR_CPU1_P0_SMB_ALERTOCP_SFF_P3V3_P12V_ADC_R_ALERTFM_LED_PWRGD_PVDDCR_SOC_P0P12V_OCP_V3_1_PLD_PWRGDPWRGD_PVDDCR_SOC_P0PVDDCR_SOC_P0_ENOCP_SFF_P3V3_P12V_ADC_ALERTPWRGD_CHGL_CPU0_R2PVDD11_S3_P0_ENFM_PVDDCR_CPU1_P1_R_ENPWRGD_CHAF_CPU0_R2FM_LED_PWRGD_PVDDCR_CPU0_P0P12V_OCP_V3_1_PWRGDFM_PVDDCR_CPU1_P1_ENE1S_0_PRSNT_R_NFM_CPU0_SP5R4FM_PRSNT_CPU0_R_NFM_PRSNT_CPU1_R_NE1S_0_PRSNT_NFM_CPU0_XTRIG_L6IRQ_BMC_SMI_R_NFM_SMM_CRASHDUMP_RFM_PVDDCR_CPU0_P0_OCP_NFM_PVDDCR_CPU1_P0_OCP_NFM_CPU0_SP5R3FM_PWRGD_PVDDCR_CPU1_P0FM_BMC_TPM_PRES_N_RFM_CPU1_XTRIG_L6PWRGD_CHAF_CPU1_R2CPU1_CORETYPE2CPU0_SP5R3FAB_BMC_REV_ID1FM_PRSNT_CPU1_NFM_CPU1_SA1FM_CPU1_CORETYPE0FM_PVDDCR_CPU1_P0_R_ENFM_APML_MUX2_OE_R_NFM_CPU0_CORETYPE1FM_CPU1_CORETYPE1CPU1_CORETYPE1FM_APML_MUX2_SELFM_APML_MUX2_OE_NFM_CPU0_SP5R1FM_CPU0_SP5R2FM_CPU1_SP5R1FM_APML_MUX2_SEL_RFM_CPU1_CORETYPE2CPU1_SP5R1FM_CPU1_SP5R2LCMXO3LF-9400C-5BG484CSMB_BMC_GPU_ENCPU0_SA1FAB_BMC_REV_ID0SMLFLCMXO3LF-9400C-5BG484CPVDD11_S3_P1_PMALERTICFM_CPU1_XTRIG_L5FM_CPU1_XTRIG_L4CPU1_XTRIG_L4CPU0_SP5R4CPU1_SA1CPU1_XTRIG_L5CPU1_XTRIG_L6CPU0_XTRIG_L6LCMXO3LF-9400C-5BG484C
SMLFIC IC
SMLF
FPGA 3/6
CPU1_PROCHOT_NPVDD11_S3_P1_OCP_NFM_CPU0_CORETYPE0FM_CPU0_SA0FM_CPU0_SA1FM_CPU1_PROCHOT_R_NFM_PVDD11_S3_P1_OCP_NFM_PVDD11_S3_P0_OCP_NFM_CPU1_SA0CPU1_THERMTRIP_R_NFM_PVDDCR_CPU0_P1_OCP_NFAB_BMC_REV_ID2FM_CPU0_PROCHOT_R_NFM_CPU1_SP5R4FM_PVDD11_S3_P0_ENPWRGD_PVDDCR_CPU0_P0FM_INT_CPU0_HP_UBM_R_NCPU1_SA0CPU0_SA0CPU0_PROCHOT_NPVDD11_S3_P0_OCP_NCPU0_THERMTRIP_R_NPVDDCR_CPU0_P1_OCP_NFM_INT_CPU0_HP_UBM_NRT_BOARD_ID_ID1RT_BOARD_ID_ID0PWRGD_PVDDCR_CPU1_P0CPU1_SP5R3CPU1_SP5R4FM_PDB_BUF_EN_R_NPWRGD_CHGL_CPU1_R2FM_PVDDCR_CPU1_P1_OCP_NFM_CPU1_SP5R3FM_PDB_BUF_EN_NFM_CLKREQ_M2_1_NFM_PLD_OCP_SFF_AUX_PWR_R_ENPVDDCR_CPU0_P1_PMALERTFM_PRSNT_CPU0_NPWRGD_P5V_AUX_R3FM_SEC_MUX_OE_NE1S_0_P3V3_P12V_ADC_ALERTLED_HDD_ACTIVITY_B_PLD_NFM_SCM_PRSNT1_NFM_THERMAL_ALERT_R_NP12V_HSC_T_CRIT_R_NE1S_0_P3V3_P12V_ADC_R_ALERTFM_SEC_MUX_SELP12V_SCM_ADC_ALERTPVDD11_S3_P0_PMALERTM2_0_P3V3_ADC_ALERTFM_PLD_OCP_SFF_AUX_PWR_ENOCP_V3_2_P3V3_P12V_ADC_ALERTFM_CLR_CMOSFM_CPU0_CORETYPE2FM_PLD_OCP_SFF_MAIN_PWR_EN_RCPU0_CORETYPE2CPU0_CORETYPE0PWRGD_OCP_SFF_PWR_GOODFM_SMB_RST_E1S_0_NCLR_CMOSFM_OCP_SFF_PWR_GOODOCP_SFF_MAIN_PWR_ENOCP_V3_2_P3V3_P12V_ADC_R_ALERTM2_SSD0_CLKREQ_EN_N
R1339
R1329
R1340
R132
R6184
R6183
21 R6073
21 R284
21 R278
21 R270
21 R226
21 R179
R220
R266
R221
21 R81
21 R285
21 R271
2 1R958
2 1R6053
2 1R275
2 1R6054
21 R205
21 R227
21 R6051
21 R182
21 R223
21 R6052
2 1R183
2 1R959
2 1R185
21 R204
21 R234
R267
21 R244
21 R238
21 R235
21 R237
21 R187
21 R245
21 R236
21 R246
21 R190
21 R243
21 R239
21 R188
21 R231
21 R137
21 R189
21 R141
21 R269
21 R268
21 R233
21 R264
21 R222
21 R232
21 R261
21 R260
21 R184
21 R263
21 R181
21 R180
21 R262
21
21
21
21
R133
K8
J8
F3
M3
M8
L8
V3
P8
N8
W16
W11
W7
R14
R13
R12
R11
R10
R9
V20
P15
N15
M18
M15
L15
K15
J15
F20
H14
H12
H11
H9
G13
G10
C16
C12
C7
N13
N12
N11
N10
M12
M11
L12
L11
K13
K12
K11
K10
AB22
AB1
Y16
Y7
W12
V21
V2
R15
R8
P14
P13
P12
P11
P10
P9
N21
N14
N9
M14
M13
M10
M9
M4
L18
L14
L13
L10
L9
L2
K21
K14
K9
J14
J13
J12
J11
J10
J9
H15
H13
H10
H8
F21
F2
E18
E5
C11
C2
B16
B7
A22
A1
T7
V5
W4
Y3
Y2
W3
AA1
Y1
U5
V4
W2
W1
U4
U3
V1
U2
T6
T5
T4
T3
R7
R6
U1
T2
P7
R5
R4
R3
P6
P5
T1
R2
N7
N6
N5
P4
M7
P3
R1
P2
N4
N3
P1
N2
M5
M6
N1
M1
L4
L3
M2
L1
L5
L6
K1
K2
K3
K4
K5
L7
K6
K7
J1
J2
J3
J4
J5
H5
J6
J7
H1
H2
H3
H4
G1
G2
G4
G3
F1
E1
F4
E3
E2
D1
H6
G5
D2
C1
H7
G6
F5
E4
G7
F6
D4
D3
U18
U18
U18
1/7
BANK 5
BANK 4
BANK 3
PL12D
PL12C
PL12B
PL12A
PL11D
PL11C
PL11B
PL11A
PL10D
PL10C
PL10B
PL10A
PL7D
PL7C
PL7B||PCLKC5_0
PL7A||PCLKT5_0
PL30D
PL30C
PL30B
PL30A
PL29D
PL29C
PL29B
PL29A
PL28D
PL28C
PL28B
PL28A
PL27D
PL27C
PL27B||PCLKC3_0
PL27A||PCLKT3_0
PL19D
PL19C
PL19B
PL19A
PL18D
PL18C
PL18B
PL18A
PL17D
PL17C
PL17B
PL17A
PL26B
PL26A
PL25D
PL25C
PL24D
PL24C
PL24B
PL24A
PL25B
PL25A
PL6B
PL6A
PL6D
PL6C
PL16D
PL16C
PL14D
PL14C
PL26D
PL26C
PL21D
PL21C
PL21B
PL21A
PL20D
PL20C
PL20B
PL20A
PL16B||PCLKC4_0
PL16A||PCLKT4_0
PL14B
PL14A
PL13D
PL13C
PL13B
PL13A
PL5D
PL5C
PL5B
PL5A
PL4D
PL4C
PL4B||L_GPLLC_IN
PL4A||L_GPLLT_IN
PL3D
PL3C
PL3B||L_GPLLC_FB
PL3A||L_GPLLT_FB
PL2D
PL2C
PL2B
PL2A
5/7
VCCIO0_5
VCCIO0_6
VCCIO0_9
VCCIO0_8
VCCIO0_7
VCCIO0_4
VCCIO0_3
VCCIO0_2
VCCIO0_1
VCCIO1_9
VCCIO1_8
VCCIO1_7
VCCIO1_6
VCCIO1_5
VCCIO1_4
VCCIO1_3
VCCIO1_2
VCCIO1_1
VCCIO2_9
VCCIO2_8
VCCIO2_7
VCCIO2_6
VCCIO2_5
VCCIO2_4
VCCIO2_3
VCCIO2_2
VCCIO2_1
VCCIO3_3
VCCIO3_2
VCCIO3_1
VCCIO4_3
VCCIO4_2
VCCIO4_1
VCCIO5_3
VCCIO5_2
VCCIO5_1
VCC12
VCC11
VCC10
VCC9
VCC8
VCC7
VCC6
VCC5
VCC4
VCC3
VCC2
VCC1
6/7
GND52
GND51
GND49
GND50
GND48
GND47
GND46
GND45
GND44
GND43
GND42
GND41
GND40
GND39
GND38
GND37
GND36
GND35
GND34
GND33
GND32
GND31
GND30
GND29
GND28
GND27
GND26
GND25
GND24
GND23
GND22
GND21
GND20
GND19
GND18
GND17
GND16
GND15
GND14
GND13
GND12
GND11
GND10
GND9
GND8
GND7
GND6
GND5
GND4
GND3
GND2
GND1
2 1
21
21
21 21
21 21
SHEETDATE
DEPARTMENT
SIZE
PROJECT DOCUMENT NUMBER REV
REVIEWER
DESIGNER
123
7 3 2 1 6 5 4
E
A
B
C
E
D
C
B
A
7 6 5 4
D
IN
INOUTIN
OUTIN
OUT
IN
IN
OUTIN
BI
IN
OUT
BIBI
BI
IN
BI
OUTBI
BI
BIBI
OUTBI
BI
IN
OUTOUT
ININ
IN
IN
OUT
IN
ININ
IN
IN
IN
IN
IN
IN
IN
IN
IN
IN
OUTOUT
IN
OUTOUT
IN
IN
ININ
OUT OUT OUT
IN
IN IN
IN
IN
INOUT
OUT
IN
INOUTINININ
OUTOUTOUTIN
OUT
IN
OUT
OUT
IN
INOUTIN
OUT
IN
IN
IN
IN
IN
IN
IN
ININ
C



Thu Sep 14 16:12:38 2023<NAME_2><NAME_1>MB FABCGT AMDV0283 OF 365
P1V8_AUXP3V3_AUXP3V3_AUXPVDD18_S5_P1
P3V3_AUXP1V8_AUX
PVDD18_S5_P08283161828316114580828013313980 15980 1598114614780828316128812881558155818114614780134135136811401411428114014124881298154815480801341352488185818582831611508017281207822248221082200822178219381 82 83161811448114580 15980 15982 8316182 8316181858127812781298115382 831610402LFCHIP1/16W1%10K0402LF10K1%CHIP1/16WCHIP10K1%0402LF1/16W 1/16WCHIP1%0402LF10K1%10KCHIP1/16W0402LF0402LF1%1/16WCHIP10K1/16WCHIP0402LF10K1%1/16WCHIP0402LF10K1%1/16W0402LF10K1%CHIP1/16W0402LF10K1%CHIP10KCHIP1%1/16W0402LF 0402LFCHIP1/16W10K1%FM_APML_MUX2_OE_NFM_APML_MUX2_SEL10KE1S_0_PRSNT_NFM_SYS_THROTTLE_N4.7KEMPTY4.7KC040216V10%NEAR CPLD
1K1K1KFM_I3C_CPU0_MUX0_OE_N1%FM_I3C_CPU0_MUX1_OE_N10KE1S_0_P12V_ENCPLD_JTAG_ENEMPTY10KFM_SEC_MUX_OE_NEMPTY4.7K
FPGA 4/60.1UFNEAR CPLDX7R10%0.1UF16VC04020.1UF0.1UF0.1UF0.1UF0.1UF0.1UF0.1UF0.1UF0.1UF0.1UF0.1UF0.1UF0.1UF0.1UFX7R0.1UF0.1UF0.1UF0.1UF0.1UF
RST_CPU0_PERST1_NRST_CPU0_PERST0_NRST_CPU1_PERST1_NRST_CPU1_PERST0_N2.2K1%0402LFCHIP2K4.7KE1S_0_P3V3_ENEMPTYP12V_OCP_SFF_EN_RP12V_OCP_V3_2_EN_R4.7KP3V3_OCP_V3_2_EN_R4.7KSCM_USB_OC_N4.7K4.7KFM_P1_PCC1_N4.7KFM_P1_PCC0_N1K1KCPLD_PROGRAMNP3V3_OCP_SFF_EN_R4.7KCHIP2KCHIP2KRST_PERST_CPU1_SWB_NRST_PERST_CPU1_SWB_1_N4.7KEMPTY4.7KEMPTYFM_SEC_MUX_SELSCM_SYS_PWRBTN_N1%1KEMPTYEMPTY1KPRSNT_HDT_N1KPVDD11_S3_P0_PMALERTPVDD11_S3_P1_PMALERTPVDDCR_CPU0_P1_PMALERT1KPVDDCR_CPU1_P0_SMB_ALERTPVDDCR_CPU1_P1_SMB_ALERT1KPVDDCR_CPU0_P0_PMALERT1K1%EMPTY1/16W1/16WFM_APML_MUX2_SEL1K1%CHIPEMPTY0.1UF0.1UFEMPTY4.7KEMPTY4.7K4.7K1/16WRST_PERST_M2_0_NRST_PERST_E1S_0_N0402LF1/16WFM_I3C_CPU1_MUX0_OE_NFM_I3C_CPU1_MUX1_OE_NFM_SEC_MUX_OE_NFM_SEC_MUX_SEL0402LF0402LFEMPTYRST_PERST_CPU0_SWB_NFM_P0_PCC0_NFM_P0_PCC1_NRST_CPU0_KBRST_R_NFM_ESPI_CPU0_ALERT_R_SELFM_APML_MUX2_OE_N
R1304
R126
R135
R134
R6188
R6186
R6185
21C359
2
1
R17
2
1
R16
2
1
R800
21C361
21C360
21C362
2
1
R12
2
1
R11
2
1
R10
21C1133
21R1287
21R1288
21R1351
21R654
21R757
21R1071
21R639
2
1
R19
2
1
R18
2
1
R804
21C1171
21C1173
21C1172
21C1174
21C1175
21C1176
21C355
21C356
21C357
21C358
2
1
R25
21C1127
21C1126
21C1129
21C1128
21C352
21C1131
21C1132
21C1134
21R1285
21R1286
21R1185
21R1188
21R1186
21R1187
21R1190
21R1189
21R1527
21R1314
21R993
21R6062
21R6061
21R1195
21R638
R8033 R136
R3
R6187
R6115
R6114
R64
21
2
1
21
2
1
2
1
21 21 2 1
21
2
1
21
2
1
21 21
CAD NOTE:CAD NOTE:
SHEETDATE
DEPARTMENT
SIZE
PROJECT DOCUMENT NUMBER REV
REVIEWER
DESIGNER
123
7 3 2 1 6 5 4
E
A
B
C
E
D
C
B
A
7 6 5 4
D
ININ
OUT
OUTOUT
OUTOUT
OUTOUT
OUT
OUTOUT
OUT
OUT
OUT
OUTOUT
OUT
OUT
IN
ININ
OUT
OUTOUT IN
OUT
OUT
IN
OUT
IN
IN
OUT
IN
OUT
OUT
INININ
OUT
IN
OUT
OUT
ININ
OUT
C



110100001000ID2ID3
TBC
BRD_SKU1001ID40INTEL PLATFORMBRD_SKU0AMD PLATFORM0 000ID0
DVT1110ID010ID100REVEVTPVT1010 0ID28 RT2 RT1000DVT2PVT2
HSC-MPS5990+ADC-TIC+VR-RTTHSC-MODULE+ADC-MAM+VR-SNIHSC-REEDSEMI+ADC-TIC+VR-RTTHSC-MODULE+ADC-MAM+VR-MPSHSC-MPS5990+ADC-TIC+VR-MPSID1
Thu Sep 14 16:12:39 2023<NAME_2><NAME_1>MB FABCGT AMDV0284 OF 36580FM_BOARD_SKU_ID0FM_BOARD_SKU_ID1FM_BOARD_SKU_ID20402LFFM_BOARD_SKU_ID4PVDD18_S5_P00402LFP1V8_AUXPVDD18_S5_P0P3V3_AUX
P3V3_AUXP1V8_AUX
1K1/16WFAB_BMC_REV_ID00402LFEMPTY1%1K0402LF1%CHIP1/16W1K 1K0402LF1/16WEMPTY1K1%CHIP1%0402LF1%0402LFCHIP1/16W1K1%FAB_REV_ID00402LF1/16WEMPTY1K1%0402LF1%1/16W 1/16WEMPTYFAB_REV_ID11%1KFAB_REV_ID21K2828288282822828282828808080
15081
800402LF 0402LF1/16WFM_BOARD_SKU_ID3EMPTY1%1K1%1/16W0402LF1/16W1/16W0402LFCHIP1/16W1/16WFM_BOARD_BMC_SKU_ID2FM_BOARD_BMC_SKU_ID3EMPTYEMPTYEMPTY0402LFCHIP1%1/16W0402LFEMPTY1/16W0402LF1K1%EMPTY0402LF1/16W1K0402LF1K1%1K1%1/16WCHIP1/16W1K1%1/16W1%1K0402LF0402LFFPGA 5/6 (BOARD ID)1/16WCHIP0402LF1/16WEMPTY1%CHIP1%1KEMPTY0402LFEMPTYCHIP1%0402LF1K1K1KFM_BOARD_BMC_SKU_ID0FM_BOARD_BMC_SKU_ID11KCHIP1%1%1K1%1/16WCHIP1KCHIP1/16W1%1%0402LF1%1K0402LFEMPTYCHIPICSN74LVC1G07DBVRSMLFCHIP1/16W5%4.7K0402LF4.7K1/16WCHIP5%0402LF25V10%X7R0.1UF0402SCM_IRQ_R_N SCM_IRQ_NSCM_IRQ_1V8_N
1/16WFM_BOARD_BMC_SKU_ID41K1K0402LF1/16W1K 1K1/16W1K1% 1%0402LF1/16W1%331%0402LF1K1KCHIP1%1/16WCHIP0402LFCHIP1/16W1%1K0402LF1/16WEMPTY0402LF0402LFEMPTY1/16W 1/16WFAB_BMC_REV_ID1FAB_BMC_REV_ID2
2
1
R1338
21 R714
5
13
2
U92
2
1 C552
2
1
R996
NC
Y
GND
A
VCC
2
1
2
1
2
1
2
1
2
1
2
1
2
1
2
1
2
1
2
1
2
1
2
1
2
1
2
1
2
1
2
1
2
1
2
1
2
1
2
1
2
1
2
1
2
1
2
1
2
1
2
1
2
1
2
1
2
1
2
1
2
1
2
1
SHEETDATE
DEPARTMENT
SIZE
PROJECT DOCUMENT NUMBER REV
REVIEWER
DESIGNER
123
7 3 2 1 6 5 4
E
A
B
C
E
D
C
B
A
7 6 5 4
D
OUT
OUT
OUT
OUT
OUT
OUT
OUT
OUT
OUT
OUT
OUT
OUT
OUT
OUT
OUT
OUT
OUTIN
R6148
R6151
R6147
R6150
R6146
R6149
R6135
R6132R6131
R6134R6133
R6130
R6142
R6137
R6121
R6126
R6141
R6136
R6125
R6120 R6124 R6123
R6129R6128
R6140R6139
R6127
R6138
R6143 R6144
R6122
R6145
C



PLACE THE 100PF CAPS FOR SI AND CLOSE TO MAIN PLDTBCPIN2: PROGRAMMER TDIPIN3: PROGRAMMER TDO
CAD NOTE: IF DEPOP R1422, PLEASE POP R557CAD NOTE: IF DEPOP R530, PLEASE POP R556
Thu Sep 14 16:12:16 2023<NAME_2><NAME_1>MB FABCGT AMDV0285 OF 365
P3V3_AUXP3V3_AUXP5V_AUX_VCCP3V3_AUX P3V3_AUXP3V3_AUXGND GND
P3V3_AUXP3V3_AUX100KIRQ_HSC_FAULT_N268 26380
8218919082818128815581288178558178
818319081270144150236818382801288183145128128242822551501718080171171801718033.200000000033.233.20IRQ_HSC_FAULTIRQ_HSC_FAULT_BUF_N1/16W1%0402LFEMPTYICPJT138KSMLF4.7KCHIP1/16W5%0402LF0402LF100K1%1/16WCHIPX7R10%04020.1UF25V0402LF 1/16WEMPTY5%0ICSMLFPJT138KLED_HDD_ACTIVITY_B_PLD_NPWRGD_P5V_AUXPWRGD_P5V_AUX_R2 PWRGD_P5V_AUX_R3PWRGD_P5V_AUX_R1EMPTY1/16W1%10K0402LFPJT138KICSMLF1/16WCHIP5%4.7K0402LF0402LFCHIP1/16W100K1%0402X7R10%25V0.1UFICSMLFPJT138KBMC_FPGA_LED1_R_NBMC_FPGA_LED1BMC_FPGA_LED2_R_NBMC_FPGA_LED1_NBMC_FPGA_LED2_NBMC_FPGA_LED22001%CHIP1/16W 0402LF0402LF2001%CHIP1/16WSMLFLTST-C190KSKT-PICLED_YELLOWICSMLFLTST-C190KSKT-PLED_YELLOW2N7002KDWICSMLFRST_CPU0_RESETL_NRST_CPU1_RESETL_NCHIP00402LFPWRGD_CPU0_PWROKPWRGD_CPU1_PWROKCHIP1/16W0402LF1%100
1KRST_PERST_CPU0_SWB_NPWRGD_P3V3_AUXLED_HDD_ACTIVITY_B_NFM_THERMAL_ALERT_NRST_PERST_CPU1_SWB_1_NFM_SMB_RST_E1S_0_NSCM_SYS_PWROK_RCHIPRST_PERST_CPU1_SWB_1_R_NRST_PERST_CPU1_SWB_NFM_SMB_RST_E1S_0_R_NRST_PERST_CPU1_SWB_R_NRST_PERST_CPU0_SWB_R_NPWRGD_P3V3_AUX_PDBFM_THERMAL_ALERT_R_N100PFSCM_SYS_PWROK_R2SCM_SYS_PWROK_R1JTAG_PLD_TCK0 JTAG_SCM_PLD_TDO JTAG_PLD_TDOJTAG_SCM_PLD_TDI JTAG_PLD_TDIJTAG_SCM_PLD_TMSJTAG_PLD_TMS1/16W5%4.7K0402LFCHIPJTAG_SCM_PLD_TCKTHLFIOCONN8_HBB1081-L200D-8HX7R10%0.1UF16VC040250V5%NPO0402FPGA 6/6
2 1R6118
D8
D7
R2
21 R6112
21 R6093
21 R6092
21 R6113
21 R6078
21 R6075
21 R6074
41
52
36
Q28
21
R1194
21
R1266
2 1R15
2
1
R530
21R1036 2
1C20
8
7
6
5
4
3
2
1
J57
2 1R13
2 1R9
21R1303
2 1R14
G2G1
G2
G1
S2 D2D1S1
S2 D2D1S1
R9027
R9026
R1422
C8005
C1209
5
2
CA
CA
52
4 31 6
4 31 6
Q9003
Q9003
Q50Q50
A C
A C
D2D1
S2S1
G2G1
8
7
6
5
4
3
2
1
21R9028
2
1
2
1
2
1
2
1
2
1
2
1
21
2
1
2
1
2
1
2
1
2
1
SHEETDATE
DEPARTMENT
SIZE
PROJECT DOCUMENT NUMBER REV
REVIEWER
DESIGNER
123
7 3 2 1 6 5 4
E
A
B
C
E
D
C
B
A
7 6 5 4
D
IN OUT
IN OUT
OUT
IN OUT
OUT
IN OUT
IN
OUTIN
IN OUT
IN OUT
ININ
OUTIN
OUT
OUT
BI
BIIN
OUT
OUT
IN OUT
IN
C9005
R9025
R6090
R2346R2344
R2343
C



Thu Sep 14 16:12:05 2023<NAME_2><NAME_1>MB FABCGT AMDV0286 OF 365P3V3P3V3P3V3_AUXP3V3_AUXP3V3_AUX
P12V_MEM_CPU0P3V3_AUX1598788899091101010101010101010101086 8286878889909186 87 8889 9091868788899091
10101010101010108610101087888990911591K0.1UF25V04021KI3C_SPD_DDRAF_CPU0_SCLM_A_CPU0_CLK_DN<0>M_A_CPU0_CLK_DP<0>M_A_CPU0_SA_CB<7:0>10%X7RM_A_CPU0_SA_CS_N<0>M_A_CPU0_SA_PARM_A_CPU0_SA_RSP<0>M_A_CPU0_SB_CS_N<1>M_A_CPU0_SB_CS_N<0>M_A_CPU0_SB_RSP<0>M_A_CPU0_SB_PARM_A_CPU0_SA_CS_N<1>PD_CHA_CPU0_DIMM0_SAAPWRGD_CHAF_CPU0_R1 PWRGD_CHAF_CPU0_R2PWRGD_CHAF_CPU0PWRGD_CHAF_CPU0PWRGD_CHAF_CPU0
M_A_CPU0_SA_CA<6:0>M_A_CPU0_SB_CA<6:0>M_A_CPU0_SA_DQ<31:0>M_A_CPU0_SA_DQS_DP<9:0>M_A_CPU0_SA_DQS_DN<9:0>M_A_CPU0_SB_DQS_DP<9:0>M_A_CPU0_SB_DQS_DN<9:0>M_A_CPU0_SB_DQ<31:0>
DDR5 - CPU0 CHAEMPTYSMLFB0530WS7F1/16W0402LFEMPTY1%10K05%1/16W0402LFCHIP05%1/16W CHIP0402LF0402LF1%10KCHIP1/16W
SMLFIOSCONN288_DDR506112002KQIOSCONN288_DDR506112002KQSMLFIOSMLFSCONN288_DDR506112002KQPD_CHA_CPU0_DIMM0_SAA49.9M_A_CPU0_SB_CB<7:0>M_A_CPU0_RESET_NM_A_CPU0_ALERT_NPWRGD_CHA_CPU0_DIMM0I3C_SPD_DDRA_CPU0_SCLI3C_SPD_DDRA_CPU0_SDAI3C_SPD_DDRAF_CPU0_SDACHIP100402LFCHIP1/16W0402LF10K1%
X6SC080525V10UF10%
1K0402LFEMPTY1/16W1% 1%0402LFEMPTY1/16W
10%10UFC080525VX6S
J1J1
2
1C142
2
1
R89
2
1
R88
2 1R291
2
1C88
2
1C89
2
1
R7
6
0
5
8
9
9
8
7
5
6
7
6
5
4
4
3
2
3
2
1
0
1
0
9
8
9
8
7
5
6
7
6
5
4
3
4
3
2
0
1
2
1
0
28
27
31
30
29
24
25
26
22
21
23
18
17
16
20
19
15
14
11
9
10
8
6
7
4
5
3
1
2
31
30
0
29
27
26
25
28
24
22
21
20
23
19
18
17
16
14
15
13
11
12
10
9
8
7
6
5
4
3
2
0
1
2
1
0
3
4
5
6
7
3
1
0
2
4
5
0
1
2
3
6
4
5
1
2
4
3
7
6
13
12
R1674
R1568
J1
DQS7_A_c||TDQS7_A_c
DQS6_A_t||TDQS6_A_t
DQS8_B_t||TDQS8_B_t
DQS8_B_c||TDQS8_B_c
DQS7_B_t||TDQS7_B_t
DQS0_A_c
DQS0_A_t
DQS0_B_c
DQS0_B_t
DQS1_A_c
DQS1_A_t
DQS1_B_c
DQS1_B_t
DQS2_A_c
DQS2_A_t
DQS2_B_c
DQS2_B_t
DQS3_A_c
DQS3_A_t
DQS3_B_c
DQS3_B_t
DQS4_A_c
DQS4_A_t
DQS4_B_c
DQS4_B_t
DQS5_A_c||TDQS5_A_c||DQS5_A_t||TDQS5_A_t
DQS5_A_t||TDQS5_A_t
DQS5_B_c||TDQS5_B_c
DQS5_B_t||TDQS5_B_t
DQS6_A_c||TDQS6_A_c||DQS6_A_t||TDQS6_A_t
DQS6_B_c||TDQS6_B_c
DQS6_B_t||TDQS6_B_t
DQS7_A_t||TDQS7_A_t
DQS7_B_c||TDQS7_B_c
DQS8_A_c||TDQS8_A_c
DQS8_A_t||TDQS8_A_t
DQS9_A_c||TDQS9_A_c
DQS9_A_t||TDQS9_A_t
DQS9_B_c||TDQS9_B_c
DQS9_B_t||TDQS9_B_t||DBI4_B_n
21
288
286
284
281
279
277
275
273
270
268
266
264
262
259
257
255
253
251
248
246
244
242
240
237
235
233
230
228
226
224
222
219
216
214
212
210
208
206
204
202
199
197
195
193
191
188
186
184
182
180
177
175
173
171
169
166
164
162
160
158
155
153
151
143
141
139
136
134
132
130
128
125
123
121
119
117
114
112
110
108
106
103
101
99
97
95
92
90
88
85
83
81
79
77
75
73
71
69
67
65
63
61
59
57
54
52
50
48
46
43
41
39
37
35
32
30
28
26
24
21
19
17
15
13
10
8
6
146
145
1
G3
G2
G1
93
94
201
200
283
282
190
189
272
271
179
178
261
260
168
167
250
249
157
156
239
238
55
56
137
138
44
45
126
127
33
34
115
116
22
23
104
105
11
12
3
232
231
220
150
149
144
2
207
147
227
74
87
86
5
4
148
287
194
285
192
142
49
140
47
280
187
278
185
135
42
133
40
276
183
274
181
131
38
129
36
269
176
267
174
124
31
122
29
265
172
263
170
120
27
118
25
258
165
256
163
113
20
111
18
254
161
252
159
109
16
107
14
247
154
245
152
102
9
100
7
229
209
84
64
217
218
236
205
234
203
91
60
89
58
243
198
241
196
98
53
96
51
82
72
225
215
80
70
223
213
78
68
221
211
76
66
62
D8003
CA
3/3
G3
G2
G1
VSS62
VSS61
VSS60
VSS58
VSS104
VSS102
VSS100
VIN_BULK2
VIN_BULK1
VIN_BULK0
VSS126
VSS125
VSS124
VSS123
VSS122
VSS121
VSS120
VSS119
VSS118
VSS117
VSS116
VSS115
VSS114
VSS113
VSS112
VSS111
VSS110
VSS109
VSS108
VSS107
VSS106
VSS105
VSS103
VSS101
VSS99
VSS98
VSS97
VSS96
VSS95
VSS94
VSS93
VSS92
VSS91
VSS90
VSS89
VSS88
VSS87
VSS86
VSS85
VSS84
VSS83
VSS82
VSS81
VSS80
VSS79
VSS78
VSS77
VSS76
VSS75
VSS74
VSS73
VSS72
VSS71
VSS70
VSS69
VSS68
VSS67
VSS66
VSS65
VSS64
VSS63
VSS59
VSS57
VSS56
VSS55
VSS54
VSS53
VSS52
VSS51
VSS50
VSS49
VSS48
VSS47
VSS46
VSS45
VSS44
VSS43
VSS42
VSS41
VSS40
VSS39
VSS38
VSS37
VSS36
VSS35
VSS34
VSS33
VSS32
VSS31
VSS30
VSS29
VSS28
VSS27
VSS26
VSS25
VSS24
VSS23
VSS22
VSS21
VSS20
VSS19
VSS18
VSS17
VSS16
VSS15
VSS14
VSS13
VSS12
VSS11
VSS10
VSS9
VSS8
VSS7
VSS6
VSS5
VSS4
VSS3
VSS2
VSS1
VSS0
2/3
1/3
PWR_GOOD||FAIL_n
DQ31_A
CB7_A
CB4_A
CB1_A
CB7_B
ALERT_n
CA0_A
CA0_B
CA1_A
CA1_B
CA2_A
CA2_B
CA3_A
CA3_B
CA4_A
CA4_B
CA5_A
CA5_B
CA6_A
CA6_B
CB6_A
CB5_A
CB3_A
CB2_A
CB0_A
CB6_B
CB5_B
CB4_B
CB3_B
CB2_B
CB1_B
CB0_B
CK_c
CK_t
CS0_A_n
CS0_B_n
CS1_A_n
CS1_B_n
DQ30_A
DQ29_A
DQ28_A
DQ27_A
DQ26_A
DQ25_A
DQ24_A
DQ23_A
DQ22_A
DQ21_A
DQ20_A
DQ19_A
DQ18_A
DQ17_A
DQ16_A
DQ15_A
DQ14_A
DQ13_A
DQ12_A
DQ11_A
DQ10_A
DQ9_A
DQ8_A
DQ7_A
DQ6_A
DQ5_A
DQ4_A
DQ3_A
DQ2_A
DQ1_A
DQ0_A
DQ31_B
DQ30_B
DQ29_B
DQ28_B
DQ27_B
DQ26_B
DQ25_B
DQ24_B
DQ23_B
DQ22_B
DQ21_B
DQ20_B
DQ19_B
DQ18_B
DQ17_B
DQ16_B
DQ15_B
DQ14_B
DQ13_B
DQ12_B
DQ11_B
DQ10_B
DQ9_B
DQ8_B
DQ7_B
DQ6_B
DQ5_B
DQ4_B
DQ3_B
DQ2_B
DQ1_B
DQ0_B
HAS
HSCL
HSDA
LBD||RSP_A_n
LBS||RSP_B_n
PAR_A
PAR_B
RESET_n
RFU6
RFU5
RFU4
RFU3
RFU2
RFU1
RFU0
VIN_MGMT
21
21
2121
2
1
21
SHEETDATE
DEPARTMENT
SIZE
PROJECT DOCUMENT NUMBER REV
REVIEWER
DESIGNER
123
7 3 2 1 6 5 4
E
A
B
C
E
D
C
B
A
7 6 5 4
D
BI
BIBI
OUT
OUT
BI
OUT
IN
IN
OUTOUT
OUTOUT
BI
BI
IN
BI
IN
OUTOUT
ININ
ININ
ININ
ININ
IN
BI
R8082
R8081R8080
R8037
C



Thu Sep 14 16:12:05 2023<NAME_2><NAME_1>MB FABCGT AMDV0287 OF 365P3V3P3V3_AUXP12V_MEM_CPU087111115986888990918688899091868889909115911111111111111111111
11871111111111111111111K
C080525V10UF10%X6SC080525V10UF10%X6S1%EMPTY1K0402LF1/16W0.1UFX7R040225V10%10CHIP0402LFPD_CHB_CPU0_DIMM_SAAM_B_CPU0_ALERT_NM_B_CPU0_RESET_NI3C_SPD_DDRB_CPU0_SCLI3C_SPD_DDRAF_CPU0_SCLPWRGD_CHAF_CPU0I3C_SPD_DDRB_CPU0_SDAI3C_SPD_DDRAF_CPU0_SDA49.9PWRGD_CHB_CPU0_DIMM1/16WCHIP1%15.4K0402LF
SMLFSCONN288_DDR506112002KQIO SCONN288_DDR506112002KQIOSMLFIOSCONN288_DDR506112002KQSMLF
DDR5 - CPU0 CHB
M_B_CPU0_SB_CB<7:0>M_B_CPU0_SB_DQ<31:0>M_B_CPU0_SA_DQ<31:0>M_B_CPU0_SB_DQS_DP<9:0>M_B_CPU0_SB_DQS_DN<9:0>M_B_CPU0_SA_DQS_DN<9:0>M_B_CPU0_SA_DQS_DP<9:0>M_B_CPU0_SA_CA<6:0>M_B_CPU0_SA_CB<7:0>M_B_CPU0_SB_CA<6:0>
M_B_CPU0_SB_RSP<0>PD_CHB_CPU0_DIMM_SAAM_B_CPU0_CLK_DN<0>M_B_CPU0_SA_CS_N<0>M_B_CPU0_SA_CS_N<1>M_B_CPU0_SB_CS_N<1>M_B_CPU0_SA_RSP<0>M_B_CPU0_SB_PARM_B_CPU0_SA_PARM_B_CPU0_SB_CS_N<0>M_B_CPU0_CLK_DP<0>
2
1C145
2
1C143
2
1
R90
2 1R292
2
1C92
2
1
R761
1
2
0
3
4
5
7
6
2
1
0
3
4
5
6
7
3
1
0
2
1
0
2
3
4
5
7
6
8
9
10
11
12
13
15
14
18
17
16
21
22
20
23
19
26
27
25
28
24
0
30
31
29
2
1
3
4
5
7
6
8
9
10
14
15
13
12
11
17
18
16
20
19
6
4
5
0
1
2
3
5
4
6
23
21
22
24
25
26
31
27
28
30
29
0
1
2
1
0
2
3
4
3
4
5
6
7
6
5
7
8
9
8
9
0
1
0
1
2
3
2
3
4
4
5
6
7
6
5
7
8
9
9
8
21R1675
R1569
J15
J15
J15
DQS7_A_c||TDQS7_A_c
DQS6_A_t||TDQS6_A_t
DQS8_B_t||TDQS8_B_t
DQS8_B_c||TDQS8_B_c
DQS7_B_t||TDQS7_B_t
DQS0_A_c
DQS0_A_t
DQS0_B_c
DQS0_B_t
DQS1_A_c
DQS1_A_t
DQS1_B_c
DQS1_B_t
DQS2_A_c
DQS2_A_t
DQS2_B_c
DQS2_B_t
DQS3_A_c
DQS3_A_t
DQS3_B_c
DQS3_B_t
DQS4_A_c
DQS4_A_t
DQS4_B_c
DQS4_B_t
DQS5_A_c||TDQS5_A_c||DQS5_A_t||TDQS5_A_t
DQS5_A_t||TDQS5_A_t
DQS5_B_c||TDQS5_B_c
DQS5_B_t||TDQS5_B_t
DQS6_A_c||TDQS6_A_c||DQS6_A_t||TDQS6_A_t
DQS6_B_c||TDQS6_B_c
DQS6_B_t||TDQS6_B_t
DQS7_A_t||TDQS7_A_t
DQS7_B_c||TDQS7_B_c
DQS8_A_c||TDQS8_A_c
DQS8_A_t||TDQS8_A_t
DQS9_A_c||TDQS9_A_c
DQS9_A_t||TDQS9_A_t
DQS9_B_c||TDQS9_B_c
DQS9_B_t||TDQS9_B_t||DBI4_B_n93
94
201
200
283
282
190
189
272
271
179
178
261
260
168
167
250
249
157
156
239
238
55
56
137
138
44
45
126
127
33
34
115
116
22
23
104
105
11
12
288
286
284
281
279
277
275
273
270
268
266
264
262
259
257
255
253
251
248
246
244
242
240
237
235
233
230
228
226
224
222
219
216
214
212
210
208
206
204
202
199
197
195
193
191
188
186
184
182
180
177
175
173
171
169
166
164
162
160
158
155
153
151
143
141
139
136
134
132
130
128
125
123
121
119
117
114
112
110
108
106
103
101
99
97
95
92
90
88
85
83
81
79
77
75
73
71
69
67
65
63
61
59
57
54
52
50
48
46
43
41
39
37
35
32
30
28
26
24
21
19
17
15
13
10
8
6
146
145
1
G3
G2
G1
3
232
231
220
150
149
144
2
207
147
227
74
87
86
5
4
148
287
194
285
192
142
49
140
47
280
187
278
185
135
42
133
40
276
183
274
181
131
38
129
36
269
176
267
174
124
31
122
29
265
172
263
170
120
27
118
25
258
165
256
163
113
20
111
18
254
161
252
159
109
16
107
14
247
154
245
152
102
9
100
7
229
209
84
64
217
218
236
205
234
203
91
60
89
58
243
198
241
196
98
53
96
51
82
72
225
215
80
70
223
213
78
68
221
211
76
66
62
2/3
3/3
G3
G2
G1
VSS62
VSS61
VSS60
VSS58
VSS104
VSS102
VSS100
VIN_BULK2
VIN_BULK1
VIN_BULK0
VSS126
VSS125
VSS124
VSS123
VSS122
VSS121
VSS120
VSS119
VSS118
VSS117
VSS116
VSS115
VSS114
VSS113
VSS112
VSS111
VSS110
VSS109
VSS108
VSS107
VSS106
VSS105
VSS103
VSS101
VSS99
VSS98
VSS97
VSS96
VSS95
VSS94
VSS93
VSS92
VSS91
VSS90
VSS89
VSS88
VSS87
VSS86
VSS85
VSS84
VSS83
VSS82
VSS81
VSS80
VSS79
VSS78
VSS77
VSS76
VSS75
VSS74
VSS73
VSS72
VSS71
VSS70
VSS69
VSS68
VSS67
VSS66
VSS65
VSS64
VSS63
VSS59
VSS57
VSS56
VSS55
VSS54
VSS53
VSS52
VSS51
VSS50
VSS49
VSS48
VSS47
VSS46
VSS45
VSS44
VSS43
VSS42
VSS41
VSS40
VSS39
VSS38
VSS37
VSS36
VSS35
VSS34
VSS33
VSS32
VSS31
VSS30
VSS29
VSS28
VSS27
VSS26
VSS25
VSS24
VSS23
VSS22
VSS21
VSS20
VSS19
VSS18
VSS17
VSS16
VSS15
VSS14
VSS13
VSS12
VSS11
VSS10
VSS9
VSS8
VSS7
VSS6
VSS5
VSS4
VSS3
VSS2
VSS1
VSS0
1/3
PWR_GOOD||FAIL_n
DQ31_A
CB7_A
CB4_A
CB1_A
CB7_B
ALERT_n
CA0_A
CA0_B
CA1_A
CA1_B
CA2_A
CA2_B
CA3_A
CA3_B
CA4_A
CA4_B
CA5_A
CA5_B
CA6_A
CA6_B
CB6_A
CB5_A
CB3_A
CB2_A
CB0_A
CB6_B
CB5_B
CB4_B
CB3_B
CB2_B
CB1_B
CB0_B
CK_c
CK_t
CS0_A_n
CS0_B_n
CS1_A_n
CS1_B_n
DQ30_A
DQ29_A
DQ28_A
DQ27_A
DQ26_A
DQ25_A
DQ24_A
DQ23_A
DQ22_A
DQ21_A
DQ20_A
DQ19_A
DQ18_A
DQ17_A
DQ16_A
DQ15_A
DQ14_A
DQ13_A
DQ12_A
DQ11_A
DQ10_A
DQ9_A
DQ8_A
DQ7_A
DQ6_A
DQ5_A
DQ4_A
DQ3_A
DQ2_A
DQ1_A
DQ0_A
DQ31_B
DQ30_B
DQ29_B
DQ28_B
DQ27_B
DQ26_B
DQ25_B
DQ24_B
DQ23_B
DQ22_B
DQ21_B
DQ20_B
DQ19_B
DQ18_B
DQ17_B
DQ16_B
DQ15_B
DQ14_B
DQ13_B
DQ12_B
DQ11_B
DQ10_B
DQ9_B
DQ8_B
DQ7_B
DQ6_B
DQ5_B
DQ4_B
DQ3_B
DQ2_B
DQ1_B
DQ0_B
HAS
HSCL
HSDA
LBD||RSP_A_n
LBS||RSP_B_n
PAR_A
PAR_B
RESET_n
RFU6
RFU5
RFU4
RFU3
RFU2
RFU1
RFU0
VIN_MGMT
21
SHEETDATE
DEPARTMENT
SIZE
PROJECT DOCUMENT NUMBER REV
REVIEWER
DESIGNER
123
7 3 2 1 6 5 4
E
A
B
C
E
D
C
B
A
7 6 5 4
D
BI
BI
IN
OUT
IN
OUT
OUTOUT
OUTOUT
BIIN
IN
BI
ININ
ININ
ININ
IN
BIIN
IN
BI
OUTOUT
C



Thu Sep 14 16:12:06 2023<NAME_2><NAME_1>MB FABCGT AMDV0288 OF 365
P12V_MEM_CPU0
P3V3P3V3_AUXI3C_SPD_DDRC_CPU0_SCL128886878990911591598687899091121212121212121212
8812128687899091 12121212121212121212
1K25V04020.1UF10%X7REMPTY1/16W1K0402LF1%
X6S10%10UFC080525VX6S10%10UF25VC080510CHIP 0402LFI3C_SPD_DDRC_CPU0_SDAM_C_CPU0_ALERT_NPD_CHC_CPU0_DIMM_SAAI3C_SPD_DDRAF_CPU0_SDA49.9I3C_SPD_DDRAF_CPU0_SCLM_C_CPU0_RESET_NM_C_CPU0_CLK_DN<0>M_C_CPU0_CLK_DP<0>M_C_CPU0_SA_CS_N<0>M_C_CPU0_SB_CS_N<0>M_C_CPU0_SA_CS_N<1>M_C_CPU0_SB_CS_N<1>M_C_CPU0_SA_PARM_C_CPU0_SB_PAR
PD_CHC_CPU0_DIMM_SAAM_C_CPU0_SB_RSP<0>M_C_CPU0_SA_RSP<0>PWRGD_CHAF_CPU0PWRGD_CHC_CPU0_DIMMM_C_CPU0_SB_DQS_DN<9:0>M_C_CPU0_SB_DQS_DP<9:0>M_C_CPU0_SA_DQS_DP<9:0>M_C_CPU0_SA_DQS_DN<9:0>M_C_CPU0_SB_DQ<31:0>M_C_CPU0_SB_CA<6:0>M_C_CPU0_SA_CA<6:0>M_C_CPU0_SB_CB<7:0>M_C_CPU0_SA_CB<7:0>M_C_CPU0_SA_DQ<31:0>
DDR5 - CPU0 CHC
SCONN288_DDR506112002KQSMLFIOIOSCONN288_DDR506112002KQSMLFIOSMLFSCONN288_DDR506112002KQ
0402LF23.2K1%CHIP1/16W
J17
J17J17 2
1C147
2
1C146
2
1
R91
2 1R293
2
1C96
2
1
R762
0
1
2
3
4
5
6
7
9
8
1
0
2
3
4
6
5
7
8
9
0
1
3
2
4
5
7
6
8
9
0
1
2
3
4
5
6
8
7
9
29
30
28
27
31
26
25
24
22
21
23
6
4
5
3
2
1
0
5
4
6
19
20
16
18
17
11
12
13
15
14
10
9
8
6
7
5
4
3
1
2
29
31
30
0
24
28
25
27
26
19
23
20
22
21
16
17
18
14
15
13
12
11
10
9
8
6
7
5
4
3
2
0
1
2
0
1
3
7
6
5
4
3
0
1
2
6
7
5
4
3
0
2
1
R1677
R1570
DQS7_A_c||TDQS7_A_c
DQS6_A_t||TDQS6_A_t
DQS8_B_t||TDQS8_B_t
DQS8_B_c||TDQS8_B_c
DQS7_B_t||TDQS7_B_t
DQS0_A_c
DQS0_A_t
DQS0_B_c
DQS0_B_t
DQS1_A_c
DQS1_A_t
DQS1_B_c
DQS1_B_t
DQS2_A_c
DQS2_A_t
DQS2_B_c
DQS2_B_t
DQS3_A_c
DQS3_A_t
DQS3_B_c
DQS3_B_t
DQS4_A_c
DQS4_A_t
DQS4_B_c
DQS4_B_t
DQS5_A_c||TDQS5_A_c||DQS5_A_t||TDQS5_A_t
DQS5_A_t||TDQS5_A_t
DQS5_B_c||TDQS5_B_c
DQS5_B_t||TDQS5_B_t
DQS6_A_c||TDQS6_A_c||DQS6_A_t||TDQS6_A_t
DQS6_B_c||TDQS6_B_c
DQS6_B_t||TDQS6_B_t
DQS7_A_t||TDQS7_A_t
DQS7_B_c||TDQS7_B_c
DQS8_A_c||TDQS8_A_c
DQS8_A_t||TDQS8_A_t
DQS9_A_c||TDQS9_A_c
DQS9_A_t||TDQS9_A_t
DQS9_B_c||TDQS9_B_c
DQS9_B_t||TDQS9_B_t||DBI4_B_n93
94
201
200
283
282
190
189
272
271
179
178
261
260
168
167
250
249
157
156
239
238
55
56
137
138
44
45
126
127
33
34
115
116
22
23
104
105
11
12
288
286
284
281
279
277
275
273
270
268
266
264
262
259
257
255
253
251
248
246
244
242
240
237
235
233
230
228
226
224
222
219
216
214
212
210
208
206
204
202
199
197
195
193
191
188
186
184
182
180
177
175
173
171
169
166
164
162
160
158
155
153
151
143
141
139
136
134
132
130
128
125
123
121
119
117
114
112
110
108
106
103
101
99
97
95
92
90
88
85
83
81
79
77
75
73
71
69
67
65
63
61
59
57
54
52
50
48
46
43
41
39
37
35
32
30
28
26
24
21
19
17
15
13
10
8
6
146
145
1
G3
G2
G1
3
232
231
220
150
149
144
2
207
147
227
74
87
86
5
4
148
287
194
285
192
142
49
140
47
280
187
278
185
135
42
133
40
276
183
274
181
131
38
129
36
269
176
267
174
124
31
122
29
265
172
263
170
120
27
118
25
258
165
256
163
113
20
111
18
254
161
252
159
109
16
107
14
247
154
245
152
102
9
100
7
229
209
84
64
217
218
236
205
234
203
91
60
89
58
243
198
241
196
98
53
96
51
82
72
225
215
80
70
223
213
78
68
221
211
76
66
62
2/3
3/3
G3
G2
G1
VSS62
VSS61
VSS60
VSS58
VSS104
VSS102
VSS100
VIN_BULK2
VIN_BULK1
VIN_BULK0
VSS126
VSS125
VSS124
VSS123
VSS122
VSS121
VSS120
VSS119
VSS118
VSS117
VSS116
VSS115
VSS114
VSS113
VSS112
VSS111
VSS110
VSS109
VSS108
VSS107
VSS106
VSS105
VSS103
VSS101
VSS99
VSS98
VSS97
VSS96
VSS95
VSS94
VSS93
VSS92
VSS91
VSS90
VSS89
VSS88
VSS87
VSS86
VSS85
VSS84
VSS83
VSS82
VSS81
VSS80
VSS79
VSS78
VSS77
VSS76
VSS75
VSS74
VSS73
VSS72
VSS71
VSS70
VSS69
VSS68
VSS67
VSS66
VSS65
VSS64
VSS63
VSS59
VSS57
VSS56
VSS55
VSS54
VSS53
VSS52
VSS51
VSS50
VSS49
VSS48
VSS47
VSS46
VSS45
VSS44
VSS43
VSS42
VSS41
VSS40
VSS39
VSS38
VSS37
VSS36
VSS35
VSS34
VSS33
VSS32
VSS31
VSS30
VSS29
VSS28
VSS27
VSS26
VSS25
VSS24
VSS23
VSS22
VSS21
VSS20
VSS19
VSS18
VSS17
VSS16
VSS15
VSS14
VSS13
VSS12
VSS11
VSS10
VSS9
VSS8
VSS7
VSS6
VSS5
VSS4
VSS3
VSS2
VSS1
VSS0
1/3
PWR_GOOD||FAIL_n
DQ31_A
CB7_A
CB4_A
CB1_A
CB7_B
ALERT_n
CA0_A
CA0_B
CA1_A
CA1_B
CA2_A
CA2_B
CA3_A
CA3_B
CA4_A
CA4_B
CA5_A
CA5_B
CA6_A
CA6_B
CB6_A
CB5_A
CB3_A
CB2_A
CB0_A
CB6_B
CB5_B
CB4_B
CB3_B
CB2_B
CB1_B
CB0_B
CK_c
CK_t
CS0_A_n
CS0_B_n
CS1_A_n
CS1_B_n
DQ30_A
DQ29_A
DQ28_A
DQ27_A
DQ26_A
DQ25_A
DQ24_A
DQ23_A
DQ22_A
DQ21_A
DQ20_A
DQ19_A
DQ18_A
DQ17_A
DQ16_A
DQ15_A
DQ14_A
DQ13_A
DQ12_A
DQ11_A
DQ10_A
DQ9_A
DQ8_A
DQ7_A
DQ6_A
DQ5_A
DQ4_A
DQ3_A
DQ2_A
DQ1_A
DQ0_A
DQ31_B
DQ30_B
DQ29_B
DQ28_B
DQ27_B
DQ26_B
DQ25_B
DQ24_B
DQ23_B
DQ22_B
DQ21_B
DQ20_B
DQ19_B
DQ18_B
DQ17_B
DQ16_B
DQ15_B
DQ14_B
DQ13_B
DQ12_B
DQ11_B
DQ10_B
DQ9_B
DQ8_B
DQ7_B
DQ6_B
DQ5_B
DQ4_B
DQ3_B
DQ2_B
DQ1_B
DQ0_B
HAS
HSCL
HSDA
LBD||RSP_A_n
LBS||RSP_B_n
PAR_A
PAR_B
RESET_n
RFU6
RFU5
RFU4
RFU3
RFU2
RFU1
RFU0
VIN_MGMT
21
21
SHEETDATE
DEPARTMENT
SIZE
PROJECT DOCUMENT NUMBER REV
REVIEWER
DESIGNER
123
7 3 2 1 6 5 4
E
A
B
C
E
D
C
B
A
7 6 5 4
D
BI
IN
OUTOUT
OUTOUT
BI
OUT
IN
OUT
BIIN
IN
BI
ININ
ININ
ININ
IN
BIIN
IN
BI
OUTOUT
C



Thu Sep 14 16:12:06 2023<NAME_2><NAME_1>MB FABCGT AMDV0289 OF 365P3V3
P12V_MEM_CPU0P3V3_AUXPD_CHD_CPU0_DIMM_SAA8986878890911591598687889091131386878890911313131313131313131389
1313131313 1313131313
1K10%25V0.1UFX7R04020402LF1KEMPTY1/16W1%
10UF25VC0805X6S10%X6S10UF25VC080510%0402LFCHIP10I3C_SPD_DDRD_CPU0_SDAI3C_SPD_DDRAF_CPU0_SDAI3C_SPD_DDRD_CPU0_SCLI3C_SPD_DDRAF_CPU0_SCLM_D_CPU0_ALERT_NPWRGD_CHD_CPU0_DIMMM_D_CPU0_RESET_NPWRGD_CHAF_CPU0M_D_CPU0_SA_RSP<0>M_D_CPU0_SA_PARM_D_CPU0_SB_PARM_D_CPU0_SB_RSP<0>M_D_CPU0_SB_CS_N<1>M_D_CPU0_SA_CS_N<1>M_D_CPU0_SB_CS_N<0>M_D_CPU0_SA_CS_N<0>M_D_CPU0_CLK_DP<0>M_D_CPU0_CLK_DN<0>PD_CHD_CPU0_DIMM_SAA
M_D_CPU0_SB_CA<6:0>M_D_CPU0_SA_CB<7:0>M_D_CPU0_SB_CB<7:0>M_D_CPU0_SB_DQ<31:0>M_D_CPU0_SA_CA<6:0>M_D_CPU0_SA_DQS_DP<9:0>M_D_CPU0_SB_DQS_DN<9:0>M_D_CPU0_SB_DQS_DP<9:0>M_D_CPU0_SA_DQS_DN<9:0>M_D_CPU0_SA_DQ<31:0>
DDR5 - CPU0 CHD
IOSMLFSCONN288_DDR506112002KQSMLFSCONN288_DDR506112002KQIOSCONN288_DDR506112002KQIOSMLF
0402LF35.7K1%CHIP1/16W49.9
J19
J19
J19
2
1C150
2
1C149
2 1
R294 2
1
R92
2
1C100
2
1
R763
0
0
1
3
2
4
5
1
2
3
4
5
6
6
8
7
0
9
7
8
9
0
1
2
3
4
5
1
2
3
4
5
6
7
9
8
6
7
8
9
31
30
29
28
27
26
25
24
23
21
22
20
19
16
18
17
15
14
13
12
11
10
9
8
6
7
5
4
3
6
5
4
3
2
1
0
6
5
4
3
2
1
0
7
2
1
31
0
30
29
28
27
26
25
24
23
22
21
19
20
16
17
18
13
14
15
11
12
10
9
8
6
7
5
4
3
2
1
0
6
5
4
2
3
1
0
7
6
5
4
2
3
1
0
21R1676
R1
DQS7_A_c||TDQS7_A_c
DQS6_A_t||TDQS6_A_t
DQS8_B_t||TDQS8_B_t
DQS8_B_c||TDQS8_B_c
DQS7_B_t||TDQS7_B_t
DQS0_A_c
DQS0_A_t
DQS0_B_c
DQS0_B_t
DQS1_A_c
DQS1_A_t
DQS1_B_c
DQS1_B_t
DQS2_A_c
DQS2_A_t
DQS2_B_c
DQS2_B_t
DQS3_A_c
DQS3_A_t
DQS3_B_c
DQS3_B_t
DQS4_A_c
DQS4_A_t
DQS4_B_c
DQS4_B_t
DQS5_A_c||TDQS5_A_c||DQS5_A_t||TDQS5_A_t
DQS5_A_t||TDQS5_A_t
DQS5_B_c||TDQS5_B_c
DQS5_B_t||TDQS5_B_t
DQS6_A_c||TDQS6_A_c||DQS6_A_t||TDQS6_A_t
DQS6_B_c||TDQS6_B_c
DQS6_B_t||TDQS6_B_t
DQS7_A_t||TDQS7_A_t
DQS7_B_c||TDQS7_B_c
DQS8_A_c||TDQS8_A_c
DQS8_A_t||TDQS8_A_t
DQS9_A_c||TDQS9_A_c
DQS9_A_t||TDQS9_A_t
DQS9_B_c||TDQS9_B_c
DQS9_B_t||TDQS9_B_t||DBI4_B_n93
94
201
200
283
282
190
189
272
271
179
178
261
260
168
167
250
249
157
156
239
238
55
56
137
138
44
45
126
127
33
34
115
116
22
23
104
105
11
12
288
286
284
281
279
277
275
273
270
268
266
264
262
259
257
255
253
251
248
246
244
242
240
237
235
233
230
228
226
224
222
219
216
214
212
210
208
206
204
202
199
197
195
193
191
188
186
184
182
180
177
175
173
171
169
166
164
162
160
158
155
153
151
143
141
139
136
134
132
130
128
125
123
121
119
117
114
112
110
108
106
103
101
99
97
95
92
90
88
85
83
81
79
77
75
73
71
69
67
65
63
61
59
57
54
52
50
48
46
43
41
39
37
35
32
30
28
26
24
21
19
17
15
13
10
8
6
146
145
1
G3
G2
G1
3
232
231
220
150
149
144
2
207
147
227
74
87
86
5
4
148
287
194
285
192
142
49
140
47
280
187
278
185
135
42
133
40
276
183
274
181
131
38
129
36
269
176
267
174
124
31
122
29
265
172
263
170
120
27
118
25
258
165
256
163
113
20
111
18
254
161
252
159
109
16
107
14
247
154
245
152
102
9
100
7
229
209
84
64
217
218
236
205
234
203
91
60
89
58
243
198
241
196
98
53
96
51
82
72
225
215
80
70
223
213
78
68
221
211
76
66
62
2/3
3/3
G3
G2
G1
VSS62
VSS61
VSS60
VSS58
VSS104
VSS102
VSS100
VIN_BULK2
VIN_BULK1
VIN_BULK0
VSS126
VSS125
VSS124
VSS123
VSS122
VSS121
VSS120
VSS119
VSS118
VSS117
VSS116
VSS115
VSS114
VSS113
VSS112
VSS111
VSS110
VSS109
VSS108
VSS107
VSS106
VSS105
VSS103
VSS101
VSS99
VSS98
VSS97
VSS96
VSS95
VSS94
VSS93
VSS92
VSS91
VSS90
VSS89
VSS88
VSS87
VSS86
VSS85
VSS84
VSS83
VSS82
VSS81
VSS80
VSS79
VSS78
VSS77
VSS76
VSS75
VSS74
VSS73
VSS72
VSS71
VSS70
VSS69
VSS68
VSS67
VSS66
VSS65
VSS64
VSS63
VSS59
VSS57
VSS56
VSS55
VSS54
VSS53
VSS52
VSS51
VSS50
VSS49
VSS48
VSS47
VSS46
VSS45
VSS44
VSS43
VSS42
VSS41
VSS40
VSS39
VSS38
VSS37
VSS36
VSS35
VSS34
VSS33
VSS32
VSS31
VSS30
VSS29
VSS28
VSS27
VSS26
VSS25
VSS24
VSS23
VSS22
VSS21
VSS20
VSS19
VSS18
VSS17
VSS16
VSS15
VSS14
VSS13
VSS12
VSS11
VSS10
VSS9
VSS8
VSS7
VSS6
VSS5
VSS4
VSS3
VSS2
VSS1
VSS0
1/3
PWR_GOOD||FAIL_n
DQ31_A
CB7_A
CB4_A
CB1_A
CB7_B
ALERT_n
CA0_A
CA0_B
CA1_A
CA1_B
CA2_A
CA2_B
CA3_A
CA3_B
CA4_A
CA4_B
CA5_A
CA5_B
CA6_A
CA6_B
CB6_A
CB5_A
CB3_A
CB2_A
CB0_A
CB6_B
CB5_B
CB4_B
CB3_B
CB2_B
CB1_B
CB0_B
CK_c
CK_t
CS0_A_n
CS0_B_n
CS1_A_n
CS1_B_n
DQ30_A
DQ29_A
DQ28_A
DQ27_A
DQ26_A
DQ25_A
DQ24_A
DQ23_A
DQ22_A
DQ21_A
DQ20_A
DQ19_A
DQ18_A
DQ17_A
DQ16_A
DQ15_A
DQ14_A
DQ13_A
DQ12_A
DQ11_A
DQ10_A
DQ9_A
DQ8_A
DQ7_A
DQ6_A
DQ5_A
DQ4_A
DQ3_A
DQ2_A
DQ1_A
DQ0_A
DQ31_B
DQ30_B
DQ29_B
DQ28_B
DQ27_B
DQ26_B
DQ25_B
DQ24_B
DQ23_B
DQ22_B
DQ21_B
DQ20_B
DQ19_B
DQ18_B
DQ17_B
DQ16_B
DQ15_B
DQ14_B
DQ13_B
DQ12_B
DQ11_B
DQ10_B
DQ9_B
DQ8_B
DQ7_B
DQ6_B
DQ5_B
DQ4_B
DQ3_B
DQ2_B
DQ1_B
DQ0_B
HAS
HSCL
HSDA
LBD||RSP_A_n
LBS||RSP_B_n
PAR_A
PAR_B
RESET_n
RFU6
RFU5
RFU4
RFU3
RFU2
RFU1
RFU0
VIN_MGMT
21
SHEETDATE
DEPARTMENT
SIZE
PROJECT DOCUMENT NUMBER REV
REVIEWER
DESIGNER
123
7 3 2 1 6 5 4
E
A
B
C
E
D
C
B
A
7 6 5 4
D
BI
IN
OUTOUT
OUTOUT
BI
OUT
IN
OUT
BI
BI
IN
IN
ININ
IN
ININ
IN
ININ
BI
IN
BI
OUTOUT
C



Thu Sep 14 16:12:06 2023<NAME_2><NAME_1>MB FABCGT AMDV0290 OF 365P3V3
P12V_MEM_CPU0P3V3_AUX90159868788899186878889911591414 1414141486878889919014141414141414141414141414141414
1K0.1UF040225V10%X7R0402LF1KEMPTY1%1/16W
10%C0805X6S10UF25VX6S10%25VC080510UF
10CHIP 0402LFPD_CHE_CPU0_DIMM_SAAI3C_SPD_DDRE_CPU0_SCLI3C_SPD_DDRE_CPU0_SDAI3C_SPD_DDRAF_CPU0_SCLPWRGD_CHE_CPU0_DIMMI3C_SPD_DDRAF_CPU0_SDAM_E_CPU0_RESET_NM_E_CPU0_ALERT_NM_E_CPU0_SA_DQS_DN<9:0>M_E_CPU0_SA_DQS_DP<9:0>M_E_CPU0_SB_DQS_DN<9:0>M_E_CPU0_SB_DQS_DP<9:0>49.9PWRGD_CHAF_CPU0PD_CHE_CPU0_DIMM_SAAM_E_CPU0_SA_CS_N<0>M_E_CPU0_CLK_DP<0>M_E_CPU0_SB_PARM_E_CPU0_SA_PARM_E_CPU0_SB_RSP<0>M_E_CPU0_SA_RSP<0>M_E_CPU0_SB_CS_N<1>M_E_CPU0_SA_CS_N<1>M_E_CPU0_SB_CS_N<0>M_E_CPU0_CLK_DN<0>M_E_CPU0_SB_CB<7:0>M_E_CPU0_SB_DQ<31:0>M_E_CPU0_SA_CA<6:0>M_E_CPU0_SB_CA<6:0>M_E_CPU0_SA_CB<7:0>M_E_CPU0_SA_DQ<31:0>
DDR5 - CPU0 CHE
IOSCONN288_DDR506112002KQSMLFIOSCONN288_DDR506112002KQSMLFIOSCONN288_DDR506112002KQSMLF
1/16WCHIP1%54.9K0402LF
J21
J21J21
2
1C153
2
1C151
2
1
R93
2 1
R295
2
1C104
2
1
R5
18
8
14
0
0
1
2
2
1
3
4
3
5
5
4
6
7
8
7
6
8
9
0
0
9
1
2
1
3
2
3
5
4
5
4
6
7
7
6
9
8
9
29
30
28
27
31
26
25
24
22
21
23
6
4
5
3
2
1
0
5
4
6
19
20
16
18
17
11
12
13
15
10
9
8
6
7
5
4
3
1
2
29
31
30
0
24
28
25
27
26
19
23
20
22
21
16
17
14
15
13
12
11
10
9
8
6
7
5
4
3
2
0
1
2
0
1
3
7
6
5
4
3
0
1
2
6
7
5
4
3
0
2
1
R1678
R1572
DQS7_A_c||TDQS7_A_c
DQS6_A_t||TDQS6_A_t
DQS8_B_t||TDQS8_B_t
DQS8_B_c||TDQS8_B_c
DQS7_B_t||TDQS7_B_t
DQS0_A_c
DQS0_A_t
DQS0_B_c
DQS0_B_t
DQS1_A_c
DQS1_A_t
DQS1_B_c
DQS1_B_t
DQS2_A_c
DQS2_A_t
DQS2_B_c
DQS2_B_t
DQS3_A_c
DQS3_A_t
DQS3_B_c
DQS3_B_t
DQS4_A_c
DQS4_A_t
DQS4_B_c
DQS4_B_t
DQS5_A_c||TDQS5_A_c||DQS5_A_t||TDQS5_A_t
DQS5_A_t||TDQS5_A_t
DQS5_B_c||TDQS5_B_c
DQS5_B_t||TDQS5_B_t
DQS6_A_c||TDQS6_A_c||DQS6_A_t||TDQS6_A_t
DQS6_B_c||TDQS6_B_c
DQS6_B_t||TDQS6_B_t
DQS7_A_t||TDQS7_A_t
DQS7_B_c||TDQS7_B_c
DQS8_A_c||TDQS8_A_c
DQS8_A_t||TDQS8_A_t
DQS9_A_c||TDQS9_A_c
DQS9_A_t||TDQS9_A_t
DQS9_B_c||TDQS9_B_c
DQS9_B_t||TDQS9_B_t||DBI4_B_n93
94
201
200
283
282
190
189
272
271
179
178
261
260
168
167
250
249
157
156
239
238
55
56
137
138
44
45
126
127
33
34
115
116
22
23
104
105
11
12
288
286
284
281
279
277
275
273
270
268
266
264
262
259
257
255
253
251
248
246
244
242
240
237
235
233
230
228
226
224
222
219
216
214
212
210
208
206
204
202
199
197
195
193
191
188
186
184
182
180
177
175
173
171
169
166
164
162
160
158
155
153
151
143
141
139
136
134
132
130
128
125
123
121
119
117
114
112
110
108
106
103
101
99
97
95
92
90
88
85
83
81
79
77
75
73
71
69
67
65
63
61
59
57
54
52
50
48
46
43
41
39
37
35
32
30
28
26
24
21
19
17
15
13
10
8
6
146
145
1
G3
G2
G1
3
232
231
220
150
149
144
2
207
147
227
74
87
86
5
4
148
287
194
285
192
142
49
140
47
280
187
278
185
135
42
133
40
276
183
274
181
131
38
129
36
269
176
267
174
124
31
122
29
265
172
263
170
120
27
118
25
258
165
256
163
113
20
111
18
254
161
252
159
109
16
107
14
247
154
245
152
102
9
100
7
229
209
84
64
217
218
236
205
234
203
91
60
89
58
243
198
241
196
98
53
96
51
82
72
225
215
80
70
223
213
78
68
221
211
76
66
62
2/3
3/3
G3
G2
G1
VSS62
VSS61
VSS60
VSS58
VSS104
VSS102
VSS100
VIN_BULK2
VIN_BULK1
VIN_BULK0
VSS126
VSS125
VSS124
VSS123
VSS122
VSS121
VSS120
VSS119
VSS118
VSS117
VSS116
VSS115
VSS114
VSS113
VSS112
VSS111
VSS110
VSS109
VSS108
VSS107
VSS106
VSS105
VSS103
VSS101
VSS99
VSS98
VSS97
VSS96
VSS95
VSS94
VSS93
VSS92
VSS91
VSS90
VSS89
VSS88
VSS87
VSS86
VSS85
VSS84
VSS83
VSS82
VSS81
VSS80
VSS79
VSS78
VSS77
VSS76
VSS75
VSS74
VSS73
VSS72
VSS71
VSS70
VSS69
VSS68
VSS67
VSS66
VSS65
VSS64
VSS63
VSS59
VSS57
VSS56
VSS55
VSS54
VSS53
VSS52
VSS51
VSS50
VSS49
VSS48
VSS47
VSS46
VSS45
VSS44
VSS43
VSS42
VSS41
VSS40
VSS39
VSS38
VSS37
VSS36
VSS35
VSS34
VSS33
VSS32
VSS31
VSS30
VSS29
VSS28
VSS27
VSS26
VSS25
VSS24
VSS23
VSS22
VSS21
VSS20
VSS19
VSS18
VSS17
VSS16
VSS15
VSS14
VSS13
VSS12
VSS11
VSS10
VSS9
VSS8
VSS7
VSS6
VSS5
VSS4
VSS3
VSS2
VSS1
VSS0
1/3
PWR_GOOD||FAIL_n
DQ31_A
CB7_A
CB4_A
CB1_A
CB7_B
ALERT_n
CA0_A
CA0_B
CA1_A
CA1_B
CA2_A
CA2_B
CA3_A
CA3_B
CA4_A
CA4_B
CA5_A
CA5_B
CA6_A
CA6_B
CB6_A
CB5_A
CB3_A
CB2_A
CB0_A
CB6_B
CB5_B
CB4_B
CB3_B
CB2_B
CB1_B
CB0_B
CK_c
CK_t
CS0_A_n
CS0_B_n
CS1_A_n
CS1_B_n
DQ30_A
DQ29_A
DQ28_A
DQ27_A
DQ26_A
DQ25_A
DQ24_A
DQ23_A
DQ22_A
DQ21_A
DQ20_A
DQ19_A
DQ18_A
DQ17_A
DQ16_A
DQ15_A
DQ14_A
DQ13_A
DQ12_A
DQ11_A
DQ10_A
DQ9_A
DQ8_A
DQ7_A
DQ6_A
DQ5_A
DQ4_A
DQ3_A
DQ2_A
DQ1_A
DQ0_A
DQ31_B
DQ30_B
DQ29_B
DQ28_B
DQ27_B
DQ26_B
DQ25_B
DQ24_B
DQ23_B
DQ22_B
DQ21_B
DQ20_B
DQ19_B
DQ18_B
DQ17_B
DQ16_B
DQ15_B
DQ14_B
DQ13_B
DQ12_B
DQ11_B
DQ10_B
DQ9_B
DQ8_B
DQ7_B
DQ6_B
DQ5_B
DQ4_B
DQ3_B
DQ2_B
DQ1_B
DQ0_B
HAS
HSCL
HSDA
LBD||RSP_A_n
LBS||RSP_B_n
PAR_A
PAR_B
RESET_n
RFU6
RFU5
RFU4
RFU3
RFU2
RFU1
RFU0
VIN_MGMT
21
21
SHEETDATE
DEPARTMENT
SIZE
PROJECT DOCUMENT NUMBER REV
REVIEWER
DESIGNER
123
7 3 2 1 6 5 4
E
A
B
C
E
D
C
B
A
7 6 5 4
D
BI
IN
OUTOUT
OUTOUT
BI
OUT
IN
OUT
BIIN
IN
BI
ININ
ININ
ININ
IN
BIIN
IN
BI
OUTOUT
C



Thu Sep 14 16:12:07 2023<NAME_2><NAME_1>MB FABCGT AMDV0291 OF 365P3V3
P12V_MEM_CPU0P3V3_AUXI3C_SPD_DDRF_CPU0_SCL1598687888990868788899015991151515868788899015151515151515151515911515 151515151515151K25V10%0402X7R0.1UFEMPTY0402LF1/16W1%1K
25V10%C080510UFX6S25VC080510UF10%X6S100402LFCHIPI3C_SPD_DDRAF_CPU0_SCLPWRGD_CHF_CPU0_DIMM49.9I3C_SPD_DDRAF_CPU0_SDAI3C_SPD_DDRF_CPU0_SDAPD_CHF_CPU0_DIMM_SAAM_F_CPU0_ALERT_NM_F_CPU0_RESET_NM_F_CPU0_SB_CB<7:0>PWRGD_CHAF_CPU0M_F_CPU0_SB_PARM_F_CPU0_SA_PARM_F_CPU0_SB_RSP<0>M_F_CPU0_SA_RSP<0>M_F_CPU0_SB_CS_N<1>M_F_CPU0_SA_CS_N<1>M_F_CPU0_SB_CS_N<0>M_F_CPU0_SA_CS_N<0>M_F_CPU0_CLK_DP<0>M_F_CPU0_CLK_DN<0>PD_CHF_CPU0_DIMM_SAAM_F_CPU0_SA_CB<7:0>M_F_CPU0_SA_CA<6:0>M_F_CPU0_SA_DQS_DN<9:0>M_F_CPU0_SA_DQS_DP<9:0>M_F_CPU0_SB_DQS_DN<9:0>M_F_CPU0_SB_DQS_DP<9:0>M_F_CPU0_SA_DQ<31:0>M_F_CPU0_SB_CA<6:0>M_F_CPU0_SB_DQ<31:0>
DDR5 - CPU0 CHF
IOSCONN288_DDR506112002KQSMLFSCONN288_DDR506112002KQSMLFIOSCONN288_DDR506112002KQSMLFIO
1/16WCHIP1%84.5K0402LF
J23
J23
J23 2
1C155
2
1C154
2
1
R94
2 1
R296
2
1C108
2
1
R764
0
1
2
4
3
1
0
2
3
4
5
6
7
9
8
6
5
7
8
9
0
1
2
4
3
0
1
2
3
4
5
6
7
9
8
5
7
6
8
9
1
0
2
3
4
5
7
6
8
9
10
11
12
13
15
14
18
17
16
21
22
20
23
19
26
27
25
28
24
0
30
31
29
2
1
3
4
5
7
6
8
9
10
14
15
13
12
11
17
18
16
20
19
23
21
22
24
25
26
31
27
28
30
29
6
5
3
4
2
1
0
6
5
3
4
1
2
0
6
7
4
5
3
2
1
0
7
6
5
3
4
2
1
0
R1679
R1573
DQS7_A_c||TDQS7_A_c
DQS6_A_t||TDQS6_A_t
DQS8_B_t||TDQS8_B_t
DQS8_B_c||TDQS8_B_c
DQS7_B_t||TDQS7_B_t
DQS0_A_c
DQS0_A_t
DQS0_B_c
DQS0_B_t
DQS1_A_c
DQS1_A_t
DQS1_B_c
DQS1_B_t
DQS2_A_c
DQS2_A_t
DQS2_B_c
DQS2_B_t
DQS3_A_c
DQS3_A_t
DQS3_B_c
DQS3_B_t
DQS4_A_c
DQS4_A_t
DQS4_B_c
DQS4_B_t
DQS5_A_c||TDQS5_A_c||DQS5_A_t||TDQS5_A_t
DQS5_A_t||TDQS5_A_t
DQS5_B_c||TDQS5_B_c
DQS5_B_t||TDQS5_B_t
DQS6_A_c||TDQS6_A_c||DQS6_A_t||TDQS6_A_t
DQS6_B_c||TDQS6_B_c
DQS6_B_t||TDQS6_B_t
DQS7_A_t||TDQS7_A_t
DQS7_B_c||TDQS7_B_c
DQS8_A_c||TDQS8_A_c
DQS8_A_t||TDQS8_A_t
DQS9_A_c||TDQS9_A_c
DQS9_A_t||TDQS9_A_t
DQS9_B_c||TDQS9_B_c
DQS9_B_t||TDQS9_B_t||DBI4_B_n93
94
201
200
283
282
190
189
272
271
179
178
261
260
168
167
250
249
157
156
239
238
55
56
137
138
44
45
126
127
33
34
115
116
22
23
104
105
11
12
288
286
284
281
279
277
275
273
270
268
266
264
262
259
257
255
253
251
248
246
244
242
240
237
235
233
230
228
226
224
222
219
216
214
212
210
208
206
204
202
199
197
195
193
191
188
186
184
182
180
177
175
173
171
169
166
164
162
160
158
155
153
151
143
141
139
136
134
132
130
128
125
123
121
119
117
114
112
110
108
106
103
101
99
97
95
92
90
88
85
83
81
79
77
75
73
71
69
67
65
63
61
59
57
54
52
50
48
46
43
41
39
37
35
32
30
28
26
24
21
19
17
15
13
10
8
6
146
145
1
G3
G2
G1
3
232
231
220
150
149
144
2
207
147
227
74
87
86
5
4
148
287
194
285
192
142
49
140
47
280
187
278
185
135
42
133
40
276
183
274
181
131
38
129
36
269
176
267
174
124
31
122
29
265
172
263
170
120
27
118
25
258
165
256
163
113
20
111
18
254
161
252
159
109
16
107
14
247
154
245
152
102
9
100
7
229
209
84
64
217
218
236
205
234
203
91
60
89
58
243
198
241
196
98
53
96
51
82
72
225
215
80
70
223
213
78
68
221
211
76
66
62
2/3
3/3
G3
G2
G1
VSS62
VSS61
VSS60
VSS58
VSS104
VSS102
VSS100
VIN_BULK2
VIN_BULK1
VIN_BULK0
VSS126
VSS125
VSS124
VSS123
VSS122
VSS121
VSS120
VSS119
VSS118
VSS117
VSS116
VSS115
VSS114
VSS113
VSS112
VSS111
VSS110
VSS109
VSS108
VSS107
VSS106
VSS105
VSS103
VSS101
VSS99
VSS98
VSS97
VSS96
VSS95
VSS94
VSS93
VSS92
VSS91
VSS90
VSS89
VSS88
VSS87
VSS86
VSS85
VSS84
VSS83
VSS82
VSS81
VSS80
VSS79
VSS78
VSS77
VSS76
VSS75
VSS74
VSS73
VSS72
VSS71
VSS70
VSS69
VSS68
VSS67
VSS66
VSS65
VSS64
VSS63
VSS59
VSS57
VSS56
VSS55
VSS54
VSS53
VSS52
VSS51
VSS50
VSS49
VSS48
VSS47
VSS46
VSS45
VSS44
VSS43
VSS42
VSS41
VSS40
VSS39
VSS38
VSS37
VSS36
VSS35
VSS34
VSS33
VSS32
VSS31
VSS30
VSS29
VSS28
VSS27
VSS26
VSS25
VSS24
VSS23
VSS22
VSS21
VSS20
VSS19
VSS18
VSS17
VSS16
VSS15
VSS14
VSS13
VSS12
VSS11
VSS10
VSS9
VSS8
VSS7
VSS6
VSS5
VSS4
VSS3
VSS2
VSS1
VSS0
1/3
PWR_GOOD||FAIL_n
DQ31_A
CB7_A
CB4_A
CB1_A
CB7_B
ALERT_n
CA0_A
CA0_B
CA1_A
CA1_B
CA2_A
CA2_B
CA3_A
CA3_B
CA4_A
CA4_B
CA5_A
CA5_B
CA6_A
CA6_B
CB6_A
CB5_A
CB3_A
CB2_A
CB0_A
CB6_B
CB5_B
CB4_B
CB3_B
CB2_B
CB1_B
CB0_B
CK_c
CK_t
CS0_A_n
CS0_B_n
CS1_A_n
CS1_B_n
DQ30_A
DQ29_A
DQ28_A
DQ27_A
DQ26_A
DQ25_A
DQ24_A
DQ23_A
DQ22_A
DQ21_A
DQ20_A
DQ19_A
DQ18_A
DQ17_A
DQ16_A
DQ15_A
DQ14_A
DQ13_A
DQ12_A
DQ11_A
DQ10_A
DQ9_A
DQ8_A
DQ7_A
DQ6_A
DQ5_A
DQ4_A
DQ3_A
DQ2_A
DQ1_A
DQ0_A
DQ31_B
DQ30_B
DQ29_B
DQ28_B
DQ27_B
DQ26_B
DQ25_B
DQ24_B
DQ23_B
DQ22_B
DQ21_B
DQ20_B
DQ19_B
DQ18_B
DQ17_B
DQ16_B
DQ15_B
DQ14_B
DQ13_B
DQ12_B
DQ11_B
DQ10_B
DQ9_B
DQ8_B
DQ7_B
DQ6_B
DQ5_B
DQ4_B
DQ3_B
DQ2_B
DQ1_B
DQ0_B
HAS
HSCL
HSDA
LBD||RSP_A_n
LBS||RSP_B_n
PAR_A
PAR_B
RESET_n
RFU6
RFU5
RFU4
RFU3
RFU2
RFU1
RFU0
VIN_MGMT
21
21
SHEETDATE
DEPARTMENT
SIZE
PROJECT DOCUMENT NUMBER REV
REVIEWER
DESIGNER
123
7 3 2 1 6 5 4
E
A
B
C
E
D
C
B
A
7 6 5 4
D
BI
IN
OUTOUT
OUTOUT
BI
OUT
IN
OUT
BI
BI
IN
IN
IN
ININ
IN
IN
ININ
IN
BI
BI
IN
OUTOUT
C



Thu Sep 14 16:12:07 2023<NAME_2><NAME_1>MB FABCGT AMDV0292 OF 365P3V3P3V3_AUXP3V3
P12V_MEM_CPU0
P3V3_AUXP3V3_AUXP3V3_AUX9394959697159921599394959697161616161616161616169293949596971616161616161616169216 8292 93 94 95 96 979293949596971616I3C_SPD_DDRGL_CPU0_SDAPD_CHG_CPU0_DIMM0_SAA1K
X6S10%10UF25VC0805X6S10%25VC080510UF
EMPTY1/16W1%1K0402LF 0402LF1KEMPTY1/16W1%040210%X7R0.1UF25V1/16WCHIP10K0402LF1%100402LFCHIPI3C_SPD_DDRGL_CPU0_SCLI3C_SPD_DDRG_CPU0_SCL49.9PWRGD_CHG_CPU0_DIMM0M_G_CPU0_SB_CB<7:0>I3C_SPD_DDRG_CPU0_SDAIOSMLFSCONN288_DDR506112002KQSCONN288_DDR506112002KQSMLFIOIOSCONN288_DDR506112002KQSMLF
CHIP0402LF1%1/16W10K1/16W0402LF5%CHIP01/16W0402LFEMPTY1%10K05%CHIP0402LF1/16WSMLFB0530WS7FEMPTYDDR5 - CPU0 CHG
M_G_CPU0_SA_CB<7:0>M_G_CPU0_SB_CA<6:0>M_G_CPU0_SA_CA<6:0> M_G_CPU0_SA_DQ<31:0>M_G_CPU0_SB_DQ<31:0>M_G_CPU0_SA_DQS_DN<9:0>M_G_CPU0_SA_DQS_DP<9:0>M_G_CPU0_SB_DQS_DP<9:0>M_G_CPU0_SB_DQS_DN<9:0>PWRGD_CHGL_CPU0M_G_CPU0_SA_RSP<0>M_G_CPU0_SA_CS_N<1>M_G_CPU0_SB_PARM_G_CPU0_SA_PARM_G_CPU0_SB_CS_N<1>M_G_CPU0_SB_CS_N<0>M_G_CPU0_SA_CS_N<0>M_G_CPU0_CLK_DP<0>M_G_CPU0_CLK_DN<0>PD_CHG_CPU0_DIMM0_SAAM_G_CPU0_SB_RSP<0>PWRGD_CHGL_CPU0_R2PWRGD_CHGL_CPU0_R1PWRGD_CHGL_CPU0PWRGD_CHGL_CPU0M_G_CPU0_ALERT_NM_G_CPU0_RESET_N
J16
J16
J16
2
1C158
2
1C157
2
1
R95
2
1
R96
2 1
R297
2
1C112
2
1
R35
24
5
8
9
7
12
11
10
13
14
17
16
15
18
19
22
21
20
24
23
26
27
25
30
28
29
31
9
8
9
8
7
7
5
6
4
3
5
6
4
2
3
2
1
0
9
8
0
1
8
9
7
6
5
4
3
6
7
5
4
3
0
2
1
0
0
1
2
1
2
3
4
5
6
7
0
1
2
3
4
5
6
7
1
0
4
3
2
5
6
9
8
7
10
11
14
13
12
16
15
17
19
18
20
21
22
23
25
26
27
29
28
30
31
1
0
3
4
2
0
1
2
3
4
5
6
1
0
2
3
4
5
6
6
R1680
R1574
DQS7_A_c||TDQS7_A_c
DQS6_A_t||TDQS6_A_t
DQS8_B_t||TDQS8_B_t
DQS8_B_c||TDQS8_B_c
DQS7_B_t||TDQS7_B_t
DQS0_A_c
DQS0_A_t
DQS0_B_c
DQS0_B_t
DQS1_A_c
DQS1_A_t
DQS1_B_c
DQS1_B_t
DQS2_A_c
DQS2_A_t
DQS2_B_c
DQS2_B_t
DQS3_A_c
DQS3_A_t
DQS3_B_c
DQS3_B_t
DQS4_A_c
DQS4_A_t
DQS4_B_c
DQS4_B_t
DQS5_A_c||TDQS5_A_c||DQS5_A_t||TDQS5_A_t
DQS5_A_t||TDQS5_A_t
DQS5_B_c||TDQS5_B_c
DQS5_B_t||TDQS5_B_t
DQS6_A_c||TDQS6_A_c||DQS6_A_t||TDQS6_A_t
DQS6_B_c||TDQS6_B_c
DQS6_B_t||TDQS6_B_t
DQS7_A_t||TDQS7_A_t
DQS7_B_c||TDQS7_B_c
DQS8_A_c||TDQS8_A_c
DQS8_A_t||TDQS8_A_t
DQS9_A_c||TDQS9_A_c
DQS9_A_t||TDQS9_A_t
DQS9_B_c||TDQS9_B_c
DQS9_B_t||TDQS9_B_t||DBI4_B_n
21
93
94
201
200
283
282
190
189
272
271
179
178
261
260
168
167
250
249
157
156
239
238
55
56
137
138
44
45
126
127
33
34
115
116
22
23
104
105
11
12
288
286
284
281
279
277
275
273
270
268
266
264
262
259
257
255
253
251
248
246
244
242
240
237
235
233
230
228
226
224
222
219
216
214
212
210
208
206
204
202
199
197
195
193
191
188
186
184
182
180
177
175
173
171
169
166
164
162
160
158
155
153
151
143
141
139
136
134
132
130
128
125
123
121
119
117
114
112
110
108
106
103
101
99
97
95
92
90
88
85
83
81
79
77
75
73
71
69
67
65
63
61
59
57
54
52
50
48
46
43
41
39
37
35
32
30
28
26
24
21
19
17
15
13
10
8
6
146
145
1
G3
G2
G1
3
232
231
220
150
149
144
2
207
147
227
74
87
86
5
4
148
287
194
285
192
142
49
140
47
280
187
278
185
135
42
133
40
276
183
274
181
131
38
129
36
269
176
267
174
124
31
122
29
265
172
263
170
120
27
118
25
258
165
256
163
113
20
111
18
254
161
252
159
109
16
107
14
247
154
245
152
102
9
100
7
229
209
84
64
217
218
236
205
234
203
91
60
89
58
243
198
241
196
98
53
96
51
82
72
225
215
80
70
223
213
78
68
221
211
76
66
62
D8004
CA
2/3
1/3
PWR_GOOD||FAIL_n
DQ31_A
CB7_A
CB4_A
CB1_A
CB7_B
ALERT_n
CA0_A
CA0_B
CA1_A
CA1_B
CA2_A
CA2_B
CA3_A
CA3_B
CA4_A
CA4_B
CA5_A
CA5_B
CA6_A
CA6_B
CB6_A
CB5_A
CB3_A
CB2_A
CB0_A
CB6_B
CB5_B
CB4_B
CB3_B
CB2_B
CB1_B
CB0_B
CK_c
CK_t
CS0_A_n
CS0_B_n
CS1_A_n
CS1_B_n
DQ30_A
DQ29_A
DQ28_A
DQ27_A
DQ26_A
DQ25_A
DQ24_A
DQ23_A
DQ22_A
DQ21_A
DQ20_A
DQ19_A
DQ18_A
DQ17_A
DQ16_A
DQ15_A
DQ14_A
DQ13_A
DQ12_A
DQ11_A
DQ10_A
DQ9_A
DQ8_A
DQ7_A
DQ6_A
DQ5_A
DQ4_A
DQ3_A
DQ2_A
DQ1_A
DQ0_A
DQ31_B
DQ30_B
DQ29_B
DQ28_B
DQ27_B
DQ26_B
DQ25_B
DQ24_B
DQ23_B
DQ22_B
DQ21_B
DQ20_B
DQ19_B
DQ18_B
DQ17_B
DQ16_B
DQ15_B
DQ14_B
DQ13_B
DQ12_B
DQ11_B
DQ10_B
DQ9_B
DQ8_B
DQ7_B
DQ6_B
DQ5_B
DQ4_B
DQ3_B
DQ2_B
DQ1_B
DQ0_B
HAS
HSCL
HSDA
LBD||RSP_A_n
LBS||RSP_B_n
PAR_A
PAR_B
RESET_n
RFU6
RFU5
RFU4
RFU3
RFU2
RFU1
RFU0
VIN_MGMT
3/3
G3
G2
G1
VSS62
VSS61
VSS60
VSS58
VSS104
VSS102
VSS100
VIN_BULK2
VIN_BULK1
VIN_BULK0
VSS126
VSS125
VSS124
VSS123
VSS122
VSS121
VSS120
VSS119
VSS118
VSS117
VSS116
VSS115
VSS114
VSS113
VSS112
VSS111
VSS110
VSS109
VSS108
VSS107
VSS106
VSS105
VSS103
VSS101
VSS99
VSS98
VSS97
VSS96
VSS95
VSS94
VSS93
VSS92
VSS91
VSS90
VSS89
VSS88
VSS87
VSS86
VSS85
VSS84
VSS83
VSS82
VSS81
VSS80
VSS79
VSS78
VSS77
VSS76
VSS75
VSS74
VSS73
VSS72
VSS71
VSS70
VSS69
VSS68
VSS67
VSS66
VSS65
VSS64
VSS63
VSS59
VSS57
VSS56
VSS55
VSS54
VSS53
VSS52
VSS51
VSS50
VSS49
VSS48
VSS47
VSS46
VSS45
VSS44
VSS43
VSS42
VSS41
VSS40
VSS39
VSS38
VSS37
VSS36
VSS35
VSS34
VSS33
VSS32
VSS31
VSS30
VSS29
VSS28
VSS27
VSS26
VSS25
VSS24
VSS23
VSS22
VSS21
VSS20
VSS19
VSS18
VSS17
VSS16
VSS15
VSS14
VSS13
VSS12
VSS11
VSS10
VSS9
VSS8
VSS7
VSS6
VSS5
VSS4
VSS3
VSS2
VSS1
VSS0
21
21
21
21
2
1
21
SHEETDATE
DEPARTMENT
SIZE
PROJECT DOCUMENT NUMBER REV
REVIEWER
DESIGNER
123
7 3 2 1 6 5 4
E
A
B
C
E
D
C
B
A
7 6 5 4
D
IN
BI
OUT
IN
BI
BIBI
OUT
IN
IN
IN
OUT
OUTOUT
OUTOUTIN
BI
ININ
IN
IN
ININ
OUT
BI
INBI
BI
OUT
R8084
R8085
R8083
R8038
C



Thu Sep 14 16:12:08 2023<NAME_2><NAME_1>MB FABCGT AMDV0293 OF 365P3V3
P12V_MEM_CPU0P3V3_AUX929495969715915992949596979317179294959697
1717171717171717171717171717171717931717171K
10%C0805X6S25V10UFC080525V10UF10%X6S
1%0402LFEMPTY1/16W1K25V0.1UF10%X7R0402100402LFCHIPI3C_SPD_DDRGL_CPU0_SDAI3C_SPD_DDRGL_CPU0_SCLI3C_SPD_DDRH_CPU0_SCLI3C_SPD_DDRH_CPU0_SDAPD_CHH_CPU0_DIMM_SAAM_H_CPU0_ALERT_NM_H_CPU0_RESET_NPWRGD_CHGL_CPU049.91/16WCHIP1%15.4K0402LF
SMLFIOSCONN288_DDR506112002KQSMLFIOSCONN288_DDR506112002KQIO
DDR5 - CPU0 CHH
M_H_CPU0_SA_DQ<31:0>M_H_CPU0_SA_CB<7:0>M_H_CPU0_SA_CA<6:0>M_H_CPU0_SB_CA<6:0>M_H_CPU0_SB_DQ<31:0>M_H_CPU0_SA_DQS_DN<9:0>M_H_CPU0_SA_DQS_DP<9:0>M_H_CPU0_SB_DQS_DP<9:0>M_H_CPU0_SB_DQS_DN<9:0>M_H_CPU0_SB_PARM_H_CPU0_SA_PARM_H_CPU0_SB_CS_N<1>M_H_CPU0_SA_CS_N<1>M_H_CPU0_SB_CS_N<0>M_H_CPU0_SA_CS_N<0>M_H_CPU0_CLK_DP<0>M_H_CPU0_CLK_DN<0>PD_CHH_CPU0_DIMM_SAAM_H_CPU0_SA_RSP<0>M_H_CPU0_SB_RSP<0>SCONN288_DDR506112002KQSMLFM_H_CPU0_SB_CB<7:0>PWRGD_CHH_CPU0_DIMM
J69
J69
J69
2
1C161
2
1C159
2
1
R97
2 1
R298
2
1C116
2
1
R765
7
6
8
9
11
12
13
14
10
19
16
18
15
20
21
22
25
23
24
29
30
28
27
26
31
9
8
9
8
7
6
4
5
3
5
7
6
4
3
2
1
0
8
9
0
2
1
8
9
7
6
5
3
4
5
7
6
4
0
3
2
1
0
0
1
2
1
2
3
4
6
5
7
0
1
2
3
0
1
2
3
4
5
6
7
8
9
10
11
12
13
14
16
15
17
19
20
22
21
18
24
25
27
26
23
29
31
30
28
4
5
7
6
0
1
2
4
3
5
6
0
1
2
3
4
5
6
0
1
2
3
4
5
17
R1681
R1575
DQS7_A_c||TDQS7_A_c
DQS6_A_t||TDQS6_A_t
DQS8_B_t||TDQS8_B_t
DQS8_B_c||TDQS8_B_c
DQS7_B_t||TDQS7_B_t
DQS0_A_c
DQS0_A_t
DQS0_B_c
DQS0_B_t
DQS1_A_c
DQS1_A_t
DQS1_B_c
DQS1_B_t
DQS2_A_c
DQS2_A_t
DQS2_B_c
DQS2_B_t
DQS3_A_c
DQS3_A_t
DQS3_B_c
DQS3_B_t
DQS4_A_c
DQS4_A_t
DQS4_B_c
DQS4_B_t
DQS5_A_c||TDQS5_A_c||DQS5_A_t||TDQS5_A_t
DQS5_A_t||TDQS5_A_t
DQS5_B_c||TDQS5_B_c
DQS5_B_t||TDQS5_B_t
DQS6_A_c||TDQS6_A_c||DQS6_A_t||TDQS6_A_t
DQS6_B_c||TDQS6_B_c
DQS6_B_t||TDQS6_B_t
DQS7_A_t||TDQS7_A_t
DQS7_B_c||TDQS7_B_c
DQS8_A_c||TDQS8_A_c
DQS8_A_t||TDQS8_A_t
DQS9_A_c||TDQS9_A_c
DQS9_A_t||TDQS9_A_t
DQS9_B_c||TDQS9_B_c
DQS9_B_t||TDQS9_B_t||DBI4_B_n93
94
201
200
283
282
190
189
272
271
179
178
261
260
168
167
250
249
157
156
239
238
55
56
137
138
44
45
126
127
33
34
115
116
22
23
104
105
11
12
288
286
284
281
279
277
275
273
270
268
266
264
262
259
257
255
253
251
248
246
244
242
240
237
235
233
230
228
226
224
222
219
216
214
212
210
208
206
204
202
199
197
195
193
191
188
186
184
182
180
177
175
173
171
169
166
164
162
160
158
155
153
151
143
141
139
136
134
132
130
128
125
123
121
119
117
114
112
110
108
106
103
101
99
97
95
92
90
88
85
83
81
79
77
75
73
71
69
67
65
63
61
59
57
54
52
50
48
46
43
41
39
37
35
32
30
28
26
24
21
19
17
15
13
10
8
6
146
145
1
G3
G2
G1
3
232
231
220
150
149
144
2
207
147
227
74
87
86
5
4
148
287
194
285
192
142
49
140
47
280
187
278
185
135
42
133
40
276
183
274
181
131
38
129
36
269
176
267
174
124
31
122
29
265
172
263
170
120
27
118
25
258
165
256
163
113
20
111
18
254
161
252
159
109
16
107
14
247
154
245
152
102
9
100
7
229
209
84
64
217
218
236
205
234
203
91
60
89
58
243
198
241
196
98
53
96
51
82
72
225
215
80
70
223
213
78
68
221
211
76
66
62
2/3
1/3
PWR_GOOD||FAIL_n
DQ31_A
CB7_A
CB4_A
CB1_A
CB7_B
ALERT_n
CA0_A
CA0_B
CA1_A
CA1_B
CA2_A
CA2_B
CA3_A
CA3_B
CA4_A
CA4_B
CA5_A
CA5_B
CA6_A
CA6_B
CB6_A
CB5_A
CB3_A
CB2_A
CB0_A
CB6_B
CB5_B
CB4_B
CB3_B
CB2_B
CB1_B
CB0_B
CK_c
CK_t
CS0_A_n
CS0_B_n
CS1_A_n
CS1_B_n
DQ30_A
DQ29_A
DQ28_A
DQ27_A
DQ26_A
DQ25_A
DQ24_A
DQ23_A
DQ22_A
DQ21_A
DQ20_A
DQ19_A
DQ18_A
DQ17_A
DQ16_A
DQ15_A
DQ14_A
DQ13_A
DQ12_A
DQ11_A
DQ10_A
DQ9_A
DQ8_A
DQ7_A
DQ6_A
DQ5_A
DQ4_A
DQ3_A
DQ2_A
DQ1_A
DQ0_A
DQ31_B
DQ30_B
DQ29_B
DQ28_B
DQ27_B
DQ26_B
DQ25_B
DQ24_B
DQ23_B
DQ22_B
DQ21_B
DQ20_B
DQ19_B
DQ18_B
DQ17_B
DQ16_B
DQ15_B
DQ14_B
DQ13_B
DQ12_B
DQ11_B
DQ10_B
DQ9_B
DQ8_B
DQ7_B
DQ6_B
DQ5_B
DQ4_B
DQ3_B
DQ2_B
DQ1_B
DQ0_B
HAS
HSCL
HSDA
LBD||RSP_A_n
LBS||RSP_B_n
PAR_A
PAR_B
RESET_n
RFU6
RFU5
RFU4
RFU3
RFU2
RFU1
RFU0
VIN_MGMT
3/3
G3
G2
G1
VSS62
VSS61
VSS60
VSS58
VSS104
VSS102
VSS100
VIN_BULK2
VIN_BULK1
VIN_BULK0
VSS126
VSS125
VSS124
VSS123
VSS122
VSS121
VSS120
VSS119
VSS118
VSS117
VSS116
VSS115
VSS114
VSS113
VSS112
VSS111
VSS110
VSS109
VSS108
VSS107
VSS106
VSS105
VSS103
VSS101
VSS99
VSS98
VSS97
VSS96
VSS95
VSS94
VSS93
VSS92
VSS91
VSS90
VSS89
VSS88
VSS87
VSS86
VSS85
VSS84
VSS83
VSS82
VSS81
VSS80
VSS79
VSS78
VSS77
VSS76
VSS75
VSS74
VSS73
VSS72
VSS71
VSS70
VSS69
VSS68
VSS67
VSS66
VSS65
VSS64
VSS63
VSS59
VSS57
VSS56
VSS55
VSS54
VSS53
VSS52
VSS51
VSS50
VSS49
VSS48
VSS47
VSS46
VSS45
VSS44
VSS43
VSS42
VSS41
VSS40
VSS39
VSS38
VSS37
VSS36
VSS35
VSS34
VSS33
VSS32
VSS31
VSS30
VSS29
VSS28
VSS27
VSS26
VSS25
VSS24
VSS23
VSS22
VSS21
VSS20
VSS19
VSS18
VSS17
VSS16
VSS15
VSS14
VSS13
VSS12
VSS11
VSS10
VSS9
VSS8
VSS7
VSS6
VSS5
VSS4
VSS3
VSS2
VSS1
VSS0
21
21
SHEETDATE
DEPARTMENT
SIZE
PROJECT DOCUMENT NUMBER REV
REVIEWER
DESIGNER
123
7 3 2 1 6 5 4
E
A
B
C
E
D
C
B
A
7 6 5 4
D
IN
IN
BI
BI
IN
IN
IN
OUT
OUTOUT
OUTOUT
IN
BI
IN
OUT
IN
IN
IN
IN
IN
OUT
BI
INBI
BI
OUT
C



Thu Sep 14 16:12:08 2023<NAME_2><NAME_1>MB FABCGT AMDV0294 OF 365
P3V3_AUXP12V_MEM_CPU0
P3V3929395969715915992939596979492939596971818181818181818941818 1818181818181818181818181K040225V0.1UFX7R10%1%1/16WEMPTY1K0402LF
C080525V10UF10%X6SC080525V10UF10%X6S100402LFCHIPI3C_SPD_DDRGL_CPU0_SDAPWRGD_CHI_CPU0_DIMMI3C_SPD_DDRI_CPU0_SCLI3C_SPD_DDRGL_CPU0_SCLPD_CHI_CPU0_DIMM_SAA49.9I3C_SPD_DDRI_CPU0_SDAPWRGD_CHGL_CPU0M_I_CPU0_CLK_DP<0>M_I_CPU0_SA_CS_N<0>M_I_CPU0_SB_CS_N<0>M_I_CPU0_SA_CS_N<1>M_I_CPU0_SB_CS_N<1>M_I_CPU0_SA_PARM_I_CPU0_SB_PARM_I_CPU0_CLK_DN<0>PD_CHI_CPU0_DIMM_SAAM_I_CPU0_SB_RSP<0>M_I_CPU0_SA_RSP<0>M_I_CPU0_SB_DQS_DN<9:0>M_I_CPU0_SB_DQS_DP<9:0>M_I_CPU0_SA_DQS_DP<9:0>M_I_CPU0_SA_DQS_DN<9:0>M_I_CPU0_SB_DQ<31:0>M_I_CPU0_SB_CA<6:0>M_I_CPU0_SA_CA<6:0>M_I_CPU0_SB_CB<7:0>M_I_CPU0_SA_CB<7:0>M_I_CPU0_SA_DQ<31:0>
DDR5 - CPU0 CHI
SMLFIOSCONN288_DDR506112002KQIOSCONN288_DDR506112002KQSMLFSCONN288_DDR506112002KQSMLFIO
0402LF23.2K1%CHIP1/16WM_I_CPU0_RESET_NM_I_CPU0_ALERT_N
J18
J18J18 2
1C163
2
1C162
2
1
R98
2 1
R299
2
1C120
2
1
R766
5
4
6
3
2
1
5
6
4
3
2
0
1
6
5
4
0
1
2
3
5
6
7
0
30
31
29
28
27
26
25
24
23
22
21
20
19
18
17
16
15
14
12
13
11
10
9
8
7
6
5
4
1
3
2
0
4
3
2
1
0
7
6
5
4
0
1
3
0
2
1
3
4
5
2
7
6
0
1
2
3
4
5
6
7
8
9
8
0
2
1
3
4
6
7
0
9
1
2
3
4
5
6
7
9
8
8
9
5
31
30
27
28
29
26
24
25
23
22
20
21
19
17
18
15
16
14
13
12
10
11
9
8
7
R1683
R1576
DQS7_A_c||TDQS7_A_c
DQS6_A_t||TDQS6_A_t
DQS8_B_t||TDQS8_B_t
DQS8_B_c||TDQS8_B_c
DQS7_B_t||TDQS7_B_t
DQS0_A_c
DQS0_A_t
DQS0_B_c
DQS0_B_t
DQS1_A_c
DQS1_A_t
DQS1_B_c
DQS1_B_t
DQS2_A_c
DQS2_A_t
DQS2_B_c
DQS2_B_t
DQS3_A_c
DQS3_A_t
DQS3_B_c
DQS3_B_t
DQS4_A_c
DQS4_A_t
DQS4_B_c
DQS4_B_t
DQS5_A_c||TDQS5_A_c||DQS5_A_t||TDQS5_A_t
DQS5_A_t||TDQS5_A_t
DQS5_B_c||TDQS5_B_c
DQS5_B_t||TDQS5_B_t
DQS6_A_c||TDQS6_A_c||DQS6_A_t||TDQS6_A_t
DQS6_B_c||TDQS6_B_c
DQS6_B_t||TDQS6_B_t
DQS7_A_t||TDQS7_A_t
DQS7_B_c||TDQS7_B_c
DQS8_A_c||TDQS8_A_c
DQS8_A_t||TDQS8_A_t
DQS9_A_c||TDQS9_A_c
DQS9_A_t||TDQS9_A_t
DQS9_B_c||TDQS9_B_c
DQS9_B_t||TDQS9_B_t||DBI4_B_n93
94
201
200
283
282
190
189
272
271
179
178
261
260
168
167
250
249
157
156
239
238
55
56
137
138
44
45
126
127
33
34
115
116
22
23
104
105
11
12
288
286
284
281
279
277
275
273
270
268
266
264
262
259
257
255
253
251
248
246
244
242
240
237
235
233
230
228
226
224
222
219
216
214
212
210
208
206
204
202
199
197
195
193
191
188
186
184
182
180
177
175
173
171
169
166
164
162
160
158
155
153
151
143
141
139
136
134
132
130
128
125
123
121
119
117
114
112
110
108
106
103
101
99
97
95
92
90
88
85
83
81
79
77
75
73
71
69
67
65
63
61
59
57
54
52
50
48
46
43
41
39
37
35
32
30
28
26
24
21
19
17
15
13
10
8
6
146
145
1
G3
G2
G1
3
232
231
220
150
149
144
2
207
147
227
74
87
86
5
4
148
287
194
285
192
142
49
140
47
280
187
278
185
135
42
133
40
276
183
274
181
131
38
129
36
269
176
267
174
124
31
122
29
265
172
263
170
120
27
118
25
258
165
256
163
113
20
111
18
254
161
252
159
109
16
107
14
247
154
245
152
102
9
100
7
229
209
84
64
217
218
236
205
234
203
91
60
89
58
243
198
241
196
98
53
96
51
82
72
225
215
80
70
223
213
78
68
221
211
76
66
62
2/3
1/3
PWR_GOOD||FAIL_n
DQ31_A
CB7_A
CB4_A
CB1_A
CB7_B
ALERT_n
CA0_A
CA0_B
CA1_A
CA1_B
CA2_A
CA2_B
CA3_A
CA3_B
CA4_A
CA4_B
CA5_A
CA5_B
CA6_A
CA6_B
CB6_A
CB5_A
CB3_A
CB2_A
CB0_A
CB6_B
CB5_B
CB4_B
CB3_B
CB2_B
CB1_B
CB0_B
CK_c
CK_t
CS0_A_n
CS0_B_n
CS1_A_n
CS1_B_n
DQ30_A
DQ29_A
DQ28_A
DQ27_A
DQ26_A
DQ25_A
DQ24_A
DQ23_A
DQ22_A
DQ21_A
DQ20_A
DQ19_A
DQ18_A
DQ17_A
DQ16_A
DQ15_A
DQ14_A
DQ13_A
DQ12_A
DQ11_A
DQ10_A
DQ9_A
DQ8_A
DQ7_A
DQ6_A
DQ5_A
DQ4_A
DQ3_A
DQ2_A
DQ1_A
DQ0_A
DQ31_B
DQ30_B
DQ29_B
DQ28_B
DQ27_B
DQ26_B
DQ25_B
DQ24_B
DQ23_B
DQ22_B
DQ21_B
DQ20_B
DQ19_B
DQ18_B
DQ17_B
DQ16_B
DQ15_B
DQ14_B
DQ13_B
DQ12_B
DQ11_B
DQ10_B
DQ9_B
DQ8_B
DQ7_B
DQ6_B
DQ5_B
DQ4_B
DQ3_B
DQ2_B
DQ1_B
DQ0_B
HAS
HSCL
HSDA
LBD||RSP_A_n
LBS||RSP_B_n
PAR_A
PAR_B
RESET_n
RFU6
RFU5
RFU4
RFU3
RFU2
RFU1
RFU0
VIN_MGMT
3/3
G3
G2
G1
VSS62
VSS61
VSS60
VSS58
VSS104
VSS102
VSS100
VIN_BULK2
VIN_BULK1
VIN_BULK0
VSS126
VSS125
VSS124
VSS123
VSS122
VSS121
VSS120
VSS119
VSS118
VSS117
VSS116
VSS115
VSS114
VSS113
VSS112
VSS111
VSS110
VSS109
VSS108
VSS107
VSS106
VSS105
VSS103
VSS101
VSS99
VSS98
VSS97
VSS96
VSS95
VSS94
VSS93
VSS92
VSS91
VSS90
VSS89
VSS88
VSS87
VSS86
VSS85
VSS84
VSS83
VSS82
VSS81
VSS80
VSS79
VSS78
VSS77
VSS76
VSS75
VSS74
VSS73
VSS72
VSS71
VSS70
VSS69
VSS68
VSS67
VSS66
VSS65
VSS64
VSS63
VSS59
VSS57
VSS56
VSS55
VSS54
VSS53
VSS52
VSS51
VSS50
VSS49
VSS48
VSS47
VSS46
VSS45
VSS44
VSS43
VSS42
VSS41
VSS40
VSS39
VSS38
VSS37
VSS36
VSS35
VSS34
VSS33
VSS32
VSS31
VSS30
VSS29
VSS28
VSS27
VSS26
VSS25
VSS24
VSS23
VSS22
VSS21
VSS20
VSS19
VSS18
VSS17
VSS16
VSS15
VSS14
VSS13
VSS12
VSS11
VSS10
VSS9
VSS8
VSS7
VSS6
VSS5
VSS4
VSS3
VSS2
VSS1
VSS0
21
21
SHEETDATE
DEPARTMENT
SIZE
PROJECT DOCUMENT NUMBER REV
REVIEWER
DESIGNER
123
7 3 2 1 6 5 4
E
A
B
C
E
D
C
B
A
7 6 5 4
D
IN
BI
OUT
IN
BI
IN
IN
IN
OUT
OUTOUT
OUTOUT
IN
BI
IN
IN
IN
ININ
IN
OUT
BI
BIIN
BI
OUT
C



Thu Sep 14 16:12:08 2023<NAME_2><NAME_1>MB FABCGT AMDV0295 OF 365
P12V_MEM_CPU0P3V3_AUXP3V3M_J_CPU0_ALERT_N9592939496971591599293949697191919191919191992939496971919191919199519191919191919191K
X6S10%10UFC080525VX6S10%10UF25VC0805
0402LF1KEMPTY1/16W1%X7R10%0.1UF25V0402CHIP 0402LF10PD_CHJ_CPU0_DIMM_SAAI3C_SPD_DDRGL_CPU0_SDAI3C_SPD_DDRGL_CPU0_SCLI3C_SPD_DDRJ_CPU0_SDAPWRGD_CHJ_CPU0_DIMM49.90402LF35.7K1%CHIP1/16W
SCONN288_DDR506112002KQIOSMLFSMLFSCONN288_DDR506112002KQIOSMLFSCONN288_DDR506112002KQIO
DDR5 - CPU0 CHJ
M_J_CPU0_SA_CA<6:0>M_J_CPU0_SB_CA<6:0>M_J_CPU0_SA_DQ<31:0>M_J_CPU0_SB_DQ<31:0>M_J_CPU0_SA_DQS_DN<9:0>M_J_CPU0_SA_DQS_DP<9:0>M_J_CPU0_SB_DQS_DP<9:0>M_J_CPU0_SB_DQS_DN<9:0>PWRGD_CHGL_CPU0M_J_CPU0_SA_RSP<0>M_J_CPU0_SB_PARM_J_CPU0_SA_PARM_J_CPU0_SB_CS_N<1>M_J_CPU0_SA_CS_N<1>M_J_CPU0_SA_CS_N<0>PD_CHJ_CPU0_DIMM_SAAM_J_CPU0_SB_CS_N<0>M_J_CPU0_CLK_DP<0>M_J_CPU0_CLK_DN<0>M_J_CPU0_SA_CB<7:0>M_J_CPU0_SB_CB<7:0>M_J_CPU0_RESET_NM_J_CPU0_SB_RSP<0>I3C_SPD_DDRJ_CPU0_SCL
J68
J68
J68
2
1C166
2
1C165
2
1
R99
2 1
R300
2
1C124
2
1
R767
6
7
10
9
8
11
12
13
14
15
17
16
20
19
18
22
21
25
24
23
27
28
26
30
29
31
8
9
9
8
7
6
5
4
3
2
1
0
9
7
6
5
4
3
2
1
0
9
8
7
8
6
4
5
3
1
2
0
7
6
0
4
5
3
2
1
0
1
2
3
4
6
7
0
1
3
2
0
2
1
4
3
5
6
7
9
8
10
12
11
14
13
15
17
16
20
19
18
21
22
25
24
23
26
27
30
29
28
31
4
5
6
7
0
1
2
3
4
5
6
0
1
2
3
4
5
6
0
2
1
3
4
5
5
R1684
R1577
DQS7_A_c||TDQS7_A_c
DQS6_A_t||TDQS6_A_t
DQS8_B_t||TDQS8_B_t
DQS8_B_c||TDQS8_B_c
DQS7_B_t||TDQS7_B_t
DQS0_A_c
DQS0_A_t
DQS0_B_c
DQS0_B_t
DQS1_A_c
DQS1_A_t
DQS1_B_c
DQS1_B_t
DQS2_A_c
DQS2_A_t
DQS2_B_c
DQS2_B_t
DQS3_A_c
DQS3_A_t
DQS3_B_c
DQS3_B_t
DQS4_A_c
DQS4_A_t
DQS4_B_c
DQS4_B_t
DQS5_A_c||TDQS5_A_c||DQS5_A_t||TDQS5_A_t
DQS5_A_t||TDQS5_A_t
DQS5_B_c||TDQS5_B_c
DQS5_B_t||TDQS5_B_t
DQS6_A_c||TDQS6_A_c||DQS6_A_t||TDQS6_A_t
DQS6_B_c||TDQS6_B_c
DQS6_B_t||TDQS6_B_t
DQS7_A_t||TDQS7_A_t
DQS7_B_c||TDQS7_B_c
DQS8_A_c||TDQS8_A_c
DQS8_A_t||TDQS8_A_t
DQS9_A_c||TDQS9_A_c
DQS9_A_t||TDQS9_A_t
DQS9_B_c||TDQS9_B_c
DQS9_B_t||TDQS9_B_t||DBI4_B_n93
94
201
200
283
282
190
189
272
271
179
178
261
260
168
167
250
249
157
156
239
238
55
56
137
138
44
45
126
127
33
34
115
116
22
23
104
105
11
12
288
286
284
281
279
277
275
273
270
268
266
264
262
259
257
255
253
251
248
246
244
242
240
237
235
233
230
228
226
224
222
219
216
214
212
210
208
206
204
202
199
197
195
193
191
188
186
184
182
180
177
175
173
171
169
166
164
162
160
158
155
153
151
143
141
139
136
134
132
130
128
125
123
121
119
117
114
112
110
108
106
103
101
99
97
95
92
90
88
85
83
81
79
77
75
73
71
69
67
65
63
61
59
57
54
52
50
48
46
43
41
39
37
35
32
30
28
26
24
21
19
17
15
13
10
8
6
146
145
1
G3
G2
G1
3
232
231
220
150
149
144
2
207
147
227
74
87
86
5
4
148
287
194
285
192
142
49
140
47
280
187
278
185
135
42
133
40
276
183
274
181
131
38
129
36
269
176
267
174
124
31
122
29
265
172
263
170
120
27
118
25
258
165
256
163
113
20
111
18
254
161
252
159
109
16
107
14
247
154
245
152
102
9
100
7
229
209
84
64
217
218
236
205
234
203
91
60
89
58
243
198
241
196
98
53
96
51
82
72
225
215
80
70
223
213
78
68
221
211
76
66
62
2/3
1/3
PWR_GOOD||FAIL_n
DQ31_A
CB7_A
CB4_A
CB1_A
CB7_B
ALERT_n
CA0_A
CA0_B
CA1_A
CA1_B
CA2_A
CA2_B
CA3_A
CA3_B
CA4_A
CA4_B
CA5_A
CA5_B
CA6_A
CA6_B
CB6_A
CB5_A
CB3_A
CB2_A
CB0_A
CB6_B
CB5_B
CB4_B
CB3_B
CB2_B
CB1_B
CB0_B
CK_c
CK_t
CS0_A_n
CS0_B_n
CS1_A_n
CS1_B_n
DQ30_A
DQ29_A
DQ28_A
DQ27_A
DQ26_A
DQ25_A
DQ24_A
DQ23_A
DQ22_A
DQ21_A
DQ20_A
DQ19_A
DQ18_A
DQ17_A
DQ16_A
DQ15_A
DQ14_A
DQ13_A
DQ12_A
DQ11_A
DQ10_A
DQ9_A
DQ8_A
DQ7_A
DQ6_A
DQ5_A
DQ4_A
DQ3_A
DQ2_A
DQ1_A
DQ0_A
DQ31_B
DQ30_B
DQ29_B
DQ28_B
DQ27_B
DQ26_B
DQ25_B
DQ24_B
DQ23_B
DQ22_B
DQ21_B
DQ20_B
DQ19_B
DQ18_B
DQ17_B
DQ16_B
DQ15_B
DQ14_B
DQ13_B
DQ12_B
DQ11_B
DQ10_B
DQ9_B
DQ8_B
DQ7_B
DQ6_B
DQ5_B
DQ4_B
DQ3_B
DQ2_B
DQ1_B
DQ0_B
HAS
HSCL
HSDA
LBD||RSP_A_n
LBS||RSP_B_n
PAR_A
PAR_B
RESET_n
RFU6
RFU5
RFU4
RFU3
RFU2
RFU1
RFU0
VIN_MGMT
3/3
G3
G2
G1
VSS62
VSS61
VSS60
VSS58
VSS104
VSS102
VSS100
VIN_BULK2
VIN_BULK1
VIN_BULK0
VSS126
VSS125
VSS124
VSS123
VSS122
VSS121
VSS120
VSS119
VSS118
VSS117
VSS116
VSS115
VSS114
VSS113
VSS112
VSS111
VSS110
VSS109
VSS108
VSS107
VSS106
VSS105
VSS103
VSS101
VSS99
VSS98
VSS97
VSS96
VSS95
VSS94
VSS93
VSS92
VSS91
VSS90
VSS89
VSS88
VSS87
VSS86
VSS85
VSS84
VSS83
VSS82
VSS81
VSS80
VSS79
VSS78
VSS77
VSS76
VSS75
VSS74
VSS73
VSS72
VSS71
VSS70
VSS69
VSS68
VSS67
VSS66
VSS65
VSS64
VSS63
VSS59
VSS57
VSS56
VSS55
VSS54
VSS53
VSS52
VSS51
VSS50
VSS49
VSS48
VSS47
VSS46
VSS45
VSS44
VSS43
VSS42
VSS41
VSS40
VSS39
VSS38
VSS37
VSS36
VSS35
VSS34
VSS33
VSS32
VSS31
VSS30
VSS29
VSS28
VSS27
VSS26
VSS25
VSS24
VSS23
VSS22
VSS21
VSS20
VSS19
VSS18
VSS17
VSS16
VSS15
VSS14
VSS13
VSS12
VSS11
VSS10
VSS9
VSS8
VSS7
VSS6
VSS5
VSS4
VSS3
VSS2
VSS1
VSS0
21
21
SHEETDATE
DEPARTMENT
SIZE
PROJECT DOCUMENT NUMBER REV
REVIEWER
DESIGNER
123
7 3 2 1 6 5 4
E
A
B
C
E
D
C
B
A
7 6 5 4
D
IN
BI
OUT
IN
BI
IN
IN
IN
OUT
OUTOUT
OUTOUTIN
BI
IN
IN
IN
IN
ININ
OUT
BI
INBI
BI
OUT
C



Thu Sep 14 16:12:09 2023<NAME_2><NAME_1>MB FABCGT AMDV0296 OF 365P3V3
P12V_MEM_CPU0P3V3_AUX96159929394959792939495971592020 2020202020202020
9620202020202020202020929394959720201K
X6S10%10UF25VC0805X6S10%10UF25VC0805
1/16WEMPTY0402LF1K1%X7R10%040225V0.1UFCHIP100402LFPD_CHK_CPU0_DIMM_SAAI3C_SPD_DDRGL_CPU0_SCLI3C_SPD_DDRGL_CPU0_SDAI3C_SPD_DDRK_CPU0_SDAI3C_SPD_DDRK_CPU0_SCLPWRGD_CHK_CPU0_DIMMM_K_CPU0_RESET_N1/16WCHIP1%54.9K0402LF
IOSCONN288_DDR506112002KQSMLFIOSCONN288_DDR506112002KQSMLFSCONN288_DDR506112002KQIOSMLF
DDR5 - CPU0 CHK
M_K_CPU0_SA_CA<6:0>M_K_CPU0_SB_DQS_DP<9:0>M_K_CPU0_SB_DQS_DN<9:0>M_K_CPU0_SA_DQS_DP<9:0>M_K_CPU0_SA_DQS_DN<9:0>M_K_CPU0_SB_DQ<31:0>M_K_CPU0_SA_DQ<31:0>M_K_CPU0_SA_CB<7:0>M_K_CPU0_SB_CA<6:0>
PD_CHK_CPU0_DIMM_SAAM_K_CPU0_SB_CS_N<0>M_K_CPU0_SB_CS_N<1>M_K_CPU0_SA_PARM_K_CPU0_SB_PARM_K_CPU0_SA_CS_N<1>M_K_CPU0_SA_CS_N<0>M_K_CPU0_SB_RSP<0>M_K_CPU0_CLK_DP<0>M_K_CPU0_CLK_DN<0>M_K_CPU0_SA_RSP<0>PWRGD_CHGL_CPU0M_K_CPU0_SB_CB<7:0>M_K_CPU0_ALERT_N49.9
J20
J20
J20
2
1C169
2
1C167
2
1
R100
2 1
R301
2
1C128
2
1
R768
25
6
6
7
8
9
10
12
11
13
14
15
16
17
18
19
20
21
22
23
24
25
26
27
28
30
29
31
6
6
7
9
8
9
7
8
7
5
6
4
3
2
0
1
9
8
6
5
4
2
3
1
0
9
8
7
4
5
3
2
1
0
0 5
4
3
2
1
0
1
2
4
3
5
6
7
0
1
2
3
5
4
0
1
2
3
4
6
5
8
7
9
11
10
12
13
14
16
15
17
18
19
20
21
22
24
23
26
27
29
28
31
30
0
1
7
0
2
1
4
3
5
6
0
1
2
3
4
5
6
2
3
4
5
R1578
DQS7_A_c||TDQS7_A_c
DQS6_A_t||TDQS6_A_t
DQS8_B_t||TDQS8_B_t
DQS8_B_c||TDQS8_B_c
DQS7_B_t||TDQS7_B_t
DQS0_A_c
DQS0_A_t
DQS0_B_c
DQS0_B_t
DQS1_A_c
DQS1_A_t
DQS1_B_c
DQS1_B_t
DQS2_A_c
DQS2_A_t
DQS2_B_c
DQS2_B_t
DQS3_A_c
DQS3_A_t
DQS3_B_c
DQS3_B_t
DQS4_A_c
DQS4_A_t
DQS4_B_c
DQS4_B_t
DQS5_A_c||TDQS5_A_c||DQS5_A_t||TDQS5_A_t
DQS5_A_t||TDQS5_A_t
DQS5_B_c||TDQS5_B_c
DQS5_B_t||TDQS5_B_t
DQS6_A_c||TDQS6_A_c||DQS6_A_t||TDQS6_A_t
DQS6_B_c||TDQS6_B_c
DQS6_B_t||TDQS6_B_t
DQS7_A_t||TDQS7_A_t
DQS7_B_c||TDQS7_B_c
DQS8_A_c||TDQS8_A_c
DQS8_A_t||TDQS8_A_t
DQS9_A_c||TDQS9_A_c
DQS9_A_t||TDQS9_A_t
DQS9_B_c||TDQS9_B_c
DQS9_B_t||TDQS9_B_t||DBI4_B_n
R1685
93
94
201
200
283
282
190
189
272
271
179
178
261
260
168
167
250
249
157
156
239
238
55
56
137
138
44
45
126
127
33
34
115
116
22
23
104
105
11
12
288
286
284
281
279
277
275
273
270
268
266
264
262
259
257
255
253
251
248
246
244
242
240
237
235
233
230
228
226
224
222
219
216
214
212
210
208
206
204
202
199
197
195
193
191
188
186
184
182
180
177
175
173
171
169
166
164
162
160
158
155
153
151
143
141
139
136
134
132
130
128
125
123
121
119
117
114
112
110
108
106
103
101
99
97
95
92
90
88
85
83
81
79
77
75
73
71
69
67
65
63
61
59
57
54
52
50
48
46
43
41
39
37
35
32
30
28
26
24
21
19
17
15
13
10
8
6
146
145
1
G3
G2
G1
3
232
231
220
150
149
144
2
207
147
227
74
87
86
5
4
148
287
194
285
192
142
49
140
47
280
187
278
185
135
42
133
40
276
183
274
181
131
38
129
36
269
176
267
174
124
31
122
29
265
172
263
170
120
27
118
25
258
165
256
163
113
20
111
18
254
161
252
159
109
16
107
14
247
154
245
152
102
9
100
7
229
209
84
64
217
218
236
205
234
203
91
60
89
58
243
198
241
196
98
53
96
51
82
72
225
215
80
70
223
213
78
68
221
211
76
66
62
2/3
1/3
PWR_GOOD||FAIL_n
DQ31_A
CB7_A
CB4_A
CB1_A
CB7_B
ALERT_n
CA0_A
CA0_B
CA1_A
CA1_B
CA2_A
CA2_B
CA3_A
CA3_B
CA4_A
CA4_B
CA5_A
CA5_B
CA6_A
CA6_B
CB6_A
CB5_A
CB3_A
CB2_A
CB0_A
CB6_B
CB5_B
CB4_B
CB3_B
CB2_B
CB1_B
CB0_B
CK_c
CK_t
CS0_A_n
CS0_B_n
CS1_A_n
CS1_B_n
DQ30_A
DQ29_A
DQ28_A
DQ27_A
DQ26_A
DQ25_A
DQ24_A
DQ23_A
DQ22_A
DQ21_A
DQ20_A
DQ19_A
DQ18_A
DQ17_A
DQ16_A
DQ15_A
DQ14_A
DQ13_A
DQ12_A
DQ11_A
DQ10_A
DQ9_A
DQ8_A
DQ7_A
DQ6_A
DQ5_A
DQ4_A
DQ3_A
DQ2_A
DQ1_A
DQ0_A
DQ31_B
DQ30_B
DQ29_B
DQ28_B
DQ27_B
DQ26_B
DQ25_B
DQ24_B
DQ23_B
DQ22_B
DQ21_B
DQ20_B
DQ19_B
DQ18_B
DQ17_B
DQ16_B
DQ15_B
DQ14_B
DQ13_B
DQ12_B
DQ11_B
DQ10_B
DQ9_B
DQ8_B
DQ7_B
DQ6_B
DQ5_B
DQ4_B
DQ3_B
DQ2_B
DQ1_B
DQ0_B
HAS
HSCL
HSDA
LBD||RSP_A_n
LBS||RSP_B_n
PAR_A
PAR_B
RESET_n
RFU6
RFU5
RFU4
RFU3
RFU2
RFU1
RFU0
VIN_MGMT
3/3
G3
G2
G1
VSS62
VSS61
VSS60
VSS58
VSS104
VSS102
VSS100
VIN_BULK2
VIN_BULK1
VIN_BULK0
VSS126
VSS125
VSS124
VSS123
VSS122
VSS121
VSS120
VSS119
VSS118
VSS117
VSS116
VSS115
VSS114
VSS113
VSS112
VSS111
VSS110
VSS109
VSS108
VSS107
VSS106
VSS105
VSS103
VSS101
VSS99
VSS98
VSS97
VSS96
VSS95
VSS94
VSS93
VSS92
VSS91
VSS90
VSS89
VSS88
VSS87
VSS86
VSS85
VSS84
VSS83
VSS82
VSS81
VSS80
VSS79
VSS78
VSS77
VSS76
VSS75
VSS74
VSS73
VSS72
VSS71
VSS70
VSS69
VSS68
VSS67
VSS66
VSS65
VSS64
VSS63
VSS59
VSS57
VSS56
VSS55
VSS54
VSS53
VSS52
VSS51
VSS50
VSS49
VSS48
VSS47
VSS46
VSS45
VSS44
VSS43
VSS42
VSS41
VSS40
VSS39
VSS38
VSS37
VSS36
VSS35
VSS34
VSS33
VSS32
VSS31
VSS30
VSS29
VSS28
VSS27
VSS26
VSS25
VSS24
VSS23
VSS22
VSS21
VSS20
VSS19
VSS18
VSS17
VSS16
VSS15
VSS14
VSS13
VSS12
VSS11
VSS10
VSS9
VSS8
VSS7
VSS6
VSS5
VSS4
VSS3
VSS2
VSS1
VSS0
21
21
SHEETDATE
DEPARTMENT
SIZE
PROJECT DOCUMENT NUMBER REV
REVIEWER
DESIGNER
123
7 3 2 1 6 5 4
E
A
B
C
E
D
C
B
A
7 6 5 4
D
IN
BI
OUT
OUTOUT
IN
BI
IN
IN
IN
OUTOUT
OUTOUT
IN
BI
IN
IN
ININ
IN
BI
OUT
BI
ININ
BI
C



Thu Sep 14 16:12:09 2023<NAME_2><NAME_1>MB FABCGT AMDV0297 OF 365
P12V_MEM_CPU0P3V3_AUXP3V39792939495961591599293949596212121212121212121219293949596212121212121212197212121211K
10%10UF25VC0805X6S10UF25VC0805X6S10%
1K0402LFEMPTY1/16W1%X7R0.1UF10%25V0402CHIP100402LFPD_CHL_CPU0_DIMM_SAAI3C_SPD_DDRGL_CPU0_SDAI3C_SPD_DDRL_CPU0_SDA49.9I3C_SPD_DDRL_CPU0_SCLI3C_SPD_DDRGL_CPU0_SCL0402LF84.5K1%CHIP1/16W
IOSMLFSCONN288_DDR506112002KQIOSCONN288_DDR506112002KQSMLFIOSCONN288_DDR506112002KQSMLF
DDR5 - CPU0 CHL
M_L_CPU0_SA_CB<7:0>M_L_CPU0_SB_CB<7:0>M_L_CPU0_SA_CA<6:0>M_L_CPU0_SB_CA<6:0>M_L_CPU0_SA_DQ<31:0>M_L_CPU0_SB_DQ<31:0>M_L_CPU0_SA_DQS_DN<9:0>M_L_CPU0_SA_DQS_DP<9:0>M_L_CPU0_SB_DQS_DP<9:0>M_L_CPU0_SB_DQS_DN<9:0>PWRGD_CHGL_CPU0M_L_CPU0_SB_PARM_L_CPU0_SA_PARM_L_CPU0_SB_CS_N<1>M_L_CPU0_SA_CS_N<1>M_L_CPU0_SB_CS_N<0>M_L_CPU0_SA_CS_N<0>M_L_CPU0_CLK_DP<0>M_L_CPU0_CLK_DN<0>PD_CHL_CPU0_DIMM_SAAM_L_CPU0_ALERT_NM_L_CPU0_RESET_NPWRGD_CHL_CPU0_DIMMM_L_CPU0_SA_RSP<0>M_L_CPU0_SB_RSP<0>
J67
J67
J67
2
1C171
2
1C170
2
1
R101
2 1
R302
2
1C132
2
1
R769
8
9
10
12
11
13
14
15
16
18
17
19
20
21
22
23
24
25
26
27
28
30
31
29
9
8
9
8
7
6
7
6
4
5
5
3
4
2
3
1
2
1
9
0
0
9
8
7
8
7
6
5
6
4
5
4
2
3
0
1
3
2
1
0
0
1
2
4
5
3
7
1
0
6
0
1
2
3
4
5
6
7
8
10
9
11
12
13
14
15
16
17
18
19
20
21
22
23
24
25
26
27
28
29
30
2
3
5
6
4
7
0
1
2
3
4
6
5
1
2
3
0
5
6
4
31
0
1
2
3
4
5
6
7
DQS7_A_c||TDQS7_A_c
DQS6_A_t||TDQS6_A_t
DQS8_B_t||TDQS8_B_t
DQS8_B_c||TDQS8_B_c
DQS7_B_t||TDQS7_B_t
DQS0_A_c
DQS0_A_t
DQS0_B_c
DQS0_B_t
DQS1_A_c
DQS1_A_t
DQS1_B_c
DQS1_B_t
DQS2_A_c
DQS2_A_t
DQS2_B_c
DQS2_B_t
DQS3_A_c
DQS3_A_t
DQS3_B_c
DQS3_B_t
DQS4_A_c
DQS4_A_t
DQS4_B_c
DQS4_B_t
DQS5_A_c||TDQS5_A_c||DQS5_A_t||TDQS5_A_t
DQS5_A_t||TDQS5_A_t
DQS5_B_c||TDQS5_B_c
DQS5_B_t||TDQS5_B_t
DQS6_A_c||TDQS6_A_c||DQS6_A_t||TDQS6_A_t
DQS6_B_c||TDQS6_B_c
DQS6_B_t||TDQS6_B_t
DQS7_A_t||TDQS7_A_t
DQS7_B_c||TDQS7_B_c
DQS8_A_c||TDQS8_A_c
DQS8_A_t||TDQS8_A_t
DQS9_A_c||TDQS9_A_c
DQS9_A_t||TDQS9_A_t
DQS9_B_c||TDQS9_B_c
DQS9_B_t||TDQS9_B_t||DBI4_B_n
R1686
R1579
93
94
201
200
283
282
190
189
272
271
179
178
261
260
168
167
250
249
157
156
239
238
55
56
137
138
44
45
126
127
33
34
115
116
22
23
104
105
11
12
288
286
284
281
279
277
275
273
270
268
266
264
262
259
257
255
253
251
248
246
244
242
240
237
235
233
230
228
226
224
222
219
216
214
212
210
208
206
204
202
199
197
195
193
191
188
186
184
182
180
177
175
173
171
169
166
164
162
160
158
155
153
151
143
141
139
136
134
132
130
128
125
123
121
119
117
114
112
110
108
106
103
101
99
97
95
92
90
88
85
83
81
79
77
75
73
71
69
67
65
63
61
59
57
54
52
50
48
46
43
41
39
37
35
32
30
28
26
24
21
19
17
15
13
10
8
6
146
145
1
G3
G2
G1
3
232
231
220
150
149
144
2
207
147
227
74
87
86
5
4
148
287
194
285
192
142
49
140
47
280
187
278
185
135
42
133
40
276
183
274
181
131
38
129
36
269
176
267
174
124
31
122
29
265
172
263
170
120
27
118
25
258
165
256
163
113
20
111
18
254
161
252
159
109
16
107
14
247
154
245
152
102
9
100
7
229
209
84
64
217
218
236
205
234
203
91
60
89
58
243
198
241
196
98
53
96
51
82
72
225
215
80
70
223
213
78
68
221
211
76
66
62
2/3
1/3
PWR_GOOD||FAIL_n
DQ31_A
CB7_A
CB4_A
CB1_A
CB7_B
ALERT_n
CA0_A
CA0_B
CA1_A
CA1_B
CA2_A
CA2_B
CA3_A
CA3_B
CA4_A
CA4_B
CA5_A
CA5_B
CA6_A
CA6_B
CB6_A
CB5_A
CB3_A
CB2_A
CB0_A
CB6_B
CB5_B
CB4_B
CB3_B
CB2_B
CB1_B
CB0_B
CK_c
CK_t
CS0_A_n
CS0_B_n
CS1_A_n
CS1_B_n
DQ30_A
DQ29_A
DQ28_A
DQ27_A
DQ26_A
DQ25_A
DQ24_A
DQ23_A
DQ22_A
DQ21_A
DQ20_A
DQ19_A
DQ18_A
DQ17_A
DQ16_A
DQ15_A
DQ14_A
DQ13_A
DQ12_A
DQ11_A
DQ10_A
DQ9_A
DQ8_A
DQ7_A
DQ6_A
DQ5_A
DQ4_A
DQ3_A
DQ2_A
DQ1_A
DQ0_A
DQ31_B
DQ30_B
DQ29_B
DQ28_B
DQ27_B
DQ26_B
DQ25_B
DQ24_B
DQ23_B
DQ22_B
DQ21_B
DQ20_B
DQ19_B
DQ18_B
DQ17_B
DQ16_B
DQ15_B
DQ14_B
DQ13_B
DQ12_B
DQ11_B
DQ10_B
DQ9_B
DQ8_B
DQ7_B
DQ6_B
DQ5_B
DQ4_B
DQ3_B
DQ2_B
DQ1_B
DQ0_B
HAS
HSCL
HSDA
LBD||RSP_A_n
LBS||RSP_B_n
PAR_A
PAR_B
RESET_n
RFU6
RFU5
RFU4
RFU3
RFU2
RFU1
RFU0
VIN_MGMT
3/3
G3
G2
G1
VSS62
VSS61
VSS60
VSS58
VSS104
VSS102
VSS100
VIN_BULK2
VIN_BULK1
VIN_BULK0
VSS126
VSS125
VSS124
VSS123
VSS122
VSS121
VSS120
VSS119
VSS118
VSS117
VSS116
VSS115
VSS114
VSS113
VSS112
VSS111
VSS110
VSS109
VSS108
VSS107
VSS106
VSS105
VSS103
VSS101
VSS99
VSS98
VSS97
VSS96
VSS95
VSS94
VSS93
VSS92
VSS91
VSS90
VSS89
VSS88
VSS87
VSS86
VSS85
VSS84
VSS83
VSS82
VSS81
VSS80
VSS79
VSS78
VSS77
VSS76
VSS75
VSS74
VSS73
VSS72
VSS71
VSS70
VSS69
VSS68
VSS67
VSS66
VSS65
VSS64
VSS63
VSS59
VSS57
VSS56
VSS55
VSS54
VSS53
VSS52
VSS51
VSS50
VSS49
VSS48
VSS47
VSS46
VSS45
VSS44
VSS43
VSS42
VSS41
VSS40
VSS39
VSS38
VSS37
VSS36
VSS35
VSS34
VSS33
VSS32
VSS31
VSS30
VSS29
VSS28
VSS27
VSS26
VSS25
VSS24
VSS23
VSS22
VSS21
VSS20
VSS19
VSS18
VSS17
VSS16
VSS15
VSS14
VSS13
VSS12
VSS11
VSS10
VSS9
VSS8
VSS7
VSS6
VSS5
VSS4
VSS3
VSS2
VSS1
VSS0
21
21
SHEETDATE
DEPARTMENT
SIZE
PROJECT DOCUMENT NUMBER REV
REVIEWER
DESIGNER
123
7 3 2 1 6 5 4
E
A
B
C
E
D
C
B
A
7 6 5 4
D
INOUT
IN
BI
IN
OUTOUT
IN
IN
OUT
OUTOUT
IN
BI
IN
ININ
ININ
BI
OUT
BI
BI
ININ
BI
OUT
C



Thu Sep 14 16:12:09 2023<NAME_2><NAME_1>MB FABCGT AMDV0298 OF 365
P3V3_AUXP3V3_AUXP3V3_AUXP3V3_AUX
P12V_MEM_CPU1
P3V3P3V3991001011021031591599910010110210398373737989910010110210337373737373737373798 82989910010110210398 99 100101102 103
373737 373737373737371K1/16W0402LFX7R10%0.1UF25V0402EMPTY0402LF1K1/16W1%1%1/16WEMPTY0402LF1K
X6S10%10UF25VC0805X6S10%10UF25VC08050402LF10CHIPI3C_SPD_DDRAF_CPU1_SDAI3C_SPD_DDRA_CPU1_SDAI3C_SPD_DDRA_CPU1_SCLI3C_SPD_DDRAF_CPU1_SCLPWRGD_CHA_CPU1_DIMM0PD_CHA_CPU1_DIMM0_SAAM_A_CPU1_RESET_NM_A_CPU1_ALERT_N49.9M_A_CPU1_SB_CS_N<1>PWRGD_CHAF_CPU1M_A_CPU1_SB_PARM_A_CPU1_SA_PARM_A_CPU1_SB_RSP<0>M_A_CPU1_SA_RSP<0>M_A_CPU1_SA_CS_N<1>M_A_CPU1_SB_CS_N<0>M_A_CPU1_SA_CS_N<0>M_A_CPU1_CLK_DP<0>M_A_CPU1_CLK_DN<0>PD_CHA_CPU1_DIMM0_SAAPWRGD_CHAF_CPU1_R2PWRGD_CHAF_CPU1PWRGD_CHAF_CPU1PWRGD_CHAF_CPU1_R1
M_A_CPU1_SB_CA<6:0>M_A_CPU1_SA_CB<7:0>M_A_CPU1_SB_CB<7:0>M_A_CPU1_SA_DQS_DN<9:0>M_A_CPU1_SB_DQS_DN<9:0>M_A_CPU1_SB_DQS_DP<9:0>M_A_CPU1_SA_DQ<31:0>M_A_CPU1_SA_DQS_DP<9:0>M_A_CPU1_SA_CA<6:0>M_A_CPU1_SB_DQ<31:0>
DDR5 - CPU1 CHASMLFB0530WS7FEMPTY05%0402LFCHIP1/16W1%10K1/16W0402LFEMPTY1/16W0402LFCHIP5%00402LFCHIP10K1/16W1%
SCONN288_DDR506112002KQIOSMLFIOSMLFSCONN288_DDR506112002KQSMLFIOSCONN288_DDR506112002KQ
10K1%CHIP
J24
J24J24
2
1C174
2
1C173
2
1
R103
2 1R303
2
1
R102
2
1C136
2
1
R36
1
4
29
6
6
5
4
3
2
0
1
6
5
4
3
2
1
0
2
4
3
0
1
31
30
28
27
26
25
23
24
22
21
20
18
19
17
15
16
12
13
14
11
10
7
8
9
6
5
2
3
4
0
1
7
6
5
4
3
2
0
7
6
5
3
2
1
1
0
0
1
2
3
5
4
0 6
3
2
4
5
6
7
8
9
1
0
7
8
9
0
1
2
3
6
5
4
2
4
3
5
6
7
8
9
7
8
9
31
29
28
30
25
27
26
23
24
20
21
22
19
18
15
16
17
14
13
10
11
12
7
9
8
5
R1687
R1580
DQS7_A_c||TDQS7_A_c
DQS6_A_t||TDQS6_A_t
DQS8_B_t||TDQS8_B_t
DQS8_B_c||TDQS8_B_c
DQS7_B_t||TDQS7_B_t
DQS0_A_c
DQS0_A_t
DQS0_B_c
DQS0_B_t
DQS1_A_c
DQS1_A_t
DQS1_B_c
DQS1_B_t
DQS2_A_c
DQS2_A_t
DQS2_B_c
DQS2_B_t
DQS3_A_c
DQS3_A_t
DQS3_B_c
DQS3_B_t
DQS4_A_c
DQS4_A_t
DQS4_B_c
DQS4_B_t
DQS5_A_c||TDQS5_A_c||DQS5_A_t||TDQS5_A_t
DQS5_A_t||TDQS5_A_t
DQS5_B_c||TDQS5_B_c
DQS5_B_t||TDQS5_B_t
DQS6_A_c||TDQS6_A_c||DQS6_A_t||TDQS6_A_t
DQS6_B_c||TDQS6_B_c
DQS6_B_t||TDQS6_B_t
DQS7_A_t||TDQS7_A_t
DQS7_B_c||TDQS7_B_c
DQS8_A_c||TDQS8_A_c
DQS8_A_t||TDQS8_A_t
DQS9_A_c||TDQS9_A_c
DQS9_A_t||TDQS9_A_t
DQS9_B_c||TDQS9_B_c
DQS9_B_t||TDQS9_B_t||DBI4_B_n
21
93
94
201
200
283
282
190
189
272
271
179
178
261
260
168
167
250
249
157
156
239
238
55
56
137
138
44
45
126
127
33
34
115
116
22
23
104
105
11
12
288
286
284
281
279
277
275
273
270
268
266
264
262
259
257
255
253
251
248
246
244
242
240
237
235
233
230
228
226
224
222
219
216
214
212
210
208
206
204
202
199
197
195
193
191
188
186
184
182
180
177
175
173
171
169
166
164
162
160
158
155
153
151
143
141
139
136
134
132
130
128
125
123
121
119
117
114
112
110
108
106
103
101
99
97
95
92
90
88
85
83
81
79
77
75
73
71
69
67
65
63
61
59
57
54
52
50
48
46
43
41
39
37
35
32
30
28
26
24
21
19
17
15
13
10
8
6
146
145
1
G3
G2
G1
3
232
231
220
150
149
144
2
207
147
227
74
87
86
5
4
148
287
194
285
192
142
49
140
47
280
187
278
185
135
42
133
40
276
183
274
181
131
38
129
36
269
176
267
174
124
31
122
29
265
172
263
170
120
27
118
25
258
165
256
163
113
20
111
18
254
161
252
159
109
16
107
14
247
154
245
152
102
9
100
7
229
209
84
64
217
218
236
205
234
203
91
60
89
58
243
198
241
196
98
53
96
51
82
72
225
215
80
70
223
213
78
68
221
211
76
66
62
D8005
CA
2/3
1/3
PWR_GOOD||FAIL_n
DQ31_A
CB7_A
CB4_A
CB1_A
CB7_B
ALERT_n
CA0_A
CA0_B
CA1_A
CA1_B
CA2_A
CA2_B
CA3_A
CA3_B
CA4_A
CA4_B
CA5_A
CA5_B
CA6_A
CA6_B
CB6_A
CB5_A
CB3_A
CB2_A
CB0_A
CB6_B
CB5_B
CB4_B
CB3_B
CB2_B
CB1_B
CB0_B
CK_c
CK_t
CS0_A_n
CS0_B_n
CS1_A_n
CS1_B_n
DQ30_A
DQ29_A
DQ28_A
DQ27_A
DQ26_A
DQ25_A
DQ24_A
DQ23_A
DQ22_A
DQ21_A
DQ20_A
DQ19_A
DQ18_A
DQ17_A
DQ16_A
DQ15_A
DQ14_A
DQ13_A
DQ12_A
DQ11_A
DQ10_A
DQ9_A
DQ8_A
DQ7_A
DQ6_A
DQ5_A
DQ4_A
DQ3_A
DQ2_A
DQ1_A
DQ0_A
DQ31_B
DQ30_B
DQ29_B
DQ28_B
DQ27_B
DQ26_B
DQ25_B
DQ24_B
DQ23_B
DQ22_B
DQ21_B
DQ20_B
DQ19_B
DQ18_B
DQ17_B
DQ16_B
DQ15_B
DQ14_B
DQ13_B
DQ12_B
DQ11_B
DQ10_B
DQ9_B
DQ8_B
DQ7_B
DQ6_B
DQ5_B
DQ4_B
DQ3_B
DQ2_B
DQ1_B
DQ0_B
HAS
HSCL
HSDA
LBD||RSP_A_n
LBS||RSP_B_n
PAR_A
PAR_B
RESET_n
RFU6
RFU5
RFU4
RFU3
RFU2
RFU1
RFU0
VIN_MGMT
3/3
G3
G2
G1
VSS62
VSS61
VSS60
VSS58
VSS104
VSS102
VSS100
VIN_BULK2
VIN_BULK1
VIN_BULK0
VSS126
VSS125
VSS124
VSS123
VSS122
VSS121
VSS120
VSS119
VSS118
VSS117
VSS116
VSS115
VSS114
VSS113
VSS112
VSS111
VSS110
VSS109
VSS108
VSS107
VSS106
VSS105
VSS103
VSS101
VSS99
VSS98
VSS97
VSS96
VSS95
VSS94
VSS93
VSS92
VSS91
VSS90
VSS89
VSS88
VSS87
VSS86
VSS85
VSS84
VSS83
VSS82
VSS81
VSS80
VSS79
VSS78
VSS77
VSS76
VSS75
VSS74
VSS73
VSS72
VSS71
VSS70
VSS69
VSS68
VSS67
VSS66
VSS65
VSS64
VSS63
VSS59
VSS57
VSS56
VSS55
VSS54
VSS53
VSS52
VSS51
VSS50
VSS49
VSS48
VSS47
VSS46
VSS45
VSS44
VSS43
VSS42
VSS41
VSS40
VSS39
VSS38
VSS37
VSS36
VSS35
VSS34
VSS33
VSS32
VSS31
VSS30
VSS29
VSS28
VSS27
VSS26
VSS25
VSS24
VSS23
VSS22
VSS21
VSS20
VSS19
VSS18
VSS17
VSS16
VSS15
VSS14
VSS13
VSS12
VSS11
VSS10
VSS9
VSS8
VSS7
VSS6
VSS5
VSS4
VSS3
VSS2
VSS1
VSS0
21
21
21
21
2
1
21
SHEETDATE
DEPARTMENT
SIZE
PROJECT DOCUMENT NUMBER REV
REVIEWER
DESIGNER
123
7 3 2 1 6 5 4
E
A
B
C
E
D
C
B
A
7 6 5 4
D
IN
BI
OUT
IN
BI
BIBI
OUT
IN
IN
IN
OUT
OUTOUT
OUTOUTIN
BI
ININ
IN
IN
ININ
OUT
BI
INBI
BI
OUT
R8087
R8088
R8086
R8039
C



Thu Sep 14 16:12:10 2023<NAME_2><NAME_1>MB FABCGT AMDV0299 OF 365P3V3
P12V_MEM_CPU1P3V3_AUX1599810010110210398100101102103159993838383838383838383838389810010110210338383838383838993838381K
X6SC080510%25V10UF25V10UFX6S10%C08050402LF1K1/16WEMPTY1%X7R10%25V0.1UF040210CHIP 0402LFI3C_SPD_DDRAF_CPU1_SCLPWRGD_CHB_CPU1_DIMMI3C_SPD_DDRB_CPU1_SCLI3C_SPD_DDRAF_CPU1_SDAI3C_SPD_DDRB_CPU1_SDAPD_CHB_CPU1_DIMM_SAAM_B_CPU1_SB_RSP<0>M_B_CPU1_SA_RSP<0>M_B_CPU1_SA_CB<7:0>0402LF15.4K1%CHIP1/16W
IOSCONN288_DDR506112002KQSMLFIOSCONN288_DDR506112002KQSMLFIOSMLFSCONN288_DDR506112002KQ
DDR5 - CPU1 CHB
M_B_CPU1_SB_CB<7:0>M_B_CPU1_SB_CA<6:0>M_B_CPU1_SA_CA<6:0> M_B_CPU1_SA_DQ<31:0>M_B_CPU1_SB_DQ<31:0>M_B_CPU1_SA_DQS_DN<9:0>M_B_CPU1_SA_DQS_DP<9:0>M_B_CPU1_SB_DQS_DP<9:0>M_B_CPU1_SB_DQS_DN<9:0>PWRGD_CHAF_CPU1M_B_CPU1_SB_PARM_B_CPU1_SA_PARM_B_CPU1_SB_CS_N<1>M_B_CPU1_SA_CS_N<1>M_B_CPU1_SB_CS_N<0>M_B_CPU1_CLK_DP<0>M_B_CPU1_CLK_DN<0>PD_CHB_CPU1_DIMM_SAAM_B_CPU1_SA_CS_N<0>M_B_CPU1_RESET_NM_B_CPU1_ALERT_N49.9
J26
J26
J26
2
1C177
2
1C175
2
1
R104
2 1R304
2
1C140
2
1
R770
7
12
11
10
9
8
17
16
13
15
14
21
22
19
20
18
23
24
25
28
27
26
30
29
31
2
9
8
7
6
5
8
9
7
5
6
4
3
0
1
8
9
7
6
3
4
2
1
0
8
9
7
6
5
5
4
3
2
1
0
0
3
4
2
0
1
2
4
3
5
7
6
0
1
2
3
5
4
6
1
0
2
3
4
5
7
6
9
8
13
14
12
11
10
15
17
16
18
19
20
23
24
25
22
21
28
30
29
27
26
31
1
2
0
7
0
1
2
3
5
4
0
6
1
2
3
4
5
6
3
4
5
6
1
R1581
DQS7_A_c||TDQS7_A_c
DQS6_A_t||TDQS6_A_t
DQS8_B_t||TDQS8_B_t
DQS8_B_c||TDQS8_B_c
DQS7_B_t||TDQS7_B_t
DQS0_A_c
DQS0_A_t
DQS0_B_c
DQS0_B_t
DQS1_A_c
DQS1_A_t
DQS1_B_c
DQS1_B_t
DQS2_A_c
DQS2_A_t
DQS2_B_c
DQS2_B_t
DQS3_A_c
DQS3_A_t
DQS3_B_c
DQS3_B_t
DQS4_A_c
DQS4_A_t
DQS4_B_c
DQS4_B_t
DQS5_A_c||TDQS5_A_c||DQS5_A_t||TDQS5_A_t
DQS5_A_t||TDQS5_A_t
DQS5_B_c||TDQS5_B_c
DQS5_B_t||TDQS5_B_t
DQS6_A_c||TDQS6_A_c||DQS6_A_t||TDQS6_A_t
DQS6_B_c||TDQS6_B_c
DQS6_B_t||TDQS6_B_t
DQS7_A_t||TDQS7_A_t
DQS7_B_c||TDQS7_B_c
DQS8_A_c||TDQS8_A_c
DQS8_A_t||TDQS8_A_t
DQS9_A_c||TDQS9_A_c
DQS9_A_t||TDQS9_A_t
DQS9_B_c||TDQS9_B_c
DQS9_B_t||TDQS9_B_t||DBI4_B_n
R1696
93
94
201
200
283
282
190
189
272
271
179
178
261
260
168
167
250
249
157
156
239
238
55
56
137
138
44
45
126
127
33
34
115
116
22
23
104
105
11
12
288
286
284
281
279
277
275
273
270
268
266
264
262
259
257
255
253
251
248
246
244
242
240
237
235
233
230
228
226
224
222
219
216
214
212
210
208
206
204
202
199
197
195
193
191
188
186
184
182
180
177
175
173
171
169
166
164
162
160
158
155
153
151
143
141
139
136
134
132
130
128
125
123
121
119
117
114
112
110
108
106
103
101
99
97
95
92
90
88
85
83
81
79
77
75
73
71
69
67
65
63
61
59
57
54
52
50
48
46
43
41
39
37
35
32
30
28
26
24
21
19
17
15
13
10
8
6
146
145
1
G3
G2
G1
3
232
231
220
150
149
144
2
207
147
227
74
87
86
5
4
148
287
194
285
192
142
49
140
47
280
187
278
185
135
42
133
40
276
183
274
181
131
38
129
36
269
176
267
174
124
31
122
29
265
172
263
170
120
27
118
25
258
165
256
163
113
20
111
18
254
161
252
159
109
16
107
14
247
154
245
152
102
9
100
7
229
209
84
64
217
218
236
205
234
203
91
60
89
58
243
198
241
196
98
53
96
51
82
72
225
215
80
70
223
213
78
68
221
211
76
66
62
2/3
1/3
PWR_GOOD||FAIL_n
DQ31_A
CB7_A
CB4_A
CB1_A
CB7_B
ALERT_n
CA0_A
CA0_B
CA1_A
CA1_B
CA2_A
CA2_B
CA3_A
CA3_B
CA4_A
CA4_B
CA5_A
CA5_B
CA6_A
CA6_B
CB6_A
CB5_A
CB3_A
CB2_A
CB0_A
CB6_B
CB5_B
CB4_B
CB3_B
CB2_B
CB1_B
CB0_B
CK_c
CK_t
CS0_A_n
CS0_B_n
CS1_A_n
CS1_B_n
DQ30_A
DQ29_A
DQ28_A
DQ27_A
DQ26_A
DQ25_A
DQ24_A
DQ23_A
DQ22_A
DQ21_A
DQ20_A
DQ19_A
DQ18_A
DQ17_A
DQ16_A
DQ15_A
DQ14_A
DQ13_A
DQ12_A
DQ11_A
DQ10_A
DQ9_A
DQ8_A
DQ7_A
DQ6_A
DQ5_A
DQ4_A
DQ3_A
DQ2_A
DQ1_A
DQ0_A
DQ31_B
DQ30_B
DQ29_B
DQ28_B
DQ27_B
DQ26_B
DQ25_B
DQ24_B
DQ23_B
DQ22_B
DQ21_B
DQ20_B
DQ19_B
DQ18_B
DQ17_B
DQ16_B
DQ15_B
DQ14_B
DQ13_B
DQ12_B
DQ11_B
DQ10_B
DQ9_B
DQ8_B
DQ7_B
DQ6_B
DQ5_B
DQ4_B
DQ3_B
DQ2_B
DQ1_B
DQ0_B
HAS
HSCL
HSDA
LBD||RSP_A_n
LBS||RSP_B_n
PAR_A
PAR_B
RESET_n
RFU6
RFU5
RFU4
RFU3
RFU2
RFU1
RFU0
VIN_MGMT
3/3
G3
G2
G1
VSS62
VSS61
VSS60
VSS58
VSS104
VSS102
VSS100
VIN_BULK2
VIN_BULK1
VIN_BULK0
VSS126
VSS125
VSS124
VSS123
VSS122
VSS121
VSS120
VSS119
VSS118
VSS117
VSS116
VSS115
VSS114
VSS113
VSS112
VSS111
VSS110
VSS109
VSS108
VSS107
VSS106
VSS105
VSS103
VSS101
VSS99
VSS98
VSS97
VSS96
VSS95
VSS94
VSS93
VSS92
VSS91
VSS90
VSS89
VSS88
VSS87
VSS86
VSS85
VSS84
VSS83
VSS82
VSS81
VSS80
VSS79
VSS78
VSS77
VSS76
VSS75
VSS74
VSS73
VSS72
VSS71
VSS70
VSS69
VSS68
VSS67
VSS66
VSS65
VSS64
VSS63
VSS59
VSS57
VSS56
VSS55
VSS54
VSS53
VSS52
VSS51
VSS50
VSS49
VSS48
VSS47
VSS46
VSS45
VSS44
VSS43
VSS42
VSS41
VSS40
VSS39
VSS38
VSS37
VSS36
VSS35
VSS34
VSS33
VSS32
VSS31
VSS30
VSS29
VSS28
VSS27
VSS26
VSS25
VSS24
VSS23
VSS22
VSS21
VSS20
VSS19
VSS18
VSS17
VSS16
VSS15
VSS14
VSS13
VSS12
VSS11
VSS10
VSS9
VSS8
VSS7
VSS6
VSS5
VSS4
VSS3
VSS2
VSS1
VSS0
21
21
SHEETDATE
DEPARTMENT
SIZE
PROJECT DOCUMENT NUMBER REV
REVIEWER
DESIGNER
123
7 3 2 1 6 5 4
E
A
B
C
E
D
C
B
A
7 6 5 4
D
OUT
BI
BI
OUT
BI
IN
IN
OUTOUT
IN
IN
OUTOUT
BI
BI
ININ
ININ
ININ
OUT
BI
ININ
IN
OUT
C



Thu Sep 14 16:12:10 2023<NAME_2><NAME_1>MB FABCGT AMDV02100 OF 365P3V3
P12V_MEM_CPU1P3V3_AUXM_C_CPU1_ALERT_N10098991011021031591599899101102103393939393939393939399899101102103100
3939393939393939393939391K
10%10UF25VC0805X6SX6S10UFC080510%25V
1K1/16W0402LFEMPTY1%25V0.1UF10%0402X7RCHIP 0402LF10PD_CHC_CPU1_DIMM_SAAI3C_SPD_DDRAF_CPU1_SDAI3C_SPD_DDRC_CPU1_SCLI3C_SPD_DDRC_CPU1_SDAI3C_SPD_DDRAF_CPU1_SCLPWRGD_CHC_CPU1_DIMM49.91/16WCHIP1%23.2K0402LF
SCONN288_DDR506112002KQSMLFIOIOSCONN288_DDR506112002KQSMLFSCONN288_DDR506112002KQIOSMLF
DDR5 - CPU1 CHC
M_C_CPU1_SA_DQ<31:0>M_C_CPU1_SA_CB<7:0>M_C_CPU1_SB_CB<7:0>M_C_CPU1_SA_CA<6:0>M_C_CPU1_SB_CA<6:0>M_C_CPU1_SB_DQ<31:0>M_C_CPU1_SA_DQS_DN<9:0>M_C_CPU1_SA_DQS_DP<9:0>M_C_CPU1_SB_DQS_DP<9:0>M_C_CPU1_SB_DQS_DN<9:0>PWRGD_CHAF_CPU1PD_CHC_CPU1_DIMM_SAA
M_C_CPU1_SB_PARM_C_CPU1_SA_PARM_C_CPU1_SB_RSP<0>M_C_CPU1_SA_RSP<0>M_C_CPU1_SB_CS_N<1>M_C_CPU1_SB_CS_N<0>M_C_CPU1_SA_CS_N<0>M_C_CPU1_SA_CS_N<1>M_C_CPU1_CLK_DP<0>M_C_CPU1_CLK_DN<0>M_C_CPU1_RESET_N
J28
J28J28 2
1C179
2
1C178
2
1
R105
2 1R305
2
1C144
2
1
R771
3
4
5
6
7
9
10
8
11
12
14
15
13
16
17
20
19
18
21
22
23
24
25
28
27
26
29
30
31
1
2
8
9
8
9
7
5
7
6
6
5
3
4
4
3
0
2
1
0
8
9
9
8
7
5
7
6
6
5
4
3
4
2
0
3
0
1
2
1
0
2
1
3
4
5
7
6
0
1
2
3
1
0
2
3
4
5
7
6
9
8
11
12
10
13
14
15
17
16
18
19
20
22
21
23
25
24
26
27
29
30
28
31
4
5
6
7
0
2
1
3
4
5
6
0
1
2
3
5
4
6
0
2
1
R1582
DQS7_A_c||TDQS7_A_c
DQS6_A_t||TDQS6_A_t
DQS8_B_t||TDQS8_B_t
DQS8_B_c||TDQS8_B_c
DQS7_B_t||TDQS7_B_t
DQS0_A_c
DQS0_A_t
DQS0_B_c
DQS0_B_t
DQS1_A_c
DQS1_A_t
DQS1_B_c
DQS1_B_t
DQS2_A_c
DQS2_A_t
DQS2_B_c
DQS2_B_t
DQS3_A_c
DQS3_A_t
DQS3_B_c
DQS3_B_t
DQS4_A_c
DQS4_A_t
DQS4_B_c
DQS4_B_t
DQS5_A_c||TDQS5_A_c||DQS5_A_t||TDQS5_A_t
DQS5_A_t||TDQS5_A_t
DQS5_B_c||TDQS5_B_c
DQS5_B_t||TDQS5_B_t
DQS6_A_c||TDQS6_A_c||DQS6_A_t||TDQS6_A_t
DQS6_B_c||TDQS6_B_c
DQS6_B_t||TDQS6_B_t
DQS7_A_t||TDQS7_A_t
DQS7_B_c||TDQS7_B_c
DQS8_A_c||TDQS8_A_c
DQS8_A_t||TDQS8_A_t
DQS9_A_c||TDQS9_A_c
DQS9_A_t||TDQS9_A_t
DQS9_B_c||TDQS9_B_c
DQS9_B_t||TDQS9_B_t||DBI4_B_n
R1697
93
94
201
200
283
282
190
189
272
271
179
178
261
260
168
167
250
249
157
156
239
238
55
56
137
138
44
45
126
127
33
34
115
116
22
23
104
105
11
12
288
286
284
281
279
277
275
273
270
268
266
264
262
259
257
255
253
251
248
246
244
242
240
237
235
233
230
228
226
224
222
219
216
214
212
210
208
206
204
202
199
197
195
193
191
188
186
184
182
180
177
175
173
171
169
166
164
162
160
158
155
153
151
143
141
139
136
134
132
130
128
125
123
121
119
117
114
112
110
108
106
103
101
99
97
95
92
90
88
85
83
81
79
77
75
73
71
69
67
65
63
61
59
57
54
52
50
48
46
43
41
39
37
35
32
30
28
26
24
21
19
17
15
13
10
8
6
146
145
1
G3
G2
G1
3
232
231
220
150
149
144
2
207
147
227
74
87
86
5
4
148
287
194
285
192
142
49
140
47
280
187
278
185
135
42
133
40
276
183
274
181
131
38
129
36
269
176
267
174
124
31
122
29
265
172
263
170
120
27
118
25
258
165
256
163
113
20
111
18
254
161
252
159
109
16
107
14
247
154
245
152
102
9
100
7
229
209
84
64
217
218
236
205
234
203
91
60
89
58
243
198
241
196
98
53
96
51
82
72
225
215
80
70
223
213
78
68
221
211
76
66
62
2/3
1/3
PWR_GOOD||FAIL_n
DQ31_A
CB7_A
CB4_A
CB1_A
CB7_B
ALERT_n
CA0_A
CA0_B
CA1_A
CA1_B
CA2_A
CA2_B
CA3_A
CA3_B
CA4_A
CA4_B
CA5_A
CA5_B
CA6_A
CA6_B
CB6_A
CB5_A
CB3_A
CB2_A
CB0_A
CB6_B
CB5_B
CB4_B
CB3_B
CB2_B
CB1_B
CB0_B
CK_c
CK_t
CS0_A_n
CS0_B_n
CS1_A_n
CS1_B_n
DQ30_A
DQ29_A
DQ28_A
DQ27_A
DQ26_A
DQ25_A
DQ24_A
DQ23_A
DQ22_A
DQ21_A
DQ20_A
DQ19_A
DQ18_A
DQ17_A
DQ16_A
DQ15_A
DQ14_A
DQ13_A
DQ12_A
DQ11_A
DQ10_A
DQ9_A
DQ8_A
DQ7_A
DQ6_A
DQ5_A
DQ4_A
DQ3_A
DQ2_A
DQ1_A
DQ0_A
DQ31_B
DQ30_B
DQ29_B
DQ28_B
DQ27_B
DQ26_B
DQ25_B
DQ24_B
DQ23_B
DQ22_B
DQ21_B
DQ20_B
DQ19_B
DQ18_B
DQ17_B
DQ16_B
DQ15_B
DQ14_B
DQ13_B
DQ12_B
DQ11_B
DQ10_B
DQ9_B
DQ8_B
DQ7_B
DQ6_B
DQ5_B
DQ4_B
DQ3_B
DQ2_B
DQ1_B
DQ0_B
HAS
HSCL
HSDA
LBD||RSP_A_n
LBS||RSP_B_n
PAR_A
PAR_B
RESET_n
RFU6
RFU5
RFU4
RFU3
RFU2
RFU1
RFU0
VIN_MGMT
3/3
G3
G2
G1
VSS62
VSS61
VSS60
VSS58
VSS104
VSS102
VSS100
VIN_BULK2
VIN_BULK1
VIN_BULK0
VSS126
VSS125
VSS124
VSS123
VSS122
VSS121
VSS120
VSS119
VSS118
VSS117
VSS116
VSS115
VSS114
VSS113
VSS112
VSS111
VSS110
VSS109
VSS108
VSS107
VSS106
VSS105
VSS103
VSS101
VSS99
VSS98
VSS97
VSS96
VSS95
VSS94
VSS93
VSS92
VSS91
VSS90
VSS89
VSS88
VSS87
VSS86
VSS85
VSS84
VSS83
VSS82
VSS81
VSS80
VSS79
VSS78
VSS77
VSS76
VSS75
VSS74
VSS73
VSS72
VSS71
VSS70
VSS69
VSS68
VSS67
VSS66
VSS65
VSS64
VSS63
VSS59
VSS57
VSS56
VSS55
VSS54
VSS53
VSS52
VSS51
VSS50
VSS49
VSS48
VSS47
VSS46
VSS45
VSS44
VSS43
VSS42
VSS41
VSS40
VSS39
VSS38
VSS37
VSS36
VSS35
VSS34
VSS33
VSS32
VSS31
VSS30
VSS29
VSS28
VSS27
VSS26
VSS25
VSS24
VSS23
VSS22
VSS21
VSS20
VSS19
VSS18
VSS17
VSS16
VSS15
VSS14
VSS13
VSS12
VSS11
VSS10
VSS9
VSS8
VSS7
VSS6
VSS5
VSS4
VSS3
VSS2
VSS1
VSS0
21
21
SHEETDATE
DEPARTMENT
SIZE
PROJECT DOCUMENT NUMBER REV
REVIEWER
DESIGNER
123
7 3 2 1 6 5 4
E
A
B
C
E
D
C
B
A
7 6 5 4
D
IN
IN
BI
OUT
BI
IN
IN
OUTOUT
IN
OUT
OUTOUTIN
BI
ININ
IN
IN
OUT
ININ
BI
INBI
BI
OUT
C



Thu Sep 14 16:12:11 2023<NAME_2><NAME_1>MB FABCGT AMDV02101 OF 365P3V3P3V3_AUXP12V_MEM_CPU1
10198991001021031591599899100102103404040101404040404040404040409899100102103 4040404040404040401K04020.1UF25VX7R10%1%1K0402LFEMPTY1/16W
C080525V10UF10%X6SC080525V10UF10%X6S100402LFCHIPPD_CHD_CPU1_DIMM_SAAI3C_SPD_DDRAF_CPU1_SDAI3C_SPD_DDRD_CPU1_SDAI3C_SPD_DDRD_CPU1_SCLI3C_SPD_DDRAF_CPU1_SCLM_D_CPU1_ALERT_NM_D_CPU1_RESET_NM_D_CPU1_SB_CB<7:0>49.9PD_CHD_CPU1_DIMM_SAAM_D_CPU1_CLK_DN<0>M_D_CPU1_CLK_DP<0>M_D_CPU1_SA_CS_N<0>M_D_CPU1_SB_CS_N<0>M_D_CPU1_SA_CS_N<1>M_D_CPU1_SB_CS_N<1>M_D_CPU1_SA_PARM_D_CPU1_SB_PARM_D_CPU1_SB_RSP<0>M_D_CPU1_SA_RSP<0>PWRGD_CHAF_CPU1PWRGD_CHD_CPU1_DIMMM_D_CPU1_SB_DQS_DN<9:0>M_D_CPU1_SB_DQS_DP<9:0>M_D_CPU1_SA_DQS_DP<9:0>M_D_CPU1_SA_DQS_DN<9:0>M_D_CPU1_SB_DQ<31:0>M_D_CPU1_SA_DQ<31:0>M_D_CPU1_SB_CA<6:0>M_D_CPU1_SA_CA<6:0>M_D_CPU1_SA_CB<7:0>
DDR5 - CPU1 CHD
SMLFIOSCONN288_DDR506112002KQSMLFSCONN288_DDR506112002KQIOSMLFIOSCONN288_DDR506112002KQ
1/16WCHIP1%35.7K0402LF
J30
J30
J30
2
1C182
2
1C181
2
1
R106
2 1R306
2
1C148
2
1
R772
0
3
1
2
0
31
29
30
28
27
25
26
24
23
22
20
21
19
18
17
16
14
15
13
12
11
10
9
7
8
6
5
4
2
3
1
0
5
6
4
0
1
3
2
5
6
4
3
2
1
0
7
5
6
4
0
2
1
0
4
5
3
3
1
2
3
4
5
7
6
9
8
2
6
7
8
0
9
0
1
4
7
3
4
5
5
7
6
9
8
6
7
0
8
9
3
2
2
11
6
4
5
2
3
31
30
28
29
27
26
24
25
23
22
21
19
20
18
17
1
15
16
14
13
12
10
11
9
8
7
6
5
4
R1583
DQS7_A_c||TDQS7_A_c
DQS6_A_t||TDQS6_A_t
DQS8_B_t||TDQS8_B_t
DQS8_B_c||TDQS8_B_c
DQS7_B_t||TDQS7_B_t
DQS0_A_c
DQS0_A_t
DQS0_B_c
DQS0_B_t
DQS1_A_c
DQS1_A_t
DQS1_B_c
DQS1_B_t
DQS2_A_c
DQS2_A_t
DQS2_B_c
DQS2_B_t
DQS3_A_c
DQS3_A_t
DQS3_B_c
DQS3_B_t
DQS4_A_c
DQS4_A_t
DQS4_B_c
DQS4_B_t
DQS5_A_c||TDQS5_A_c||DQS5_A_t||TDQS5_A_t
DQS5_A_t||TDQS5_A_t
DQS5_B_c||TDQS5_B_c
DQS5_B_t||TDQS5_B_t
DQS6_A_c||TDQS6_A_c||DQS6_A_t||TDQS6_A_t
DQS6_B_c||TDQS6_B_c
DQS6_B_t||TDQS6_B_t
DQS7_A_t||TDQS7_A_t
DQS7_B_c||TDQS7_B_c
DQS8_A_c||TDQS8_A_c
DQS8_A_t||TDQS8_A_t
DQS9_A_c||TDQS9_A_c
DQS9_A_t||TDQS9_A_t
DQS9_B_c||TDQS9_B_c
DQS9_B_t||TDQS9_B_t||DBI4_B_n
R1699
93
94
201
200
283
282
190
189
272
271
179
178
261
260
168
167
250
249
157
156
239
238
55
56
137
138
44
45
126
127
33
34
115
116
22
23
104
105
11
12
288
286
284
281
279
277
275
273
270
268
266
264
262
259
257
255
253
251
248
246
244
242
240
237
235
233
230
228
226
224
222
219
216
214
212
210
208
206
204
202
199
197
195
193
191
188
186
184
182
180
177
175
173
171
169
166
164
162
160
158
155
153
151
143
141
139
136
134
132
130
128
125
123
121
119
117
114
112
110
108
106
103
101
99
97
95
92
90
88
85
83
81
79
77
75
73
71
69
67
65
63
61
59
57
54
52
50
48
46
43
41
39
37
35
32
30
28
26
24
21
19
17
15
13
10
8
6
146
145
1
G3
G2
G1
3
232
231
220
150
149
144
2
207
147
227
74
87
86
5
4
148
287
194
285
192
142
49
140
47
280
187
278
185
135
42
133
40
276
183
274
181
131
38
129
36
269
176
267
174
124
31
122
29
265
172
263
170
120
27
118
25
258
165
256
163
113
20
111
18
254
161
252
159
109
16
107
14
247
154
245
152
102
9
100
7
229
209
84
64
217
218
236
205
234
203
91
60
89
58
243
198
241
196
98
53
96
51
82
72
225
215
80
70
223
213
78
68
221
211
76
66
62
1/3
PWR_GOOD||FAIL_n
DQ31_A
CB7_A
CB4_A
CB1_A
CB7_B
ALERT_n
CA0_A
CA0_B
CA1_A
CA1_B
CA2_A
CA2_B
CA3_A
CA3_B
CA4_A
CA4_B
CA5_A
CA5_B
CA6_A
CA6_B
CB6_A
CB5_A
CB3_A
CB2_A
CB0_A
CB6_B
CB5_B
CB4_B
CB3_B
CB2_B
CB1_B
CB0_B
CK_c
CK_t
CS0_A_n
CS0_B_n
CS1_A_n
CS1_B_n
DQ30_A
DQ29_A
DQ28_A
DQ27_A
DQ26_A
DQ25_A
DQ24_A
DQ23_A
DQ22_A
DQ21_A
DQ20_A
DQ19_A
DQ18_A
DQ17_A
DQ16_A
DQ15_A
DQ14_A
DQ13_A
DQ12_A
DQ11_A
DQ10_A
DQ9_A
DQ8_A
DQ7_A
DQ6_A
DQ5_A
DQ4_A
DQ3_A
DQ2_A
DQ1_A
DQ0_A
DQ31_B
DQ30_B
DQ29_B
DQ28_B
DQ27_B
DQ26_B
DQ25_B
DQ24_B
DQ23_B
DQ22_B
DQ21_B
DQ20_B
DQ19_B
DQ18_B
DQ17_B
DQ16_B
DQ15_B
DQ14_B
DQ13_B
DQ12_B
DQ11_B
DQ10_B
DQ9_B
DQ8_B
DQ7_B
DQ6_B
DQ5_B
DQ4_B
DQ3_B
DQ2_B
DQ1_B
DQ0_B
HAS
HSCL
HSDA
LBD||RSP_A_n
LBS||RSP_B_n
PAR_A
PAR_B
RESET_n
RFU6
RFU5
RFU4
RFU3
RFU2
RFU1
RFU0
VIN_MGMT
2/3
3/3
G3
G2
G1
VSS62
VSS61
VSS60
VSS58
VSS104
VSS102
VSS100
VIN_BULK2
VIN_BULK1
VIN_BULK0
VSS126
VSS125
VSS124
VSS123
VSS122
VSS121
VSS120
VSS119
VSS118
VSS117
VSS116
VSS115
VSS114
VSS113
VSS112
VSS111
VSS110
VSS109
VSS108
VSS107
VSS106
VSS105
VSS103
VSS101
VSS99
VSS98
VSS97
VSS96
VSS95
VSS94
VSS93
VSS92
VSS91
VSS90
VSS89
VSS88
VSS87
VSS86
VSS85
VSS84
VSS83
VSS82
VSS81
VSS80
VSS79
VSS78
VSS77
VSS76
VSS75
VSS74
VSS73
VSS72
VSS71
VSS70
VSS69
VSS68
VSS67
VSS66
VSS65
VSS64
VSS63
VSS59
VSS57
VSS56
VSS55
VSS54
VSS53
VSS52
VSS51
VSS50
VSS49
VSS48
VSS47
VSS46
VSS45
VSS44
VSS43
VSS42
VSS41
VSS40
VSS39
VSS38
VSS37
VSS36
VSS35
VSS34
VSS33
VSS32
VSS31
VSS30
VSS29
VSS28
VSS27
VSS26
VSS25
VSS24
VSS23
VSS22
VSS21
VSS20
VSS19
VSS18
VSS17
VSS16
VSS15
VSS14
VSS13
VSS12
VSS11
VSS10
VSS9
VSS8
VSS7
VSS6
VSS5
VSS4
VSS3
VSS2
VSS1
VSS0
21
21
SHEETDATE
DEPARTMENT
SIZE
PROJECT DOCUMENT NUMBER REV
REVIEWER
DESIGNER
123
7 3 2 1 6 5 4
E
A
B
C
E
D
C
B
A
7 6 5 4
D
BI
OUT
INOUT
IN
IN
IN
ININ
ININ
ININ
ININ
BI
IN
OUTOUT
OUT
OUTOUT
BI
BI
BI
BI
OUT
C



Thu Sep 14 16:12:11 2023<NAME_2><NAME_1>MB FABCGT AMDV02102 OF 365P3V3P3V3_AUXP12V_MEM_CPU1
I3C_SPD_DDRE_CPU1_SCL989910010110315915998991001011034141414141414141989910010110310241414141414141414141414141411021K
X6SC080510%25V10UFX6S10%10UF25VC0805
1K1/16W1%EMPTY0402LFX7R10%25V0.1UF04020402LFCHIP10I3C_SPD_DDRAF_CPU1_SDAI3C_SPD_DDRAF_CPU1_SCL49.9I3C_SPD_DDRE_CPU1_SDAPWRGD_CHE_CPU1_DIMM1/16WCHIP1%54.9K0402LF
SCONN288_DDR506112002KQIOSMLFSCONN288_DDR506112002KQSMLFIOIOSCONN288_DDR506112002KQSMLF
DDR5 - CPU1 CHE
M_E_CPU1_SA_DQ<31:0>M_E_CPU1_SA_CA<6:0>M_E_CPU1_SB_CA<6:0>M_E_CPU1_SB_DQ<31:0>M_E_CPU1_SA_DQS_DN<9:0>M_E_CPU1_SA_DQS_DP<9:0>M_E_CPU1_SB_DQS_DP<9:0>M_E_CPU1_SB_DQS_DN<9:0>PWRGD_CHAF_CPU1PD_CHE_CPU1_DIMM_SAAM_E_CPU1_SA_RSP<0>M_E_CPU1_SB_PARM_E_CPU1_SA_PARM_E_CPU1_SB_RSP<0>M_E_CPU1_SA_CS_N<1>M_E_CPU1_SA_CS_N<0>M_E_CPU1_SB_CS_N<1>M_E_CPU1_SB_CS_N<0>M_E_CPU1_CLK_DP<0>M_E_CPU1_CLK_DN<0>M_E_CPU1_SA_CB<7:0>M_E_CPU1_SB_CB<7:0>M_E_CPU1_ALERT_NM_E_CPU1_RESET_NPD_CHE_CPU1_DIMM_SAA
J32
J32J32
2
1C509
2
1C183
2
1
R107
2 1R307
2
1C152
2
1
R6
7
8
9
11
10
14
13
12
15
16
0
17
18
19
20
21
23
22
24
27
26
1
25
28
29
31
30
2
3
4
5
6
0
7
0
2
8
9
2
6
7
5
9
8
7
6
5
4
3
1 1
0
4
3
2
1
8
9
6
7
3
9
8
7
6
5
3
5
4
1
2
4
4
3
2
1
0
0
5
6
7
1
0
2
3
4
6
5
0
1
2
3
4
5
6
2
3
0
1
4
5
6
7
8
9
10
11
13
12
15
14
16
18
19
17
21
20
22
24
23
26
25
27
29
28
30
31
1
0
2
3
4
6
5
R1584
DQS7_A_c||TDQS7_A_c
DQS6_A_t||TDQS6_A_t
DQS8_B_t||TDQS8_B_t
DQS8_B_c||TDQS8_B_c
DQS7_B_t||TDQS7_B_t
DQS0_A_c
DQS0_A_t
DQS0_B_c
DQS0_B_t
DQS1_A_c
DQS1_A_t
DQS1_B_c
DQS1_B_t
DQS2_A_c
DQS2_A_t
DQS2_B_c
DQS2_B_t
DQS3_A_c
DQS3_A_t
DQS3_B_c
DQS3_B_t
DQS4_A_c
DQS4_A_t
DQS4_B_c
DQS4_B_t
DQS5_A_c||TDQS5_A_c||DQS5_A_t||TDQS5_A_t
DQS5_A_t||TDQS5_A_t
DQS5_B_c||TDQS5_B_c
DQS5_B_t||TDQS5_B_t
DQS6_A_c||TDQS6_A_c||DQS6_A_t||TDQS6_A_t
DQS6_B_c||TDQS6_B_c
DQS6_B_t||TDQS6_B_t
DQS7_A_t||TDQS7_A_t
DQS7_B_c||TDQS7_B_c
DQS8_A_c||TDQS8_A_c
DQS8_A_t||TDQS8_A_t
DQS9_A_c||TDQS9_A_c
DQS9_A_t||TDQS9_A_t
DQS9_B_c||TDQS9_B_c
DQS9_B_t||TDQS9_B_t||DBI4_B_n
R1701
93
94
201
200
283
282
190
189
272
271
179
178
261
260
168
167
250
249
157
156
239
238
55
56
137
138
44
45
126
127
33
34
115
116
22
23
104
105
11
12
288
286
284
281
279
277
275
273
270
268
266
264
262
259
257
255
253
251
248
246
244
242
240
237
235
233
230
228
226
224
222
219
216
214
212
210
208
206
204
202
199
197
195
193
191
188
186
184
182
180
177
175
173
171
169
166
164
162
160
158
155
153
151
143
141
139
136
134
132
130
128
125
123
121
119
117
114
112
110
108
106
103
101
99
97
95
92
90
88
85
83
81
79
77
75
73
71
69
67
65
63
61
59
57
54
52
50
48
46
43
41
39
37
35
32
30
28
26
24
21
19
17
15
13
10
8
6
146
145
1
G3
G2
G1
3
232
231
220
150
149
144
2
207
147
227
74
87
86
5
4
148
287
194
285
192
142
49
140
47
280
187
278
185
135
42
133
40
276
183
274
181
131
38
129
36
269
176
267
174
124
31
122
29
265
172
263
170
120
27
118
25
258
165
256
163
113
20
111
18
254
161
252
159
109
16
107
14
247
154
245
152
102
9
100
7
229
209
84
64
217
218
236
205
234
203
91
60
89
58
243
198
241
196
98
53
96
51
82
72
225
215
80
70
223
213
78
68
221
211
76
66
62
1/3
PWR_GOOD||FAIL_n
DQ31_A
CB7_A
CB4_A
CB1_A
CB7_B
ALERT_n
CA0_A
CA0_B
CA1_A
CA1_B
CA2_A
CA2_B
CA3_A
CA3_B
CA4_A
CA4_B
CA5_A
CA5_B
CA6_A
CA6_B
CB6_A
CB5_A
CB3_A
CB2_A
CB0_A
CB6_B
CB5_B
CB4_B
CB3_B
CB2_B
CB1_B
CB0_B
CK_c
CK_t
CS0_A_n
CS0_B_n
CS1_A_n
CS1_B_n
DQ30_A
DQ29_A
DQ28_A
DQ27_A
DQ26_A
DQ25_A
DQ24_A
DQ23_A
DQ22_A
DQ21_A
DQ20_A
DQ19_A
DQ18_A
DQ17_A
DQ16_A
DQ15_A
DQ14_A
DQ13_A
DQ12_A
DQ11_A
DQ10_A
DQ9_A
DQ8_A
DQ7_A
DQ6_A
DQ5_A
DQ4_A
DQ3_A
DQ2_A
DQ1_A
DQ0_A
DQ31_B
DQ30_B
DQ29_B
DQ28_B
DQ27_B
DQ26_B
DQ25_B
DQ24_B
DQ23_B
DQ22_B
DQ21_B
DQ20_B
DQ19_B
DQ18_B
DQ17_B
DQ16_B
DQ15_B
DQ14_B
DQ13_B
DQ12_B
DQ11_B
DQ10_B
DQ9_B
DQ8_B
DQ7_B
DQ6_B
DQ5_B
DQ4_B
DQ3_B
DQ2_B
DQ1_B
DQ0_B
HAS
HSCL
HSDA
LBD||RSP_A_n
LBS||RSP_B_n
PAR_A
PAR_B
RESET_n
RFU6
RFU5
RFU4
RFU3
RFU2
RFU1
RFU0
VIN_MGMT
2/3
3/3
G3
G2
G1
VSS62
VSS61
VSS60
VSS58
VSS104
VSS102
VSS100
VIN_BULK2
VIN_BULK1
VIN_BULK0
VSS126
VSS125
VSS124
VSS123
VSS122
VSS121
VSS120
VSS119
VSS118
VSS117
VSS116
VSS115
VSS114
VSS113
VSS112
VSS111
VSS110
VSS109
VSS108
VSS107
VSS106
VSS105
VSS103
VSS101
VSS99
VSS98
VSS97
VSS96
VSS95
VSS94
VSS93
VSS92
VSS91
VSS90
VSS89
VSS88
VSS87
VSS86
VSS85
VSS84
VSS83
VSS82
VSS81
VSS80
VSS79
VSS78
VSS77
VSS76
VSS75
VSS74
VSS73
VSS72
VSS71
VSS70
VSS69
VSS68
VSS67
VSS66
VSS65
VSS64
VSS63
VSS59
VSS57
VSS56
VSS55
VSS54
VSS53
VSS52
VSS51
VSS50
VSS49
VSS48
VSS47
VSS46
VSS45
VSS44
VSS43
VSS42
VSS41
VSS40
VSS39
VSS38
VSS37
VSS36
VSS35
VSS34
VSS33
VSS32
VSS31
VSS30
VSS29
VSS28
VSS27
VSS26
VSS25
VSS24
VSS23
VSS22
VSS21
VSS20
VSS19
VSS18
VSS17
VSS16
VSS15
VSS14
VSS13
VSS12
VSS11
VSS10
VSS9
VSS8
VSS7
VSS6
VSS5
VSS4
VSS3
VSS2
VSS1
VSS0
21
21
SHEETDATE
DEPARTMENT
SIZE
PROJECT DOCUMENT NUMBER REV
REVIEWER
DESIGNER
123
7 3 2 1 6 5 4
E
A
B
C
E
D
C
B
A
7 6 5 4
D
BI
OUTIN
IN
IN
IN
ININ
ININ
OUT
ININ
ININ
BI
BI
IN
OUT
OUTOUT
OUTOUT
BI
OUT
BI
BI
C



Thu Sep 14 16:12:11 2023<NAME_2><NAME_1>MB FABCGT AMDV02103 OF 365P3V3
P12V_MEM_CPU1P3V3_AUX159989910010110298991001011021591034242424242424242424298991001011024242424242424242424210342421K
X6S10%10UF25VC0805X6S10%10UF25VC0805
1K1%1/16WEMPTY0402LF10%25VX7R0.1UF040210CHIP 0402LFI3C_SPD_DDRAF_CPU1_SCLI3C_SPD_DDRF_CPU1_SCLI3C_SPD_DDRAF_CPU1_SDAI3C_SPD_DDRF_CPU1_SDAPD_CHF_CPU1_DIMM_SAAPWRGD_CHF_CPU1_DIMM0402LF84.5K1%CHIP1/16W
IOSCONN288_DDR506112002KQSMLFIOSCONN288_DDR506112002KQSMLFSMLFIOSCONN288_DDR506112002KQ
DDR5 - CPU1 CHF
M_F_CPU1_SA_DQ<31:0>M_F_CPU1_SA_CB<7:0>M_F_CPU1_SB_CB<7:0>M_F_CPU1_SA_CA<6:0>M_F_CPU1_SB_CA<6:0>M_F_CPU1_SB_DQ<31:0>M_F_CPU1_SA_DQS_DN<9:0>M_F_CPU1_SA_DQS_DP<9:0>M_F_CPU1_SB_DQS_DP<9:0>M_F_CPU1_SB_DQS_DN<9:0>PWRGD_CHAF_CPU1M_F_CPU1_SB_RSP<0>M_F_CPU1_SA_RSP<0>M_F_CPU1_SB_PARM_F_CPU1_SA_PARM_F_CPU1_SB_CS_N<1>M_F_CPU1_SA_CS_N<1>M_F_CPU1_SB_CS_N<0>M_F_CPU1_SA_CS_N<0>M_F_CPU1_CLK_DP<0>M_F_CPU1_CLK_DN<0>PD_CHF_CPU1_DIMM_SAAM_F_CPU1_RESET_NM_F_CPU1_ALERT_N49.9
J33
J33
J33
2
1C527
2
1C518
2
1
R108
2 1R1183
2
1C156
2
1
R773
7
6
8
9
11
12
13
14
10
19
16
18
17
15
20
21
22
25
23
24
29
30
28
27
26
31
2
4
9
8
7
9
8
6
7
6
5
4
3
2
5
1
3
0
1
9
8
7
9
0
8
7
6
5
3
4
2
4
6
5
2
3
1
0
0
1
1
2
3
4
6
5
7
0
1
2
3
0
1
2
3
4
5
6
7
8
9
10
11
12
13
14
16
15
17
19
20
22
21
18
24
25
27
26
23
29
31
30
28
4
5
7
6
0
1
2
4
3
5
6
0
1
2
3
4
5
6
0
1
2
3
4
5
0
R1585
DQS7_A_c||TDQS7_A_c
DQS6_A_t||TDQS6_A_t
DQS8_B_t||TDQS8_B_t
DQS8_B_c||TDQS8_B_c
DQS7_B_t||TDQS7_B_t
DQS0_A_c
DQS0_A_t
DQS0_B_c
DQS0_B_t
DQS1_A_c
DQS1_A_t
DQS1_B_c
DQS1_B_t
DQS2_A_c
DQS2_A_t
DQS2_B_c
DQS2_B_t
DQS3_A_c
DQS3_A_t
DQS3_B_c
DQS3_B_t
DQS4_A_c
DQS4_A_t
DQS4_B_c
DQS4_B_t
DQS5_A_c||TDQS5_A_c||DQS5_A_t||TDQS5_A_t
DQS5_A_t||TDQS5_A_t
DQS5_B_c||TDQS5_B_c
DQS5_B_t||TDQS5_B_t
DQS6_A_c||TDQS6_A_c||DQS6_A_t||TDQS6_A_t
DQS6_B_c||TDQS6_B_c
DQS6_B_t||TDQS6_B_t
DQS7_A_t||TDQS7_A_t
DQS7_B_c||TDQS7_B_c
DQS8_A_c||TDQS8_A_c
DQS8_A_t||TDQS8_A_t
DQS9_A_c||TDQS9_A_c
DQS9_A_t||TDQS9_A_t
DQS9_B_c||TDQS9_B_c
DQS9_B_t||TDQS9_B_t||DBI4_B_n
R1704
93
94
201
200
283
282
190
189
272
271
179
178
261
260
168
167
250
249
157
156
239
238
55
56
137
138
44
45
126
127
33
34
115
116
22
23
104
105
11
12
288
286
284
281
279
277
275
273
270
268
266
264
262
259
257
255
253
251
248
246
244
242
240
237
235
233
230
228
226
224
222
219
216
214
212
210
208
206
204
202
199
197
195
193
191
188
186
184
182
180
177
175
173
171
169
166
164
162
160
158
155
153
151
143
141
139
136
134
132
130
128
125
123
121
119
117
114
112
110
108
106
103
101
99
97
95
92
90
88
85
83
81
79
77
75
73
71
69
67
65
63
61
59
57
54
52
50
48
46
43
41
39
37
35
32
30
28
26
24
21
19
17
15
13
10
8
6
146
145
1
G3
G2
G1
3
232
231
220
150
149
144
2
207
147
227
74
87
86
5
4
148
287
194
285
192
142
49
140
47
280
187
278
185
135
42
133
40
276
183
274
181
131
38
129
36
269
176
267
174
124
31
122
29
265
172
263
170
120
27
118
25
258
165
256
163
113
20
111
18
254
161
252
159
109
16
107
14
247
154
245
152
102
9
100
7
229
209
84
64
217
218
236
205
234
203
91
60
89
58
243
198
241
196
98
53
96
51
82
72
225
215
80
70
223
213
78
68
221
211
76
66
62
2/3
1/3
PWR_GOOD||FAIL_n
DQ31_A
CB7_A
CB4_A
CB1_A
CB7_B
ALERT_n
CA0_A
CA0_B
CA1_A
CA1_B
CA2_A
CA2_B
CA3_A
CA3_B
CA4_A
CA4_B
CA5_A
CA5_B
CA6_A
CA6_B
CB6_A
CB5_A
CB3_A
CB2_A
CB0_A
CB6_B
CB5_B
CB4_B
CB3_B
CB2_B
CB1_B
CB0_B
CK_c
CK_t
CS0_A_n
CS0_B_n
CS1_A_n
CS1_B_n
DQ30_A
DQ29_A
DQ28_A
DQ27_A
DQ26_A
DQ25_A
DQ24_A
DQ23_A
DQ22_A
DQ21_A
DQ20_A
DQ19_A
DQ18_A
DQ17_A
DQ16_A
DQ15_A
DQ14_A
DQ13_A
DQ12_A
DQ11_A
DQ10_A
DQ9_A
DQ8_A
DQ7_A
DQ6_A
DQ5_A
DQ4_A
DQ3_A
DQ2_A
DQ1_A
DQ0_A
DQ31_B
DQ30_B
DQ29_B
DQ28_B
DQ27_B
DQ26_B
DQ25_B
DQ24_B
DQ23_B
DQ22_B
DQ21_B
DQ20_B
DQ19_B
DQ18_B
DQ17_B
DQ16_B
DQ15_B
DQ14_B
DQ13_B
DQ12_B
DQ11_B
DQ10_B
DQ9_B
DQ8_B
DQ7_B
DQ6_B
DQ5_B
DQ4_B
DQ3_B
DQ2_B
DQ1_B
DQ0_B
HAS
HSCL
HSDA
LBD||RSP_A_n
LBS||RSP_B_n
PAR_A
PAR_B
RESET_n
RFU6
RFU5
RFU4
RFU3
RFU2
RFU1
RFU0
VIN_MGMT
3/3
G3
G2
G1
VSS62
VSS61
VSS60
VSS58
VSS104
VSS102
VSS100
VIN_BULK2
VIN_BULK1
VIN_BULK0
VSS126
VSS125
VSS124
VSS123
VSS122
VSS121
VSS120
VSS119
VSS118
VSS117
VSS116
VSS115
VSS114
VSS113
VSS112
VSS111
VSS110
VSS109
VSS108
VSS107
VSS106
VSS105
VSS103
VSS101
VSS99
VSS98
VSS97
VSS96
VSS95
VSS94
VSS93
VSS92
VSS91
VSS90
VSS89
VSS88
VSS87
VSS86
VSS85
VSS84
VSS83
VSS82
VSS81
VSS80
VSS79
VSS78
VSS77
VSS76
VSS75
VSS74
VSS73
VSS72
VSS71
VSS70
VSS69
VSS68
VSS67
VSS66
VSS65
VSS64
VSS63
VSS59
VSS57
VSS56
VSS55
VSS54
VSS53
VSS52
VSS51
VSS50
VSS49
VSS48
VSS47
VSS46
VSS45
VSS44
VSS43
VSS42
VSS41
VSS40
VSS39
VSS38
VSS37
VSS36
VSS35
VSS34
VSS33
VSS32
VSS31
VSS30
VSS29
VSS28
VSS27
VSS26
VSS25
VSS24
VSS23
VSS22
VSS21
VSS20
VSS19
VSS18
VSS17
VSS16
VSS15
VSS14
VSS13
VSS12
VSS11
VSS10
VSS9
VSS8
VSS7
VSS6
VSS5
VSS4
VSS3
VSS2
VSS1
VSS0
21
21
SHEETDATE
DEPARTMENT
SIZE
PROJECT DOCUMENT NUMBER REV
REVIEWER
DESIGNER
123
7 3 2 1 6 5 4
E
A
B
C
E
D
C
B
A
7 6 5 4
D
IN
IN
BI
OUT
BI
IN
IN
IN
OUT
OUTOUT
OUTOUTIN
BI
ININ
IN
IN
IN
IN
OUT
BI
INBI
BI
OUT
C



Thu Sep 14 16:12:12 2023<NAME_2><NAME_1>MB FABCGT AMDV02104 OF 365P3V3P3V3_AUXP3V3_AUXP3V3_AUXP3V3_AUX
P12V_MEM_CPU1
P3V310410510610710810915910510610710810910510610710810915943431044343434343434343434343
82104105106107108109104104 105 106 107 108 109
4343434343434343431K1/16WCHIP0402LF0.1UF25V10%X7R0402EMPTY1/16W1%1K0402LF1%0402LFEMPTY1/16W1K
10UFC080525V10%X6SX6SC080525V10UF10%
0402LFCHIP10PWRGD_CHGL_CPU1I3C_SPD_DDRGL_CPU1_SCLI3C_SPD_DDRG_CPU1_SCLI3C_SPD_DDRGL_CPU1_SDAI3C_SPD_DDRG_CPU1_SDAM_G_CPU1_ALERT_NM_G_CPU1_RESET_NPD_CHG_CPU1_DIMM0_SAAPWRGD_CHG_CPU1_DIMM049.9M_G_CPU1_SB_CB<7:0>M_G_CPU1_SB_PARM_G_CPU1_SA_PARM_G_CPU1_SB_RSP<0>M_G_CPU1_SA_RSP<0>M_G_CPU1_SB_CS_N<1>M_G_CPU1_SA_CS_N<1>M_G_CPU1_SB_CS_N<0>M_G_CPU1_SA_CS_N<0>M_G_CPU1_CLK_DP<0>M_G_CPU1_CLK_DN<0>
PWRGD_CHGL_CPU1_R2PWRGD_CHGL_CPU1PD_CHG_CPU1_DIMM0_SAAPWRGD_CHGL_CPU1PWRGD_CHGL_CPU1_R1
M_G_CPU1_SB_CA<6:0>M_G_CPU1_SA_DQ<31:0>M_G_CPU1_SB_DQ<31:0>M_G_CPU1_SA_DQS_DN<9:0>M_G_CPU1_SA_DQS_DP<9:0>M_G_CPU1_SB_DQS_DN<9:0>M_G_CPU1_SB_DQS_DP<9:0>M_G_CPU1_SA_CA<6:0>M_G_CPU1_SA_CB<7:0>
DDR5 - CPU1 CHGB0530WS7FSMLFEMPTY0402LFCHIP5%01/16W1/16W1%10K0402LFEMPTY05%0402LF1/16W CHIP1%0402LF10KCHIP1/16W
SCONN288_DDR506112002KQIOSMLFSCONN288_DDR506112002KQSMLFIO SMLFIOSCONN288_DDR506112002KQ
1%10K
J102
J102
J102
2
1C531
2
1C530
2
1
R110
2
1
R109
2 1
R1184
2
1C160
2
1
R37
13
7
1
0
3
2
4
6
5
4
3
1
2
0
5
6
3
4
0
1
2
7
6
5
4
29
28
31
30
24
23
27
26
25
19
18
22
21
20
14
12
17
15
16
9
8
7
11
10
4
3
2
6
5
0
1
3
0
7
2
1
6
5
2
3
4
0
0
1
2
0
1
2
3
4
1
5
6
7
3
4
5
6
7
8
9
0
1
2
8
9
0
1
2
3
4
5
6
7
3
5
4
6
7
8
9
8
9
31
26
27
29
28
30
22
21
20
25
23
24
17
16
15
19
18
12
11
10
14
13
5
8
9
6
R1586
DQS7_A_c||TDQS7_A_c
DQS6_A_t||TDQS6_A_t
DQS8_B_t||TDQS8_B_t
DQS8_B_c||TDQS8_B_c
DQS7_B_t||TDQS7_B_t
DQS0_A_c
DQS0_A_t
DQS0_B_c
DQS0_B_t
DQS1_A_c
DQS1_A_t
DQS1_B_c
DQS1_B_t
DQS2_A_c
DQS2_A_t
DQS2_B_c
DQS2_B_t
DQS3_A_c
DQS3_A_t
DQS3_B_c
DQS3_B_t
DQS4_A_c
DQS4_A_t
DQS4_B_c
DQS4_B_t
DQS5_A_c||TDQS5_A_c||DQS5_A_t||TDQS5_A_t
DQS5_A_t||TDQS5_A_t
DQS5_B_c||TDQS5_B_c
DQS5_B_t||TDQS5_B_t
DQS6_A_c||TDQS6_A_c||DQS6_A_t||TDQS6_A_t
DQS6_B_c||TDQS6_B_c
DQS6_B_t||TDQS6_B_t
DQS7_A_t||TDQS7_A_t
DQS7_B_c||TDQS7_B_c
DQS8_A_c||TDQS8_A_c
DQS8_A_t||TDQS8_A_t
DQS9_A_c||TDQS9_A_c
DQS9_A_t||TDQS9_A_t
DQS9_B_c||TDQS9_B_c
DQS9_B_t||TDQS9_B_t||DBI4_B_n
R1705
21
93
94
201
200
283
282
190
189
272
271
179
178
261
260
168
167
250
249
157
156
239
238
55
56
137
138
44
45
126
127
33
34
115
116
22
23
104
105
11
12
288
286
284
281
279
277
275
273
270
268
266
264
262
259
257
255
253
251
248
246
244
242
240
237
235
233
230
228
226
224
222
219
216
214
212
210
208
206
204
202
199
197
195
193
191
188
186
184
182
180
177
175
173
171
169
166
164
162
160
158
155
153
151
143
141
139
136
134
132
130
128
125
123
121
119
117
114
112
110
108
106
103
101
99
97
95
92
90
88
85
83
81
79
77
75
73
71
69
67
65
63
61
59
57
54
52
50
48
46
43
41
39
37
35
32
30
28
26
24
21
19
17
15
13
10
8
6
146
145
1
G3
G2
G1
3
232
231
220
150
149
144
2
207
147
227
74
87
86
5
4
148
287
194
285
192
142
49
140
47
280
187
278
185
135
42
133
40
276
183
274
181
131
38
129
36
269
176
267
174
124
31
122
29
265
172
263
170
120
27
118
25
258
165
256
163
113
20
111
18
254
161
252
159
109
16
107
14
247
154
245
152
102
9
100
7
229
209
84
64
217
218
236
205
234
203
91
60
89
58
243
198
241
196
98
53
96
51
82
72
225
215
80
70
223
213
78
68
221
211
76
66
62
D8006
CA
2/3
1/3
PWR_GOOD||FAIL_n
DQ31_A
CB7_A
CB4_A
CB1_A
CB7_B
ALERT_n
CA0_A
CA0_B
CA1_A
CA1_B
CA2_A
CA2_B
CA3_A
CA3_B
CA4_A
CA4_B
CA5_A
CA5_B
CA6_A
CA6_B
CB6_A
CB5_A
CB3_A
CB2_A
CB0_A
CB6_B
CB5_B
CB4_B
CB3_B
CB2_B
CB1_B
CB0_B
CK_c
CK_t
CS0_A_n
CS0_B_n
CS1_A_n
CS1_B_n
DQ30_A
DQ29_A
DQ28_A
DQ27_A
DQ26_A
DQ25_A
DQ24_A
DQ23_A
DQ22_A
DQ21_A
DQ20_A
DQ19_A
DQ18_A
DQ17_A
DQ16_A
DQ15_A
DQ14_A
DQ13_A
DQ12_A
DQ11_A
DQ10_A
DQ9_A
DQ8_A
DQ7_A
DQ6_A
DQ5_A
DQ4_A
DQ3_A
DQ2_A
DQ1_A
DQ0_A
DQ31_B
DQ30_B
DQ29_B
DQ28_B
DQ27_B
DQ26_B
DQ25_B
DQ24_B
DQ23_B
DQ22_B
DQ21_B
DQ20_B
DQ19_B
DQ18_B
DQ17_B
DQ16_B
DQ15_B
DQ14_B
DQ13_B
DQ12_B
DQ11_B
DQ10_B
DQ9_B
DQ8_B
DQ7_B
DQ6_B
DQ5_B
DQ4_B
DQ3_B
DQ2_B
DQ1_B
DQ0_B
HAS
HSCL
HSDA
LBD||RSP_A_n
LBS||RSP_B_n
PAR_A
PAR_B
RESET_n
RFU6
RFU5
RFU4
RFU3
RFU2
RFU1
RFU0
VIN_MGMT
3/3
G3
G2
G1
VSS62
VSS61
VSS60
VSS58
VSS104
VSS102
VSS100
VIN_BULK2
VIN_BULK1
VIN_BULK0
VSS126
VSS125
VSS124
VSS123
VSS122
VSS121
VSS120
VSS119
VSS118
VSS117
VSS116
VSS115
VSS114
VSS113
VSS112
VSS111
VSS110
VSS109
VSS108
VSS107
VSS106
VSS105
VSS103
VSS101
VSS99
VSS98
VSS97
VSS96
VSS95
VSS94
VSS93
VSS92
VSS91
VSS90
VSS89
VSS88
VSS87
VSS86
VSS85
VSS84
VSS83
VSS82
VSS81
VSS80
VSS79
VSS78
VSS77
VSS76
VSS75
VSS74
VSS73
VSS72
VSS71
VSS70
VSS69
VSS68
VSS67
VSS66
VSS65
VSS64
VSS63
VSS59
VSS57
VSS56
VSS55
VSS54
VSS53
VSS52
VSS51
VSS50
VSS49
VSS48
VSS47
VSS46
VSS45
VSS44
VSS43
VSS42
VSS41
VSS40
VSS39
VSS38
VSS37
VSS36
VSS35
VSS34
VSS33
VSS32
VSS31
VSS30
VSS29
VSS28
VSS27
VSS26
VSS25
VSS24
VSS23
VSS22
VSS21
VSS20
VSS19
VSS18
VSS17
VSS16
VSS15
VSS14
VSS13
VSS12
VSS11
VSS10
VSS9
VSS8
VSS7
VSS6
VSS5
VSS4
VSS3
VSS2
VSS1
VSS0
21
21
21
21
2
1
21
SHEETDATE
DEPARTMENT
SIZE
PROJECT DOCUMENT NUMBER REV
REVIEWER
DESIGNER
123
7 3 2 1 6 5 4
E
A
B
C
E
D
C
B
A
7 6 5 4
D
IN
IN
BI
OUT
BI
BIBI
OUT
IN
IN
IN
OUT
OUTOUT
OUTOUT
IN
BI
IN
ININ
ININ
IN
OUT
BI
INBI
BI
OUT
R8090
R8091
R8089
R8040
C



Thu Sep 14 16:12:12 2023<NAME_2><NAME_1>MB FABCGT AMDV02105 OF 365P3V3
P12V_MEM_CPU1P3V3_AUX105159104106107108109104106107108109159444444444444444444441041061071081094444444444444444441054444441K
X6S10%10UF25VC0805X6S10%10UF25VC0805
1K0402LFEMPTY1/16W1%X7R10%25V0.1UF0402CHIP 0402LF10PD_CHH_CPU1_DIMM_SAAI3C_SPD_DDRH_CPU1_SCLI3C_SPD_DDRGL_CPU1_SCLI3C_SPD_DDRGL_CPU1_SDAI3C_SPD_DDRH_CPU1_SDAPWRGD_CHH_CPU1_DIMM0402LF15.4K1%CHIP1/16W
SCONN288_DDR506112002KQIOSMLFIOSMLFSCONN288_DDR506112002KQSCONN288_DDR506112002KQIOSMLF
DDR5 - CPU1 CHH
M_H_CPU1_SA_DQ<31:0>M_H_CPU1_SA_CB<7:0>M_H_CPU1_SA_CA<6:0>M_H_CPU1_SB_CA<6:0>M_H_CPU1_SB_CB<7:0>M_H_CPU1_SB_DQ<31:0>M_H_CPU1_SA_DQS_DN<9:0>M_H_CPU1_SA_DQS_DP<9:0>M_H_CPU1_SB_DQS_DP<9:0>M_H_CPU1_SB_DQS_DN<9:0>PWRGD_CHGL_CPU1M_H_CPU1_SB_PARM_H_CPU1_SA_PARM_H_CPU1_SB_RSP<0>M_H_CPU1_SA_RSP<0>M_H_CPU1_SB_CS_N<1>M_H_CPU1_SA_CS_N<1>M_H_CPU1_SA_CS_N<0>M_H_CPU1_CLK_DP<0>M_H_CPU1_CLK_DN<0>PD_CHH_CPU1_DIMM_SAAM_H_CPU1_SB_CS_N<0>M_H_CPU1_ALERT_NM_H_CPU1_RESET_N49.9
J27
J27
J27
2
1C533
2
1C532
2
1
R111
2 1
R310
2
1C164
2
1
R774
7
8
9
11
10
12
13
14
16
15
18
17
19
21
20
22
23
25
24
26
29
28
27
30
31
2
3
4
5
9
8
9
8
7
6
5
4
1
0
8
9
7
6
3
2
1
0
9
8
7
6
5
3
4
2
1
0
2
7
6
5
4
3
2
1
0
3
1
0
4
5
6
7
0
1
2
3
4
0
2
3
1
4
5
6
7
8
9
10
11
13
12
14
15
16
17
18
19
20
21
22
23
24
25
26
27
28
29
31
30
0
7
6
5
3
2
1
0
4
5
6
1
0
2
3
4
6
5
1
2
3
6
4
5
R1587
DQS7_A_c||TDQS7_A_c
DQS6_A_t||TDQS6_A_t
DQS8_B_t||TDQS8_B_t
DQS8_B_c||TDQS8_B_c
DQS7_B_t||TDQS7_B_t
DQS0_A_c
DQS0_A_t
DQS0_B_c
DQS0_B_t
DQS1_A_c
DQS1_A_t
DQS1_B_c
DQS1_B_t
DQS2_A_c
DQS2_A_t
DQS2_B_c
DQS2_B_t
DQS3_A_c
DQS3_A_t
DQS3_B_c
DQS3_B_t
DQS4_A_c
DQS4_A_t
DQS4_B_c
DQS4_B_t
DQS5_A_c||TDQS5_A_c||DQS5_A_t||TDQS5_A_t
DQS5_A_t||TDQS5_A_t
DQS5_B_c||TDQS5_B_c
DQS5_B_t||TDQS5_B_t
DQS6_A_c||TDQS6_A_c||DQS6_A_t||TDQS6_A_t
DQS6_B_c||TDQS6_B_c
DQS6_B_t||TDQS6_B_t
DQS7_A_t||TDQS7_A_t
DQS7_B_c||TDQS7_B_c
DQS8_A_c||TDQS8_A_c
DQS8_A_t||TDQS8_A_t
DQS9_A_c||TDQS9_A_c
DQS9_A_t||TDQS9_A_t
DQS9_B_c||TDQS9_B_c
DQS9_B_t||TDQS9_B_t||DBI4_B_n
R1707
93
94
201
200
283
282
190
189
272
271
179
178
261
260
168
167
250
249
157
156
239
238
55
56
137
138
44
45
126
127
33
34
115
116
22
23
104
105
11
12
288
286
284
281
279
277
275
273
270
268
266
264
262
259
257
255
253
251
248
246
244
242
240
237
235
233
230
228
226
224
222
219
216
214
212
210
208
206
204
202
199
197
195
193
191
188
186
184
182
180
177
175
173
171
169
166
164
162
160
158
155
153
151
143
141
139
136
134
132
130
128
125
123
121
119
117
114
112
110
108
106
103
101
99
97
95
92
90
88
85
83
81
79
77
75
73
71
69
67
65
63
61
59
57
54
52
50
48
46
43
41
39
37
35
32
30
28
26
24
21
19
17
15
13
10
8
6
146
145
1
G3
G2
G1
3
232
231
220
150
149
144
2
207
147
227
74
87
86
5
4
148
287
194
285
192
142
49
140
47
280
187
278
185
135
42
133
40
276
183
274
181
131
38
129
36
269
176
267
174
124
31
122
29
265
172
263
170
120
27
118
25
258
165
256
163
113
20
111
18
254
161
252
159
109
16
107
14
247
154
245
152
102
9
100
7
229
209
84
64
217
218
236
205
234
203
91
60
89
58
243
198
241
196
98
53
96
51
82
72
225
215
80
70
223
213
78
68
221
211
76
66
62
2/3
1/3
PWR_GOOD||FAIL_n
DQ31_A
CB7_A
CB4_A
CB1_A
CB7_B
ALERT_n
CA0_A
CA0_B
CA1_A
CA1_B
CA2_A
CA2_B
CA3_A
CA3_B
CA4_A
CA4_B
CA5_A
CA5_B
CA6_A
CA6_B
CB6_A
CB5_A
CB3_A
CB2_A
CB0_A
CB6_B
CB5_B
CB4_B
CB3_B
CB2_B
CB1_B
CB0_B
CK_c
CK_t
CS0_A_n
CS0_B_n
CS1_A_n
CS1_B_n
DQ30_A
DQ29_A
DQ28_A
DQ27_A
DQ26_A
DQ25_A
DQ24_A
DQ23_A
DQ22_A
DQ21_A
DQ20_A
DQ19_A
DQ18_A
DQ17_A
DQ16_A
DQ15_A
DQ14_A
DQ13_A
DQ12_A
DQ11_A
DQ10_A
DQ9_A
DQ8_A
DQ7_A
DQ6_A
DQ5_A
DQ4_A
DQ3_A
DQ2_A
DQ1_A
DQ0_A
DQ31_B
DQ30_B
DQ29_B
DQ28_B
DQ27_B
DQ26_B
DQ25_B
DQ24_B
DQ23_B
DQ22_B
DQ21_B
DQ20_B
DQ19_B
DQ18_B
DQ17_B
DQ16_B
DQ15_B
DQ14_B
DQ13_B
DQ12_B
DQ11_B
DQ10_B
DQ9_B
DQ8_B
DQ7_B
DQ6_B
DQ5_B
DQ4_B
DQ3_B
DQ2_B
DQ1_B
DQ0_B
HAS
HSCL
HSDA
LBD||RSP_A_n
LBS||RSP_B_n
PAR_A
PAR_B
RESET_n
RFU6
RFU5
RFU4
RFU3
RFU2
RFU1
RFU0
VIN_MGMT
3/3
G3
G2
G1
VSS62
VSS61
VSS60
VSS58
VSS104
VSS102
VSS100
VIN_BULK2
VIN_BULK1
VIN_BULK0
VSS126
VSS125
VSS124
VSS123
VSS122
VSS121
VSS120
VSS119
VSS118
VSS117
VSS116
VSS115
VSS114
VSS113
VSS112
VSS111
VSS110
VSS109
VSS108
VSS107
VSS106
VSS105
VSS103
VSS101
VSS99
VSS98
VSS97
VSS96
VSS95
VSS94
VSS93
VSS92
VSS91
VSS90
VSS89
VSS88
VSS87
VSS86
VSS85
VSS84
VSS83
VSS82
VSS81
VSS80
VSS79
VSS78
VSS77
VSS76
VSS75
VSS74
VSS73
VSS72
VSS71
VSS70
VSS69
VSS68
VSS67
VSS66
VSS65
VSS64
VSS63
VSS59
VSS57
VSS56
VSS55
VSS54
VSS53
VSS52
VSS51
VSS50
VSS49
VSS48
VSS47
VSS46
VSS45
VSS44
VSS43
VSS42
VSS41
VSS40
VSS39
VSS38
VSS37
VSS36
VSS35
VSS34
VSS33
VSS32
VSS31
VSS30
VSS29
VSS28
VSS27
VSS26
VSS25
VSS24
VSS23
VSS22
VSS21
VSS20
VSS19
VSS18
VSS17
VSS16
VSS15
VSS14
VSS13
VSS12
VSS11
VSS10
VSS9
VSS8
VSS7
VSS6
VSS5
VSS4
VSS3
VSS2
VSS1
VSS0
21
21
SHEETDATE
DEPARTMENT
SIZE
PROJECT DOCUMENT NUMBER REV
REVIEWER
DESIGNER
123
7 3 2 1 6 5 4
E
A
B
C
E
D
C
B
A
7 6 5 4
D
IN
BI
OUT
IN
BI
IN
IN
OUTOUT
IN
OUT
OUTOUT
IN
BI
IN
IN
IN
ININ
IN
OUT
BI
BIIN
BI
OUT
C



Thu Sep 14 16:12:12 2023<NAME_2><NAME_1>MB FABCGT AMDV02106 OF 365P3V3
P12V_MEM_CPU1P3V3_AUX1061591041051071081091041051071081091594545454545454545451041051071081094545106
45454545454545454545451K
X6S10%10UF25VC0805X6S10%25VC080510UF
0402LF1K1%1/16WEMPTY040225V0.1UFX7R10%100402LFCHIPPD_CHI_CPU1_DIMM_SAAI3C_SPD_DDRGL_CPU1_SCLPWRGD_CHI_CPU1_DIMMI3C_SPD_DDRGL_CPU1_SDA49.9I3C_SPD_DDRI_CPU1_SCLI3C_SPD_DDRI_CPU1_SDA1/16WCHIP1%23.2K0402LF
SCONN288_DDR506112002KQIOSMLFSCONN288_DDR506112002KQIOSMLFSMLFSCONN288_DDR506112002KQIO
DDR5 - CPU1 CHI
M_I_CPU1_SA_CB<7:0>M_I_CPU1_SA_CA<6:0>M_I_CPU1_SB_CA<6:0>M_I_CPU1_SA_DQ<31:0>M_I_CPU1_SB_DQ<31:0>M_I_CPU1_SA_DQS_DN<9:0>M_I_CPU1_SA_DQS_DP<9:0>M_I_CPU1_SB_DQS_DP<9:0>M_I_CPU1_SB_DQS_DN<9:0>PWRGD_CHGL_CPU1M_I_CPU1_SA_RSP<0>M_I_CPU1_SB_RSP<0>PD_CHI_CPU1_DIMM_SAA
M_I_CPU1_SB_PARM_I_CPU1_SA_PARM_I_CPU1_SB_CS_N<1>M_I_CPU1_SA_CS_N<1>M_I_CPU1_SB_CS_N<0>M_I_CPU1_SA_CS_N<0>M_I_CPU1_CLK_DP<0>M_I_CPU1_CLK_DN<0>M_I_CPU1_SB_CB<7:0>M_I_CPU1_RESET_NM_I_CPU1_ALERT_N
J100
J100
J100 2
1C535
2
1C534
2
1
R112
2 1
R311
2
1C168
2
1
R775
7
10
9
8
11
12
13
14
15
17
16
20
19
18
22
21
25
24
23
27
28
26
30
29
31
7
9
0
1
3
9
9
8
8
7
6
5
4
2
3
7
6
4
5
2
1
0
8
9
8
6
5
4
3
2
1
0
7
6
0
5
3
4
2
1
0
1
2
3
4
5
6
7
0
1
3
2
0
2
1
4
3
5
6
7
9
8
10
12
11
14
13
15
17
16
20
19
18
21
22
25
24
23
26
27
30
29
28
31
4
5
6
7
0
1
2
3
4
5
6
0
1
2
3
4
5
6
0
2
1
3
4
5
6
R1588
DQS7_A_c||TDQS7_A_c
DQS6_A_t||TDQS6_A_t
DQS8_B_t||TDQS8_B_t
DQS8_B_c||TDQS8_B_c
DQS7_B_t||TDQS7_B_t
DQS0_A_c
DQS0_A_t
DQS0_B_c
DQS0_B_t
DQS1_A_c
DQS1_A_t
DQS1_B_c
DQS1_B_t
DQS2_A_c
DQS2_A_t
DQS2_B_c
DQS2_B_t
DQS3_A_c
DQS3_A_t
DQS3_B_c
DQS3_B_t
DQS4_A_c
DQS4_A_t
DQS4_B_c
DQS4_B_t
DQS5_A_c||TDQS5_A_c||DQS5_A_t||TDQS5_A_t
DQS5_A_t||TDQS5_A_t
DQS5_B_c||TDQS5_B_c
DQS5_B_t||TDQS5_B_t
DQS6_A_c||TDQS6_A_c||DQS6_A_t||TDQS6_A_t
DQS6_B_c||TDQS6_B_c
DQS6_B_t||TDQS6_B_t
DQS7_A_t||TDQS7_A_t
DQS7_B_c||TDQS7_B_c
DQS8_A_c||TDQS8_A_c
DQS8_A_t||TDQS8_A_t
DQS9_A_c||TDQS9_A_c
DQS9_A_t||TDQS9_A_t
DQS9_B_c||TDQS9_B_c
DQS9_B_t||TDQS9_B_t||DBI4_B_n
R1708
93
94
201
200
283
282
190
189
272
271
179
178
261
260
168
167
250
249
157
156
239
238
55
56
137
138
44
45
126
127
33
34
115
116
22
23
104
105
11
12
288
286
284
281
279
277
275
273
270
268
266
264
262
259
257
255
253
251
248
246
244
242
240
237
235
233
230
228
226
224
222
219
216
214
212
210
208
206
204
202
199
197
195
193
191
188
186
184
182
180
177
175
173
171
169
166
164
162
160
158
155
153
151
143
141
139
136
134
132
130
128
125
123
121
119
117
114
112
110
108
106
103
101
99
97
95
92
90
88
85
83
81
79
77
75
73
71
69
67
65
63
61
59
57
54
52
50
48
46
43
41
39
37
35
32
30
28
26
24
21
19
17
15
13
10
8
6
146
145
1
G3
G2
G1
3
232
231
220
150
149
144
2
207
147
227
74
87
86
5
4
148
287
194
285
192
142
49
140
47
280
187
278
185
135
42
133
40
276
183
274
181
131
38
129
36
269
176
267
174
124
31
122
29
265
172
263
170
120
27
118
25
258
165
256
163
113
20
111
18
254
161
252
159
109
16
107
14
247
154
245
152
102
9
100
7
229
209
84
64
217
218
236
205
234
203
91
60
89
58
243
198
241
196
98
53
96
51
82
72
225
215
80
70
223
213
78
68
221
211
76
66
62
2/3
1/3
PWR_GOOD||FAIL_n
DQ31_A
CB7_A
CB4_A
CB1_A
CB7_B
ALERT_n
CA0_A
CA0_B
CA1_A
CA1_B
CA2_A
CA2_B
CA3_A
CA3_B
CA4_A
CA4_B
CA5_A
CA5_B
CA6_A
CA6_B
CB6_A
CB5_A
CB3_A
CB2_A
CB0_A
CB6_B
CB5_B
CB4_B
CB3_B
CB2_B
CB1_B
CB0_B
CK_c
CK_t
CS0_A_n
CS0_B_n
CS1_A_n
CS1_B_n
DQ30_A
DQ29_A
DQ28_A
DQ27_A
DQ26_A
DQ25_A
DQ24_A
DQ23_A
DQ22_A
DQ21_A
DQ20_A
DQ19_A
DQ18_A
DQ17_A
DQ16_A
DQ15_A
DQ14_A
DQ13_A
DQ12_A
DQ11_A
DQ10_A
DQ9_A
DQ8_A
DQ7_A
DQ6_A
DQ5_A
DQ4_A
DQ3_A
DQ2_A
DQ1_A
DQ0_A
DQ31_B
DQ30_B
DQ29_B
DQ28_B
DQ27_B
DQ26_B
DQ25_B
DQ24_B
DQ23_B
DQ22_B
DQ21_B
DQ20_B
DQ19_B
DQ18_B
DQ17_B
DQ16_B
DQ15_B
DQ14_B
DQ13_B
DQ12_B
DQ11_B
DQ10_B
DQ9_B
DQ8_B
DQ7_B
DQ6_B
DQ5_B
DQ4_B
DQ3_B
DQ2_B
DQ1_B
DQ0_B
HAS
HSCL
HSDA
LBD||RSP_A_n
LBS||RSP_B_n
PAR_A
PAR_B
RESET_n
RFU6
RFU5
RFU4
RFU3
RFU2
RFU1
RFU0
VIN_MGMT
3/3
G3
G2
G1
VSS62
VSS61
VSS60
VSS58
VSS104
VSS102
VSS100
VIN_BULK2
VIN_BULK1
VIN_BULK0
VSS126
VSS125
VSS124
VSS123
VSS122
VSS121
VSS120
VSS119
VSS118
VSS117
VSS116
VSS115
VSS114
VSS113
VSS112
VSS111
VSS110
VSS109
VSS108
VSS107
VSS106
VSS105
VSS103
VSS101
VSS99
VSS98
VSS97
VSS96
VSS95
VSS94
VSS93
VSS92
VSS91
VSS90
VSS89
VSS88
VSS87
VSS86
VSS85
VSS84
VSS83
VSS82
VSS81
VSS80
VSS79
VSS78
VSS77
VSS76
VSS75
VSS74
VSS73
VSS72
VSS71
VSS70
VSS69
VSS68
VSS67
VSS66
VSS65
VSS64
VSS63
VSS59
VSS57
VSS56
VSS55
VSS54
VSS53
VSS52
VSS51
VSS50
VSS49
VSS48
VSS47
VSS46
VSS45
VSS44
VSS43
VSS42
VSS41
VSS40
VSS39
VSS38
VSS37
VSS36
VSS35
VSS34
VSS33
VSS32
VSS31
VSS30
VSS29
VSS28
VSS27
VSS26
VSS25
VSS24
VSS23
VSS22
VSS21
VSS20
VSS19
VSS18
VSS17
VSS16
VSS15
VSS14
VSS13
VSS12
VSS11
VSS10
VSS9
VSS8
VSS7
VSS6
VSS5
VSS4
VSS3
VSS2
VSS1
VSS0
21
21
SHEETDATE
DEPARTMENT
SIZE
PROJECT DOCUMENT NUMBER REV
REVIEWER
DESIGNER
123
7 3 2 1 6 5 4
E
A
B
C
E
D
C
B
A
7 6 5 4
D
IN
BI
OUT
IN
BI
IN
IN
OUT
IN
OUT
OUT
OUTOUT
IN
BI
IN
IN
IN
IN
ININ
OUT
BI
INBI
BI
OUT
C



Thu Sep 14 16:12:13 2023<NAME_2><NAME_1>MB FABCGT AMDV02107 OF 365
P3V3_AUXP12V_MEM_CPU1
P3V3M_J_CPU1_ALERT_N107104105106108109159159104105106108109464646464646464646464610746104105106108109464646464646464646461K25V040210%0.1UFX7R1%1KEMPTY0402LF1/16W
C080525V10UF10%X6SC080525V10UF10%X6S10CHIP 0402LFPD_CHJ_CPU1_DIMM_SAAI3C_SPD_DDRGL_CPU1_SDAI3C_SPD_DDRJ_CPU1_SDAI3C_SPD_DDRJ_CPU1_SCLI3C_SPD_DDRGL_CPU1_SCLPWRGD_CHJ_CPU1_DIMMM_J_CPU1_SA_CS_N<0>49.9M_J_CPU1_RESET_NM_J_CPU1_SB_PARM_J_CPU1_SA_PARM_J_CPU1_SB_RSP<0>M_J_CPU1_SB_CS_N<1>M_J_CPU1_SA_CS_N<1>M_J_CPU1_SB_CS_N<0>M_J_CPU1_CLK_DP<0>M_J_CPU1_CLK_DN<0>PD_CHJ_CPU1_DIMM_SAAM_J_CPU1_SA_RSP<0>PWRGD_CHGL_CPU1M_J_CPU1_SB_CA<6:0>M_J_CPU1_SA_CB<7:0>M_J_CPU1_SB_CB<7:0>M_J_CPU1_SA_CA<6:0> M_J_CPU1_SA_DQ<31:0>M_J_CPU1_SB_DQS_DN<9:0>M_J_CPU1_SB_DQS_DP<9:0>M_J_CPU1_SA_DQS_DN<9:0>M_J_CPU1_SA_DQS_DP<9:0>M_J_CPU1_SB_DQ<31:0>
DDR5 - CPU1 CHJ
SCONN288_DDR506112002KQSMLFIOSMLFSCONN288_DDR506112002KQIO SMLFSCONN288_DDR506112002KQIO
1/16WCHIP1%35.7K0402LF
J29
J29
J29 2
1C537
2
1C536
2
1
R113
2 1
R312
2
1C172
2
1
R776
6
5
4
3
2
6
5
4
3
2
1
0
6
5
3
4
1
2
0
7
6
1
0
30
31
28
29
27
26
25
23
24
22
21
20
19
18
17
15
16
14
13
12
10
11
9
7
8
5
6
4
3
2
1
0
4
5
3
2
1
0
7
6
5
3
4
2
1
0
1
3
2
4
5
0
6
7
8
0
1
2
3
4
6
5
7
8
0
9
1
2
4
3
5
6
7
9
0
2
1
3
4
5
7
6
8
8
9
9
31
29
30
28
27
26
25
24
23
22
21
20
19
18
17
16
15
14
13
11
12
10
9
8
7
R1709
R1589
DQS7_A_c||TDQS7_A_c
DQS6_A_t||TDQS6_A_t
DQS8_B_t||TDQS8_B_t
DQS8_B_c||TDQS8_B_c
DQS7_B_t||TDQS7_B_t
DQS0_A_c
DQS0_A_t
DQS0_B_c
DQS0_B_t
DQS1_A_c
DQS1_A_t
DQS1_B_c
DQS1_B_t
DQS2_A_c
DQS2_A_t
DQS2_B_c
DQS2_B_t
DQS3_A_c
DQS3_A_t
DQS3_B_c
DQS3_B_t
DQS4_A_c
DQS4_A_t
DQS4_B_c
DQS4_B_t
DQS5_A_c||TDQS5_A_c||DQS5_A_t||TDQS5_A_t
DQS5_A_t||TDQS5_A_t
DQS5_B_c||TDQS5_B_c
DQS5_B_t||TDQS5_B_t
DQS6_A_c||TDQS6_A_c||DQS6_A_t||TDQS6_A_t
DQS6_B_c||TDQS6_B_c
DQS6_B_t||TDQS6_B_t
DQS7_A_t||TDQS7_A_t
DQS7_B_c||TDQS7_B_c
DQS8_A_c||TDQS8_A_c
DQS8_A_t||TDQS8_A_t
DQS9_A_c||TDQS9_A_c
DQS9_A_t||TDQS9_A_t
DQS9_B_c||TDQS9_B_c
DQS9_B_t||TDQS9_B_t||DBI4_B_n93
94
201
200
283
282
190
189
272
271
179
178
261
260
168
167
250
249
157
156
239
238
55
56
137
138
44
45
126
127
33
34
115
116
22
23
104
105
11
12
288
286
284
281
279
277
275
273
270
268
266
264
262
259
257
255
253
251
248
246
244
242
240
237
235
233
230
228
226
224
222
219
216
214
212
210
208
206
204
202
199
197
195
193
191
188
186
184
182
180
177
175
173
171
169
166
164
162
160
158
155
153
151
143
141
139
136
134
132
130
128
125
123
121
119
117
114
112
110
108
106
103
101
99
97
95
92
90
88
85
83
81
79
77
75
73
71
69
67
65
63
61
59
57
54
52
50
48
46
43
41
39
37
35
32
30
28
26
24
21
19
17
15
13
10
8
6
146
145
1
G3
G2
G1
3
232
231
220
150
149
144
2
207
147
227
74
87
86
5
4
148
287
194
285
192
142
49
140
47
280
187
278
185
135
42
133
40
276
183
274
181
131
38
129
36
269
176
267
174
124
31
122
29
265
172
263
170
120
27
118
25
258
165
256
163
113
20
111
18
254
161
252
159
109
16
107
14
247
154
245
152
102
9
100
7
229
209
84
64
217
218
236
205
234
203
91
60
89
58
243
198
241
196
98
53
96
51
82
72
225
215
80
70
223
213
78
68
221
211
76
66
62
2/3
1/3
PWR_GOOD||FAIL_n
DQ31_A
CB7_A
CB4_A
CB1_A
CB7_B
ALERT_n
CA0_A
CA0_B
CA1_A
CA1_B
CA2_A
CA2_B
CA3_A
CA3_B
CA4_A
CA4_B
CA5_A
CA5_B
CA6_A
CA6_B
CB6_A
CB5_A
CB3_A
CB2_A
CB0_A
CB6_B
CB5_B
CB4_B
CB3_B
CB2_B
CB1_B
CB0_B
CK_c
CK_t
CS0_A_n
CS0_B_n
CS1_A_n
CS1_B_n
DQ30_A
DQ29_A
DQ28_A
DQ27_A
DQ26_A
DQ25_A
DQ24_A
DQ23_A
DQ22_A
DQ21_A
DQ20_A
DQ19_A
DQ18_A
DQ17_A
DQ16_A
DQ15_A
DQ14_A
DQ13_A
DQ12_A
DQ11_A
DQ10_A
DQ9_A
DQ8_A
DQ7_A
DQ6_A
DQ5_A
DQ4_A
DQ3_A
DQ2_A
DQ1_A
DQ0_A
DQ31_B
DQ30_B
DQ29_B
DQ28_B
DQ27_B
DQ26_B
DQ25_B
DQ24_B
DQ23_B
DQ22_B
DQ21_B
DQ20_B
DQ19_B
DQ18_B
DQ17_B
DQ16_B
DQ15_B
DQ14_B
DQ13_B
DQ12_B
DQ11_B
DQ10_B
DQ9_B
DQ8_B
DQ7_B
DQ6_B
DQ5_B
DQ4_B
DQ3_B
DQ2_B
DQ1_B
DQ0_B
HAS
HSCL
HSDA
LBD||RSP_A_n
LBS||RSP_B_n
PAR_A
PAR_B
RESET_n
RFU6
RFU5
RFU4
RFU3
RFU2
RFU1
RFU0
VIN_MGMT
3/3
G3
G2
G1
VSS62
VSS61
VSS60
VSS58
VSS104
VSS102
VSS100
VIN_BULK2
VIN_BULK1
VIN_BULK0
VSS126
VSS125
VSS124
VSS123
VSS122
VSS121
VSS120
VSS119
VSS118
VSS117
VSS116
VSS115
VSS114
VSS113
VSS112
VSS111
VSS110
VSS109
VSS108
VSS107
VSS106
VSS105
VSS103
VSS101
VSS99
VSS98
VSS97
VSS96
VSS95
VSS94
VSS93
VSS92
VSS91
VSS90
VSS89
VSS88
VSS87
VSS86
VSS85
VSS84
VSS83
VSS82
VSS81
VSS80
VSS79
VSS78
VSS77
VSS76
VSS75
VSS74
VSS73
VSS72
VSS71
VSS70
VSS69
VSS68
VSS67
VSS66
VSS65
VSS64
VSS63
VSS59
VSS57
VSS56
VSS55
VSS54
VSS53
VSS52
VSS51
VSS50
VSS49
VSS48
VSS47
VSS46
VSS45
VSS44
VSS43
VSS42
VSS41
VSS40
VSS39
VSS38
VSS37
VSS36
VSS35
VSS34
VSS33
VSS32
VSS31
VSS30
VSS29
VSS28
VSS27
VSS26
VSS25
VSS24
VSS23
VSS22
VSS21
VSS20
VSS19
VSS18
VSS17
VSS16
VSS15
VSS14
VSS13
VSS12
VSS11
VSS10
VSS9
VSS8
VSS7
VSS6
VSS5
VSS4
VSS3
VSS2
VSS1
VSS0
21
21
SHEETDATE
DEPARTMENT
SIZE
PROJECT DOCUMENT NUMBER REV
REVIEWER
DESIGNER
123
7 3 2 1 6 5 4
E
A
B
C
E
D
C
B
A
7 6 5 4
D
OUTIN
BI
OUTOUT
IN
BI
IN
IN
IN
OUTOUT
OUTOUT
IN
BI
IN
IN
ININ
IN
IN
OUT
BI
INBI
BI
C



Thu Sep 14 16:12:13 2023<NAME_2><NAME_1>MB FABCGT AMDV02108 OF 365P3V3
P12V_MEM_CPU1P3V3_AUXM_K_CPU1_ALERT_N10815910410510610710910410510610710915947474747474747474747104105106107109108
4747474747474747474747471K
X6S10%10UF25VC0805X6S10%10UF25VC0805
1K0402LFEMPTY1/16W1%10%0402X7R25V0.1UFCHIP 0402LF10PD_CHK_CPU1_DIMM_SAAI3C_SPD_DDRGL_CPU1_SCLPWRGD_CHK_CPU1_DIMMI3C_SPD_DDRGL_CPU1_SDAI3C_SPD_DDRK_CPU1_SDAI3C_SPD_DDRK_CPU1_SCL1/16WCHIP1%54.9K0402LF
IOSMLFSCONN288_DDR506112002KQSCONN288_DDR506112002KQIOSMLFSMLFSCONN288_DDR506112002KQIO
DDR5 - CPU1 CHK
M_K_CPU1_SA_DQ<31:0>M_K_CPU1_SA_CB<7:0>M_K_CPU1_SB_CB<7:0>M_K_CPU1_SA_CA<6:0>M_K_CPU1_SB_CA<6:0>M_K_CPU1_SB_DQ<31:0>M_K_CPU1_SA_DQS_DN<9:0>M_K_CPU1_SA_DQS_DP<9:0>M_K_CPU1_SB_DQS_DP<9:0>M_K_CPU1_SB_DQS_DN<9:0>PWRGD_CHGL_CPU1PD_CHK_CPU1_DIMM_SAA
M_K_CPU1_SB_PARM_K_CPU1_SA_PARM_K_CPU1_SB_RSP<0>M_K_CPU1_SA_RSP<0>M_K_CPU1_SB_CS_N<1>M_K_CPU1_SA_CS_N<1>M_K_CPU1_SB_CS_N<0>M_K_CPU1_SA_CS_N<0>M_K_CPU1_CLK_DP<0>M_K_CPU1_CLK_DN<0>M_K_CPU1_RESET_N49.9
J99
J99
J99
2
1C547
2
1C546
2
1
R114
2 1
R313
2
1C176
2
1
R777
8
9
10
12
11
13
14
15
16
18
17
19
20
21
22
23
24
25
26
27
28
30
31
29
8
9
9
8
7
6
7
6
5
5
3
4
4
3
2
1
2
1
0
0
9
9
8
7
8
6
7
6
5
4
4
5
3
2
3
0
1
2
1
0
0
1
2
4
5
3
0
1
6
7
0
1
2
3
4
5
6
7
8
10
9
11
12
13
14
15
16
17
18
19
20
21
22
23
24
25
26
27
28
29
30
2
3
5
6
4
7
0
1
2
3
4
6
5
1
2
3
0
5
6
4
31
0
1
2
3
4
5
6
7
R1710
R1590
DQS7_A_c||TDQS7_A_c
DQS6_A_t||TDQS6_A_t
DQS8_B_t||TDQS8_B_t
DQS8_B_c||TDQS8_B_c
DQS7_B_t||TDQS7_B_t
DQS0_A_c
DQS0_A_t
DQS0_B_c
DQS0_B_t
DQS1_A_c
DQS1_A_t
DQS1_B_c
DQS1_B_t
DQS2_A_c
DQS2_A_t
DQS2_B_c
DQS2_B_t
DQS3_A_c
DQS3_A_t
DQS3_B_c
DQS3_B_t
DQS4_A_c
DQS4_A_t
DQS4_B_c
DQS4_B_t
DQS5_A_c||TDQS5_A_c||DQS5_A_t||TDQS5_A_t
DQS5_A_t||TDQS5_A_t
DQS5_B_c||TDQS5_B_c
DQS5_B_t||TDQS5_B_t
DQS6_A_c||TDQS6_A_c||DQS6_A_t||TDQS6_A_t
DQS6_B_c||TDQS6_B_c
DQS6_B_t||TDQS6_B_t
DQS7_A_t||TDQS7_A_t
DQS7_B_c||TDQS7_B_c
DQS8_A_c||TDQS8_A_c
DQS8_A_t||TDQS8_A_t
DQS9_A_c||TDQS9_A_c
DQS9_A_t||TDQS9_A_t
DQS9_B_c||TDQS9_B_c
DQS9_B_t||TDQS9_B_t||DBI4_B_n93
94
201
200
283
282
190
189
272
271
179
178
261
260
168
167
250
249
157
156
239
238
55
56
137
138
44
45
126
127
33
34
115
116
22
23
104
105
11
12
288
286
284
281
279
277
275
273
270
268
266
264
262
259
257
255
253
251
248
246
244
242
240
237
235
233
230
228
226
224
222
219
216
214
212
210
208
206
204
202
199
197
195
193
191
188
186
184
182
180
177
175
173
171
169
166
164
162
160
158
155
153
151
143
141
139
136
134
132
130
128
125
123
121
119
117
114
112
110
108
106
103
101
99
97
95
92
90
88
85
83
81
79
77
75
73
71
69
67
65
63
61
59
57
54
52
50
48
46
43
41
39
37
35
32
30
28
26
24
21
19
17
15
13
10
8
6
146
145
1
G3
G2
G1
3
232
231
220
150
149
144
2
207
147
227
74
87
86
5
4
148
287
194
285
192
142
49
140
47
280
187
278
185
135
42
133
40
276
183
274
181
131
38
129
36
269
176
267
174
124
31
122
29
265
172
263
170
120
27
118
25
258
165
256
163
113
20
111
18
254
161
252
159
109
16
107
14
247
154
245
152
102
9
100
7
229
209
84
64
217
218
236
205
234
203
91
60
89
58
243
198
241
196
98
53
96
51
82
72
225
215
80
70
223
213
78
68
221
211
76
66
62
2/3
1/3
PWR_GOOD||FAIL_n
DQ31_A
CB7_A
CB4_A
CB1_A
CB7_B
ALERT_n
CA0_A
CA0_B
CA1_A
CA1_B
CA2_A
CA2_B
CA3_A
CA3_B
CA4_A
CA4_B
CA5_A
CA5_B
CA6_A
CA6_B
CB6_A
CB5_A
CB3_A
CB2_A
CB0_A
CB6_B
CB5_B
CB4_B
CB3_B
CB2_B
CB1_B
CB0_B
CK_c
CK_t
CS0_A_n
CS0_B_n
CS1_A_n
CS1_B_n
DQ30_A
DQ29_A
DQ28_A
DQ27_A
DQ26_A
DQ25_A
DQ24_A
DQ23_A
DQ22_A
DQ21_A
DQ20_A
DQ19_A
DQ18_A
DQ17_A
DQ16_A
DQ15_A
DQ14_A
DQ13_A
DQ12_A
DQ11_A
DQ10_A
DQ9_A
DQ8_A
DQ7_A
DQ6_A
DQ5_A
DQ4_A
DQ3_A
DQ2_A
DQ1_A
DQ0_A
DQ31_B
DQ30_B
DQ29_B
DQ28_B
DQ27_B
DQ26_B
DQ25_B
DQ24_B
DQ23_B
DQ22_B
DQ21_B
DQ20_B
DQ19_B
DQ18_B
DQ17_B
DQ16_B
DQ15_B
DQ14_B
DQ13_B
DQ12_B
DQ11_B
DQ10_B
DQ9_B
DQ8_B
DQ7_B
DQ6_B
DQ5_B
DQ4_B
DQ3_B
DQ2_B
DQ1_B
DQ0_B
HAS
HSCL
HSDA
LBD||RSP_A_n
LBS||RSP_B_n
PAR_A
PAR_B
RESET_n
RFU6
RFU5
RFU4
RFU3
RFU2
RFU1
RFU0
VIN_MGMT
3/3
G3
G2
G1
VSS62
VSS61
VSS60
VSS58
VSS104
VSS102
VSS100
VIN_BULK2
VIN_BULK1
VIN_BULK0
VSS126
VSS125
VSS124
VSS123
VSS122
VSS121
VSS120
VSS119
VSS118
VSS117
VSS116
VSS115
VSS114
VSS113
VSS112
VSS111
VSS110
VSS109
VSS108
VSS107
VSS106
VSS105
VSS103
VSS101
VSS99
VSS98
VSS97
VSS96
VSS95
VSS94
VSS93
VSS92
VSS91
VSS90
VSS89
VSS88
VSS87
VSS86
VSS85
VSS84
VSS83
VSS82
VSS81
VSS80
VSS79
VSS78
VSS77
VSS76
VSS75
VSS74
VSS73
VSS72
VSS71
VSS70
VSS69
VSS68
VSS67
VSS66
VSS65
VSS64
VSS63
VSS59
VSS57
VSS56
VSS55
VSS54
VSS53
VSS52
VSS51
VSS50
VSS49
VSS48
VSS47
VSS46
VSS45
VSS44
VSS43
VSS42
VSS41
VSS40
VSS39
VSS38
VSS37
VSS36
VSS35
VSS34
VSS33
VSS32
VSS31
VSS30
VSS29
VSS28
VSS27
VSS26
VSS25
VSS24
VSS23
VSS22
VSS21
VSS20
VSS19
VSS18
VSS17
VSS16
VSS15
VSS14
VSS13
VSS12
VSS11
VSS10
VSS9
VSS8
VSS7
VSS6
VSS5
VSS4
VSS3
VSS2
VSS1
VSS0
21
21
SHEETDATE
DEPARTMENT
SIZE
PROJECT DOCUMENT NUMBER REV
REVIEWER
DESIGNER
123
7 3 2 1 6 5 4
E
A
B
C
E
D
C
B
A
7 6 5 4
D
INOUT
IN
BI
IN
IN
IN
OUT
OUTOUT
OUTOUT
IN
BI
IN
ININ
ININ
BI
OUT
BI
BI
ININ
BI
OUT
C



Thu Sep 14 16:12:14 2023<NAME_2><NAME_1>MB FABCGT AMDV02109 OF 365P3V3P3V3_AUXP12V_MEM_CPU1
10910410510610710815915910410510610710848484848484810948484848104105106107108
4848484848484848484848481K0.1UF040225V10%X7R1%1/16WEMPTY1K0402LF
10UF10%X6SC080525V10UFC080525V10%X6S100402LFCHIPPD_CHL_CPU1_DIMM_SAAI3C_SPD_DDRGL_CPU1_SDAI3C_SPD_DDRGL_CPU1_SCLI3C_SPD_DDRL_CPU1_SCLI3C_SPD_DDRL_CPU1_SDAM_L_CPU1_SA_PARM_L_CPU1_SB_RSP<0>M_L_CPU1_SA_CS_N<1>M_L_CPU1_SB_CS_N<0>M_L_CPU1_CLK_DP<0>M_L_CPU1_CLK_DN<0>PD_CHL_CPU1_DIMM_SAAM_L_CPU1_SB_CS_N<1>M_L_CPU1_SA_CS_N<0>M_L_CPU1_SB_PARM_L_CPU1_SA_RSP<0>PWRGD_CHGL_CPU1
M_L_CPU1_SA_CA<6:0>M_L_CPU1_SB_CA<6:0>M_L_CPU1_SA_CB<7:0>M_L_CPU1_SB_CB<7:0>M_L_CPU1_SB_DQ<31:0>M_L_CPU1_SA_DQS_DN<9:0>M_L_CPU1_SA_DQS_DP<9:0>M_L_CPU1_SB_DQS_DN<9:0>M_L_CPU1_SB_DQS_DP<9:0>M_L_CPU1_SA_DQ<31:0>
DDR5 - CPU1 CHL
SMLFIOSCONN288_DDR506112002KQSCONN288_DDR506112002KQSMLFIO SCONN288_DDR506112002KQSMLFIO
1/16WCHIP1%84.5K0402LF49.9PWRGD_CHL_CPU1_DIMMM_L_CPU1_RESET_NM_L_CPU1_ALERT_N
J37
J37
J37 2
1C549
2
1C548
2
1
R115
2 1
R314
2
1C180
2
1
R778
0
3
4
6
7
5
30
31
2
1
0
6
5
4
3
6
0
2
1
5
4
3
1
2
0
7
6
4
5
3
2
1
25
26
27
29
28
20
21
22
24
23
15
16
17
19
18
10
11
12
14
13
5
6
8
9
7
0
1
4
3
2
6
7
5
3
4
2
1
1
2
0
3
4
0
5
7
6
0
1
2
3
5
4
6
7
8
9
1
0
2
3
4
6
5
8
9
1
0
2
3
4
5
6
7
9
7
8
8
9
28
30
31
29
23
24
25
27
26
18
19
20
22
21
13
14
17
16
15
8
9
10
11
12
R1711
R1591
DQS7_A_c||TDQS7_A_c
DQS6_A_t||TDQS6_A_t
DQS8_B_t||TDQS8_B_t
DQS8_B_c||TDQS8_B_c
DQS7_B_t||TDQS7_B_t
DQS0_A_c
DQS0_A_t
DQS0_B_c
DQS0_B_t
DQS1_A_c
DQS1_A_t
DQS1_B_c
DQS1_B_t
DQS2_A_c
DQS2_A_t
DQS2_B_c
DQS2_B_t
DQS3_A_c
DQS3_A_t
DQS3_B_c
DQS3_B_t
DQS4_A_c
DQS4_A_t
DQS4_B_c
DQS4_B_t
DQS5_A_c||TDQS5_A_c||DQS5_A_t||TDQS5_A_t
DQS5_A_t||TDQS5_A_t
DQS5_B_c||TDQS5_B_c
DQS5_B_t||TDQS5_B_t
DQS6_A_c||TDQS6_A_c||DQS6_A_t||TDQS6_A_t
DQS6_B_c||TDQS6_B_c
DQS6_B_t||TDQS6_B_t
DQS7_A_t||TDQS7_A_t
DQS7_B_c||TDQS7_B_c
DQS8_A_c||TDQS8_A_c
DQS8_A_t||TDQS8_A_t
DQS9_A_c||TDQS9_A_c
DQS9_A_t||TDQS9_A_t
DQS9_B_c||TDQS9_B_c
DQS9_B_t||TDQS9_B_t||DBI4_B_n93
94
201
200
283
282
190
189
272
271
179
178
261
260
168
167
250
249
157
156
239
238
55
56
137
138
44
45
126
127
33
34
115
116
22
23
104
105
11
12
288
286
284
281
279
277
275
273
270
268
266
264
262
259
257
255
253
251
248
246
244
242
240
237
235
233
230
228
226
224
222
219
216
214
212
210
208
206
204
202
199
197
195
193
191
188
186
184
182
180
177
175
173
171
169
166
164
162
160
158
155
153
151
143
141
139
136
134
132
130
128
125
123
121
119
117
114
112
110
108
106
103
101
99
97
95
92
90
88
85
83
81
79
77
75
73
71
69
67
65
63
61
59
57
54
52
50
48
46
43
41
39
37
35
32
30
28
26
24
21
19
17
15
13
10
8
6
146
145
1
G3
G2
G1
3
232
231
220
150
149
144
2
207
147
227
74
87
86
5
4
148
287
194
285
192
142
49
140
47
280
187
278
185
135
42
133
40
276
183
274
181
131
38
129
36
269
176
267
174
124
31
122
29
265
172
263
170
120
27
118
25
258
165
256
163
113
20
111
18
254
161
252
159
109
16
107
14
247
154
245
152
102
9
100
7
229
209
84
64
217
218
236
205
234
203
91
60
89
58
243
198
241
196
98
53
96
51
82
72
225
215
80
70
223
213
78
68
221
211
76
66
62
2/3
1/3
PWR_GOOD||FAIL_n
DQ31_A
CB7_A
CB4_A
CB1_A
CB7_B
ALERT_n
CA0_A
CA0_B
CA1_A
CA1_B
CA2_A
CA2_B
CA3_A
CA3_B
CA4_A
CA4_B
CA5_A
CA5_B
CA6_A
CA6_B
CB6_A
CB5_A
CB3_A
CB2_A
CB0_A
CB6_B
CB5_B
CB4_B
CB3_B
CB2_B
CB1_B
CB0_B
CK_c
CK_t
CS0_A_n
CS0_B_n
CS1_A_n
CS1_B_n
DQ30_A
DQ29_A
DQ28_A
DQ27_A
DQ26_A
DQ25_A
DQ24_A
DQ23_A
DQ22_A
DQ21_A
DQ20_A
DQ19_A
DQ18_A
DQ17_A
DQ16_A
DQ15_A
DQ14_A
DQ13_A
DQ12_A
DQ11_A
DQ10_A
DQ9_A
DQ8_A
DQ7_A
DQ6_A
DQ5_A
DQ4_A
DQ3_A
DQ2_A
DQ1_A
DQ0_A
DQ31_B
DQ30_B
DQ29_B
DQ28_B
DQ27_B
DQ26_B
DQ25_B
DQ24_B
DQ23_B
DQ22_B
DQ21_B
DQ20_B
DQ19_B
DQ18_B
DQ17_B
DQ16_B
DQ15_B
DQ14_B
DQ13_B
DQ12_B
DQ11_B
DQ10_B
DQ9_B
DQ8_B
DQ7_B
DQ6_B
DQ5_B
DQ4_B
DQ3_B
DQ2_B
DQ1_B
DQ0_B
HAS
HSCL
HSDA
LBD||RSP_A_n
LBS||RSP_B_n
PAR_A
PAR_B
RESET_n
RFU6
RFU5
RFU4
RFU3
RFU2
RFU1
RFU0
VIN_MGMT
3/3
G3
G2
G1
VSS62
VSS61
VSS60
VSS58
VSS104
VSS102
VSS100
VIN_BULK2
VIN_BULK1
VIN_BULK0
VSS126
VSS125
VSS124
VSS123
VSS122
VSS121
VSS120
VSS119
VSS118
VSS117
VSS116
VSS115
VSS114
VSS113
VSS112
VSS111
VSS110
VSS109
VSS108
VSS107
VSS106
VSS105
VSS103
VSS101
VSS99
VSS98
VSS97
VSS96
VSS95
VSS94
VSS93
VSS92
VSS91
VSS90
VSS89
VSS88
VSS87
VSS86
VSS85
VSS84
VSS83
VSS82
VSS81
VSS80
VSS79
VSS78
VSS77
VSS76
VSS75
VSS74
VSS73
VSS72
VSS71
VSS70
VSS69
VSS68
VSS67
VSS66
VSS65
VSS64
VSS63
VSS59
VSS57
VSS56
VSS55
VSS54
VSS53
VSS52
VSS51
VSS50
VSS49
VSS48
VSS47
VSS46
VSS45
VSS44
VSS43
VSS42
VSS41
VSS40
VSS39
VSS38
VSS37
VSS36
VSS35
VSS34
VSS33
VSS32
VSS31
VSS30
VSS29
VSS28
VSS27
VSS26
VSS25
VSS24
VSS23
VSS22
VSS21
VSS20
VSS19
VSS18
VSS17
VSS16
VSS15
VSS14
VSS13
VSS12
VSS11
VSS10
VSS9
VSS8
VSS7
VSS6
VSS5
VSS4
VSS3
VSS2
VSS1
VSS0
21
21
SHEETDATE
DEPARTMENT
SIZE
PROJECT DOCUMENT NUMBER REV
REVIEWER
DESIGNER
123
7 3 2 1 6 5 4
E
A
B
C
E
D
C
B
A
7 6 5 4
D
IN
BI
OUTIN
OUT
BI
IN
IN
IN
OUT
OUTOUT
OUTOUT
IN
BI
IN
IN
ININ
IN
IN
OUT
BI
BI
INBI
C



Thu Aug 24 10:14:17 2023<NAME_2><NAME_1>MB FABCGT AMDV02110 OF 365Blank
SHEETDATE
DEPARTMENT
SIZE
PROJECT DOCUMENT NUMBER REV
REVIEWER
DESIGNER
123
7 3 2 1 6 5 4
E
A
B
C
E
D
C
B
A
7 6 5 4
D
C



Thu Sep 14 16:12:36 2023<NAME_2><NAME_1>MB FABCGT AMDV02111 OF 365
PCIE REDRIVER BOM1P3V3_AUXP3V3_AUX
P3V3_AUXP3V3_AUX
P3V3_AUXP3V3_AUXP3V3_AUX113113111111111111111111113113111111111111111234111112111111113111111113113111111234112113111111
1%0402LFPCIE REDRIVER BOM168K1%P2E_MB_BMC_TX_BUF_DP<0>P2E_MB_BMC_TX_BUF_DN<0>10%25VPCIE REDRIVER BOM104020402FM_P2E_FGBFM_P2E_SWAFM_P2E_SWBFM_P2E_EQA0FM_P2E_EQA1FM_P2E_EQB1P2E_MB_BMC_TX_C_R1_DP<0>P2E_MB_BMC_RX_R1_DN<0>1%0402LFEMPTY1/16WPCIE REDRIVER BOM1FM_P2E_SWAFM_P2E_SWB0402LFEMPTY1/16W1%PCIE REDRIVER BOM1IO_SLOT1KFM_P2E_EQB1EMPTY1/16WPCIE REDRIVER BOM1EMPTY1/16W1K1%FM_P2E_EQA1FM_P2E_EQA00402LF1%PCIE REDRIVER BOM1PCIE REDRIVER BOM11/16WEMPTY0402LF0402LFIO_SLOT0402LFEMPTY1/16W1%0402LF0402LF68KIO_SLOT68K PCIE REDRIVER BOM11/16WCLK_GEN2_GPU_FPGA_OE_OR_NPCIE REDRIVER BOM1PCIE REDRIVER BOM14.7K1%PCIE REDRIVER BOM10402LF0402LFFM_P2E_MODEPCIE REDRIVER BOM1EMPTY1/16WPU_TESTIO_SLOTPCIE REDRIVER BOM1PCIE REDRIVER BOM10.1UFPI3EQX12902AZLEXPCIE REDRIVER BOM1PCIE REDRIVER BOM1
1%1/16W68K0402LFEMPTY0402LF1K1/16WCHIP1%1KEMPTY0402LF1/16W0402LF1%68KEMPTY1%1KEMPTY1/16W0402LF0402LF1K1%CHIP1/16W1K1%EMPTY1/16W0402LF1%1K1%EMPTY0402LF1/16W1/16W1KEMPTY0402LF1%68K1/16W0402LF1%4.7K1/16WEMPTY1%0402LF4.7KCHIP4.7K1%1/16W1/16WCHIP4.7K0402LF
0402LF1/16WEMPTY1%1K1/16WIO_SLOT
FM_P2E_EQB0P2E_MB_BMC_RX_R1_DP<0>FM_P2E_FGAFM_P2E_FGBP2E_MB_BMC_RX_BUF_C_DN<0>P2E_MB_BMC_RX_BUF_C_DP<0>
BMC - GPU FPGA PCIE - RE-DRIVER (main)IO_SLOTIO_SLOTIO_SLOTIO_SLOTIO_SLOTIO_SLOTIO_SLOTIO_SLOT
C080510UF25VX6S10%X7R040225V10%0.1UF25V0.1UFX7R040210%X7R10%25VX7RSMLF0.1UFICFM_P2E_MODEFM_P2E_EN_N0CHIP 0402LFPCIE REDRIVER BOM1IO_SLOTEMPTYCLK_GEN2_GPU_FPGA_OE_OR_NP2E_MB_BMC_TX_C_R1_DN<0>1%1K1%1%1/16WEMPTYIO_SLOT IO_SLOT0402LFFM_P2E_FGA0402LF1%1/16WEMPTYEMPTYPCIE REDRIVER BOM1PCIE REDRIVER BOM1PCIE REDRIVER BOM1PCIE REDRIVER BOM11KPCIE REDRIVER BOM11/16WEMPTYPCIE REDRIVER BOM11K1%PCIE REDRIVER BOM168K1%1/16W1/16WEMPTYPCIE REDRIVER BOM1PCIE REDRIVER BOM1PCIE REDRIVER BOM1IO_SLOT0402LFPCIE REDRIVER BOM11KEMPTY1/16W68K1%1%1KPCIE REDRIVER BOM10402LFPCIE REDRIVER BOM1PCIE REDRIVER BOM1PCIE REDRIVER BOM1FM_P2E_EQB0IO_SLOT0402LFIO_SLOTEMPTY1/16WPCIE REDRIVER BOM11KPCIE REDRIVER BOM1PCIE REDRIVER BOM1EMPTY
R3286
R3285
R3280
R3279
R3269
R3267
R3271
R3268
25
16
10
1
512
29
30
TH
28
22
19
13
7
6
4
14
27
15
20
26
21
11
9
8
17
18
24
23
2
3
U237
GND_TH
MODE
SWA
GND7
FGA
EQA1
VDD4
AOP
AON
GND6
EQA0
EQB0
GND5
BIN
BIP
VDD3
EQB1
FGB
GND4
SWB
EN#
VDD2
BOP
BON
GND3
GND2
TEST#
GND1
AIN
AIP
VDD1
2
1
2
1
2
1
2
1
2
1
2
1
2
1
2
1
21
2
1
2
1C1865
2
1C1864
2
1C1863
2
1
2
1
2
1
2
1
2
1
2
1
2
1
2
1
2
1
2
1
2
1
2
1
2
1
2
1
2
1
2
1
2
1
2
1
2
1
2
1
2
1
2
1
SHEETDATE
DEPARTMENT
SIZE
PROJECT DOCUMENT NUMBER REV
REVIEWER
DESIGNER
123
7 3 2 1 6 5 4
E
A
B
C
E
D
C
B
A
7 6 5 4
D
OUT
OUT
OUTOUT
OUTOUT
IN
OUTOUT
IN
IN
IN
IN
IN
ININ
IN
IN
IN
IN
ININ
OUTOUT
OUTOUT
OUTOUT
R3266
R3293
R3292
R3291
R3265
R3289
R3290R3288
R4537
C1866C1867
R3287
R3283
R3284R3282
R3275
R3276
R3281
R3277
R3278R3274
R3273
R3270
R3272
C



TBC
TBC
Thu Sep 14 16:12:44 2023<NAME_2><NAME_1>MB FABCGT AMDV02112 OF 365P3V3_AUXP3V3_AUXP3V3_AUXP3V3_AUX P3V3_AUXP3V3_AUX
P3V3_AUX
112112112112112112
112112113113113113112112112112112112111234112112113113113113112112PCIE REDRIVER BOM2FM_P2E_BUF2_VOD_SELPCIE REDRIVER BOM2PCIE REDRIVER BOM2FM_P2E_BUF2_SD_THPCIE REDRIVER BOM2PCIE REDRIVER BOM2FM_P2E_BUF2_RXDETPCIE REDRIVER BOM21K1%EMPTYPCIE REDRIVER BOM21KEMPTY1/16WPCIE REDRIVER BOM2CHIP0402LFPCIE REDRIVER BOM2PCIE REDRIVER BOM2FM_P2E_BUF2_EQB0PCIE REDRIVER BOM21/16W1K1%1/16WEMPTY0402LFFM_P2E_BUF2_VODB_DBFM_P2E_BUF2_VODA_DBPCIE REDRIVER BOM21/16WCHIP1%1K0402LFPCIE REDRIVER BOM21/16WEMPTY0402LF1%FM_P2E_BUF2_RXDETPCIE REDRIVER BOM2PCIE REDRIVER BOM20.1UF25VX7R1%0402LFCHIP1K1/16WICDS125BR111RTWRSMLFPCIE REDRIVER BOM2PCIE REDRIVER BOM2
0402LF1/16WCHIP1K1%1K1KEMPTY1K1%EMPTY1K1%1%0402LF1K1K0402LFEMPTY1/16W1%1K1%1K1/16WCHIP0402LF 0402LF1/16W1%EMPTY0402LF1K1/16W1%EMPTY0402LF1%0402LF1/16WEMPTY1K1/16W1%EMPTY1K0402LF1/16W1K1%0402LF0402LF1/16W1K1%CHIPBMC-GPU FPGA PCIE - RE-DRIVER (2nd)
FM_P2E_BUF2_VOD_SELNC_RES
CHIP1%
X7R040210%25V0.1UF10%BUF2_VDD16VX6SC080510UFPCIE REDRIVER BOM225VX6SC04021UF10% 10%PCIE REDRIVER BOM20402P2E_MB_BMC_RX_R2_DN<0>P2E_MB_BMC_RX_R2_DP<0>PD_P2E_BUF2_ENSMBP2E_MB_BMC_TX_C_R2_DN<0>P2E_MB_BMC_TX_C_R2_DP<0>FM_P2E_BUF2_VODB_DBFM_P2E_BUF2_VODA_DBFM_P2E_BUF2_EQB0FM_P2E_BUF2_EQB1FM_P2E_BUF2_EQA1FM_P2E_BUF2_EQA005%0402LFCLK_GEN2_GPU_FPGA_OE_OR_NFM_P2E_BUF2_SD_THPCIE REDRIVER BOM21/16WPCIE REDRIVER BOM2FM_P2E_BUF2_EQB10402LFPCIE REDRIVER BOM21%1/16W0402LF1/16WFM_P2E_EN2_NPCIE REDRIVER BOM21/16WCHIPP2E_MB_BMC_TX_BUF2_DP<0>P2E_MB_BMC_TX_BUF2_DN<0>P2E_MB_BMC_RX_BUF2_C_DP<0>P2E_MB_BMC_RX_BUF2_C_DN<0>PCIE REDRIVER BOM20402LFEMPTYPCIE REDRIVER BOM2FM_P2E_BUF2_EQA0FM_P2E_BUF2_EQA11/16W
C6010C6009
R6163
R6162
R6160
C6012C6011
17
15
16
22
21
25
4
14
5
18
13
6
19
20
8
7
12
11
23
24
2
1
9
10
3
U6000
TH_GND
INA+
INA-
VDD_22
VDD_21
OUTB+
OUTB-
RXDET||DONE#
VOD_SEL||READEN#
VDD_SEL
VIN
SD_TH
RES
INB-
INB+
EQA0||AD0
EQA1||AD1
OUTA-
OUTA+
PWDN
SCL||VODB_DB
SDA||VODA_DB
ENSMB
EQB1||AD2
EQB0||AD3
2
1
2
1
2
1
2
1
2
1
2
1
2
1
2
1
2
1
2
1
2
1
2
1
2
1
2
1
2
1
2
1
2
1
2
1
21
2
1
2
1
2
1
2
1
2
1
SHEETDATE
DEPARTMENT
SIZE
PROJECT DOCUMENT NUMBER REV
REVIEWER
DESIGNER
123
7 3 2 1 6 5 4
E
A
B
C
E
D
C
B
A
7 6 5 4
D
ININ
OUTOUTOUT
OUT
OUT
OUT
OUT
OUT
OUT
OUTOUT
OUTOUT
IN
IN
IN
IN
ININ
ININ
ININ
ININ
R6179R6177
R6180R6178R6176
R6175
R6170R6168
R6167 R6169
R6172
R6171
R6174
R6173R6165
R6166R6164
C



TO GPU FPGAFROM 1ST REDRIVERFROM 2ND REDRIVERFROM 2ND REDRIVERFROM 1ST REDRIVERTO 1ST REDRIVERTO 2ND REDRIVERTO 1ST REDRIVERFROM FPGATO 2ND REDRIVERTO BMCFROM BMC
Thu Sep 14 16:12:44 2023<NAME_2><NAME_1>MB FABCGT AMDV02113 OF 365
112112150122122111112112150111111111111111150150122112122112112112111111P2E_MB_BMC_TX_BUF2_DP<0>P2E_MB_BMC_TX_BUF2_DN<0>PCIE REDRIVER BOM2PCIE REDRIVER BOM2PCIE REDRIVER BOM2P2E_MB_BMC_RX_BUF_DP<0>PCIE REDRIVER BOM1P2E_MB_BMC_TX_BUF_C_DP<0>P2E_MB_BMC_TX_BUF_C_DN<0>0.1UFPCIE REDRIVER BOM1PCIE REDRIVER BOM2PCIE REDRIVER BOM1P2E_MB_BMC_TX_BUF_DP<0>P2E_MB_BMC_RX_BUF2_C_DP<0>P2E_MB_BMC_RX_BUF2_C_DN<0>P2E_MB_BMC_RX_BUF_DN<0>P2E_MB_BMC_TX_BUF_DN<0>C1870/C6005 C1871/C6006 CO-LAYOUT0402PCIE REDRIVER BOM1X7RP2E_MB_BMC_RX_R1_DP<0>P2E_MB_BMC_RX_R1_DN<0>CHIP0201LFPCIE REDRIVER BOM2PCIE REDRIVER BOM10CHIP1/20W5%0PCIE REDRIVER BOM1CHIP0PCIE REDRIVER BOM20P2E_MB_BMC_TX_C_R1_DP<0>P2E_MB_BMC_TX_C_R1_DN<0>0201LF0201LF00
BMC-GPU FPGA PCIE RE-DRIVER SELECT
R6152/R6154 R6153/R6155 CO-LAYOUT1/20WCHIPP2E_MB_BMC_TX_C_DP<0>P2E_MB_BMC_TX_C_DN<0>CHIP5%0201LFP2E_MB_BMC_RX_DP<0>P2E_MB_BMC_RX_R2_DN<0>0P2E_MB_BMC_RX_DN<0>P2E_MB_BMC_TX_C_R2_DN<0>PCIE REDRIVER BOM1P2E_MB_BMC_TX_C_R2_DP<0>0201LFCHIP0201LFR6156/R6158 R6157/R6159 CO-LAYOUTCHIPPCIE REDRIVER BOM1P2E_MB_BMC_RX_R2_DP<0>00201LFPCIE REDRIVER BOM2CHIP0201LFPCIE REDRIVER BOM20.1UF 25V25V10%0.1UFC1868/C6007 C1869/C6008 CO-LAYOUTP2E_MB_BMC_RX_BUF_C_DN<0>P2E_MB_BMC_RX_BUF_C_DP<0>0402
C6005
C6006
C1871
C1870
C1869
C1868
C6008
C6007 21 21
21 21
21R6158 21R6159
21R6157
21R6156
21 21
21 21
21 21
21 21
CAD NOTE: CAD NOTE:
CAD NOTE:
CAD NOTE:
R6152R6153
R6155R6154
SHEETDATE
DEPARTMENT
SIZE
PROJECT DOCUMENT NUMBER REV
REVIEWER
DESIGNER
123
7 3 2 1 6 5 4
E
A
B
C
E
D
C
B
A
7 6 5 4
D
IN OUT OUT
OUT
ININ
ININ OUT
OUT
OUT
ININ
ININ OUTOUT
OUTOUT
OUTOUTININ
IN
C



Thu Aug 24 10:14:19 2023<NAME_2><NAME_1>MB FABCGT AMDV02114 OF 365Blank
SHEETDATE
DEPARTMENT
SIZE
PROJECT DOCUMENT NUMBER REV
REVIEWER
DESIGNER
123
7 3 2 1 6 5 4
E
A
B
C
E
D
C
B
A
7 6 5 4
D
C



CPU0_P3_TX/RX<0-15> LANE REVERSALCPU0_P2_TX/RX<0-15> LANE REVERSAL
Thu Sep 14 16:12:58 2023GT AMD<NAME_2>V02<NAME_1>MB FABC115 OF 365P5E_CPU0_P3_RX_BUF_DP<13>127126297297309309308309309298298308308297124309308298298309309309298298308297297124130309309298298308297297308298298308309309298308308297297309309127298298308308298124297297297308297297128308298308297297308298309309FM_SWB_BIC_READY_NGPU_WP_HW_CTRL_ISO_NP5E_CPU0_P2_RX_BUF_DP<10>P5E_CPU0_P2_RX_BUF_DN<10>P5E_CPU0_P3_TX_BUF_C_DN<11>P5E_CPU0_P3_TX_BUF_C_DP<11>P5E_CPU0_P3_RX_BUF_DN<10>P5E_CPU0_P3_TX_BUF_C_DP<8>P5E_CPU0_P3_TX_BUF_C_DN<8>P5E_CPU0_P2_TX_BUF_C_DP<8>P5E_CPU0_P2_TX_BUF_C_DN<8>P5E_CPU0_P3_RX_BUF_DP<8>P5E_CPU0_P3_RX_BUF_DN<8>P5E_CPU0_P2_RX_BUF_DN<8>GPU_3V3IO_RSVD4P5E_CPU0_P3_TX_BUF_C_DP<9>P5E_CPU0_P3_RX_BUF_DP<9>P5E_CPU0_P2_TX_BUF_C_DN<9>P5E_CPU0_P2_TX_BUF_C_DP<9>P5E_CPU0_P3_TX_BUF_C_DN<9>P5E_CPU0_P3_TX_BUF_C_DP<10>P5E_CPU0_P3_TX_BUF_C_DN<10>P5E_CPU0_P2_TX_BUF_C_DP<10>P5E_CPU0_P2_TX_BUF_C_DN<10>P5E_CPU0_P3_RX_BUF_DP<10>P5E_CPU0_P2_RX_BUF_DP<12>P5E_CPU0_P2_RX_BUF_DN<12>GPU_3V3IO_RSVD3RST_SWB_BIC_BUF_NP5E_CPU0_P3_TX_BUF_C_DP<13>P5E_CPU0_P3_TX_BUF_C_DN<13>P5E_CPU0_P2_TX_BUF_C_DP<13>P5E_CPU0_P2_TX_BUF_C_DN<13>P5E_CPU0_P2_RX_BUF_DP<13>P5E_CPU0_P2_RX_BUF_DN<13>P5E_CPU0_P3_RX_BUF_DP<11>P5E_CPU0_P2_TX_BUF_C_DP<11>P5E_CPU0_P2_TX_BUF_C_DN<11>P5E_CPU0_P3_RX_BUF_DN<13>P5E_CPU0_P3_TX_BUF_C_DP<14>P5E_CPU0_P3_TX_BUF_C_DN<14>P5E_CPU0_P2_TX_BUF_C_DN<14>P5E_CPU0_P3_RX_BUF_DP<14>P5E_CPU0_P3_RX_BUF_DN<14>P5E_CPU0_P2_RX_BUF_DP<14>P5E_CPU0_P2_RX_BUF_DN<14>P5E_CPU0_P3_TX_BUF_C_DN<15>P5E_CPU0_P3_TX_BUF_C_DP<15>RST_BMC_FROM_SWB_NP5E_CPU0_P2_TX_BUF_C_DP<15>P5E_CPU0_P2_TX_BUF_C_DN<15>P5E_CPU0_P3_RX_BUF_DP<15>P5E_CPU0_P3_RX_BUF_DN<15>P5E_CPU0_P2_TX_BUF_C_DP<14>GPU_3V3IO_RSVD1P5E_CPU0_P2_RX_BUF_DP<9>P5E_CPU0_P2_RX_BUF_DN<9>P5E_CPU0_P2_RX_BUF_DP<11>P5E_CPU0_P3_RX_BUF_DN<11>P5E_CPU0_P2_RX_BUF_DP<15>P5E_CPU0_P2_RX_BUF_DN<11>IOTHLFTHLFIO
PCIE - CPU0_EXAMAX_P2/P3_X16FM_SWB_PWR_EN_R_BUFP5E_CPU0_P3_RX_BUF_DN<9>P5E_CPU0_P2_TX_BUF_C_DP<12>P5E_CPU0_P3_RX_BUF_DP<12>P5E_CPU0_P2_RX_BUF_DP<8>P5E_CPU0_P2_RX_BUF_DN<15>P5E_CPU0_P3_RX_BUF_DN<12>P5E_CPU0_P2_TX_BUF_C_DN<12>P5E_CPU0_P3_TX_BUF_C_DN<12>P5E_CPU0_P3_TX_BUF_C_DP<12>
N8
N7
N6
N5
M8
M7
M6
M5
L8
L7
L6
L5
K8
K7
K6
K5
J8
J7
J6
J5
I8
I7
I6
I5
H8
H7
H6
H5
G8
G7
G6
G5
F8
F7
F6
F5
E8
E7
E6
E5
D8
D7
D6
D5
C8
C7
C6
C5
B8
B7
B6
B5
A8
A7
A6
A5
N4
N3
N2
N1
M4
M3
M2
M1
L4
L3
L2
L1
K4
K3
K2
K1
J4
J3
J2
J1
I4
I3
I2
I1
H4
H3
H2
H1
G4
G3
G2
G1
F4
F3
F2
F1
E4
E3
E2
E1
D4
D3
D2
D1
C4
C3
C2
C1
B4
B3
B2
B1
A4
A3
A2
A1
J105 J105
1/2
NM
5
LKJC D E F G H IA B
6
7
8
N8
M8
N7
M7
N6
M6
N5
M5
L5
L6
L7
L8
K5
K6
K7
K8
J5
J6
J7
J8
I5
I6
I7
I8
H5
H6
H7
H8
G5
G6
G7
G8
F5
F6
F7
F8
E5
E6
E7
E8
D5
D6
D7
D8
C5
C6
C7
C8
B5
B6
B7
B8
A5
A6
A7
A8
2/2
NM
1
LKJC D E F G H IA B
2
3
4
N4
M4
N3
M3
N2
M2
N1
M1
L1
L2
L3
L4
K1
K2
K3
K4
J1
J2
J3
J4
I1
I2
I3
I4
H1
H2
H3
H4
G1
G2
G3
G4
F1
F2
F3
F4
E1
E2
E3
E4
D1
D2
D3
D4
C1
C2
C3
C4
B1
B2
B3
B4
A1
A2
A3
A4
SHEETDATE
DEPARTMENT
SIZE
PROJECT DOCUMENT NUMBER REV
REVIEWER
DESIGNER
123
7 3 2 1 6 5 4
E
A
B
C
E
D
C
B
A
7 6 5 4
D
OUT
OUT
OUTOUT
OUTOUT
OUT
IN
ININ
IN
IN
OUT
OUTOUT
OUT
IN
IN
IN
OUT
ININ
OUTOUT
OUTOUT
ININ
IN
IN
IN
IN
OUT
OUTOUT
OUTOUT
ININ
OUT
ININ
OUT
OUTOUT
OUT
ININ
ININ
OUT
OUT
OUT
OUT
OUTOUT
OUT
ININ
ININ
IN
OUT
OUTOUT
OUT
ININ
ININ
IN
IN
C



CPU0_P3_TX/RX<0-15> LANE REVERSALCPU0_P2_TX/RX<0-15> LANE REVERSAL
Thu Sep 14 16:12:57 2023116 OF 365MB FABCV02GT AMD<NAME_1><NAME_2>
P5E_CPU0_P2_TX_BUF_C_DN<5>UART_BMC_BIC_RX309309125150297297308309297297308308298298298308123309309308127298309309297297297309309298298297309249298309309309130298298298308308297297249308297297308308308297297309309308308297298298298309297308298298298308308P5E_CPU0_P3_TX_BUF_C_DN<7>P5E_CPU0_P3_TX_BUF_C_DP<7>PRSNT_CABLE_GPU_A1_NUART_BMC_BIC_TXP5E_CPU0_P2_RX_BUF_DN<6>P5E_CPU0_P2_RX_BUF_DP<3>P5E_CPU0_P3_RX_BUF_DP<3>P5E_CPU0_P3_TX_BUF_C_DP<3>P5E_CPU0_P2_RX_BUF_DN<2>P5E_CPU0_P2_RX_BUF_DP<2>P5E_CPU0_P3_RX_BUF_DN<2>P5E_CPU0_P3_RX_BUF_DP<2>P5E_CPU0_P2_TX_BUF_C_DN<2>P5E_CPU0_P2_TX_BUF_C_DP<0>P5E_CPU0_P2_TX_BUF_C_DN<0>P5E_CPU0_P3_RX_BUF_DP<0>PRSNT_CABLE_SWB_B1_NP5E_CPU0_P3_TX_BUF_C_DP<0>P5E_CPU0_P3_TX_BUF_C_DN<0>P5E_CPU0_P3_RX_BUF_DN<0>FM_SWB_PWRGDP5E_CPU0_P2_TX_BUF_C_DP<2>P5E_CPU0_P3_TX_BUF_C_DN<2>P5E_CPU0_P3_TX_BUF_C_DP<2>P5E_CPU0_P2_RX_BUF_DN<1>P5E_CPU0_P2_RX_BUF_DP<0>P5E_CPU0_P2_RX_BUF_DN<0>P5E_CPU0_P3_TX_BUF_C_DP<1>P5E_CPU0_P3_TX_BUF_C_DN<1>P5E_CPU0_P2_TX_BUF_C_DP<1>P5E_CPU0_P2_TX_BUF_C_DN<1>P5E_CPU0_P2_RX_BUF_DP<1>P5E_CPU0_P3_TX_BUF_C_DN<3>I3C_BMC_SWB_BUF_SCLP5E_CPU0_P2_TX_BUF_C_DP<4>P5E_CPU0_P3_TX_BUF_C_DN<4>P5E_CPU0_P3_TX_BUF_C_DP<4>P5E_CPU0_P3_TX_BUF_C_DP<5>P5E_CPU0_P2_TX_BUF_C_DP<6>P5E_CPU0_P2_TX_BUF_C_DP<7>P5E_CPU0_P2_TX_BUF_C_DN<7>P5E_CPU0_P3_RX_BUF_DP<7>P5E_CPU0_P3_RX_BUF_DN<7>P5E_CPU0_P2_RX_BUF_DP<7>P5E_CPU0_P2_RX_BUF_DN<7>NC_J106_A5I3C_BMC_SWB_BUF_SDAP5E_CPU0_P3_RX_BUF_DN<1>IOTHLFIOTHLF
PCIE - CPU0_EXAMAX_P2/P3_X16P5E_CPU0_P2_RX_BUF_DP<4>P5E_CPU0_P2_RX_BUF_DN<4>P5E_CPU0_P3_RX_BUF_DP<1>P5E_CPU0_P3_RX_BUF_DP<5>P5E_CPU0_P3_RX_BUF_DN<5>P5E_CPU0_P2_RX_BUF_DP<5>P5E_CPU0_P2_RX_BUF_DN<5>P5E_CPU0_P3_TX_BUF_C_DP<6>P5E_CPU0_P3_TX_BUF_C_DN<6>P5E_CPU0_P3_RX_BUF_DP<6>P5E_CPU0_P3_RX_BUF_DN<6>P5E_CPU0_P2_RX_BUF_DP<6>P5E_CPU0_P2_TX_BUF_C_DN<6>P5E_CPU0_P2_TX_BUF_C_DP<5>P5E_CPU0_P3_TX_BUF_C_DN<5>P5E_CPU0_P2_RX_BUF_DN<3>P5E_CPU0_P3_RX_BUF_DN<3>P5E_CPU0_P2_TX_BUF_C_DN<3>P5E_CPU0_P2_TX_BUF_C_DP<3>P5E_CPU0_P2_TX_BUF_C_DN<4>P5E_CPU0_P3_RX_BUF_DP<4>P5E_CPU0_P3_RX_BUF_DN<4>
N4
N3
N2
N1
M4
M3
M2
M1
L4
L3
L2
L1
K4
K3
K2
K1
J4
J3
J2
J1
I4
I3
I2
I1
H4
H3
H2
H1
G4
G3
G2
G1
F4
F3
F2
F1
E4
E3
E2
E1
D4
D3
D2
D1
C4
C3
C2
C1
B4
B3
B2
B1
A4
A3
A2
A1
N8
N7
N6
N5
M8
M7
M6
M5
L8
L7
L6
L5
K8
K7
K6
K5
J8
J7
J6
J5
I8
I7
I6
I5
H8
H7
H6
H5
G8
G7
G6
G5
F8
F7
F6
F5
E8
E7
E6
E5
D8
D7
D6
D5
C8
C7
C6
C5
B8
B7
B6
B5
A8
A7
A6
A5
J106
J106
2/2
NM
1
LKJC D E F G H IA B
2
3
4
N4
M4
N3
M3
N2
M2
N1
M1
L1
L2
L3
L4
K1
K2
K3
K4
J1
J2
J3
J4
I1
I2
I3
I4
H1
H2
H3
H4
G1
G2
G3
G4
F1
F2
F3
F4
E1
E2
E3
E4
D1
D2
D3
D4
C1
C2
C3
C4
B1
B2
B3
B4
A1
A2
A3
A4
1/2
NM
5
LKJC D E F G H IA B
6
7
8
N8
M8
N7
M7
N6
M6
N5
M5
L5
L6
L7
L8
K5
K6
K7
K8
J5
J6
J7
J8
I5
I6
I7
I8
H5
H6
H7
H8
G5
G6
G7
G8
F5
F6
F7
F8
E5
E6
E7
E8
D5
D6
D7
D8
C5
C6
C7
C8
B5
B6
B7
B8
A5
A6
A7
A8
SHEETDATE
DEPARTMENT
SIZE
PROJECT DOCUMENT NUMBER REV
REVIEWER
DESIGNER
123
7 3 2 1 6 5 4
E
A
B
C
E
D
C
B
A
7 6 5 4
D
IN
OUT OUT
OUTOUT
OUTOUT
OUT
ININ
BI
ININ
OUT
OUTOUT
OUTOUT
OUT
IN
ININ
IN
OUTOUT
OUTOUT
IN
OUT
IN
ININ
IN
OUTOUT
OUTOUT
IN
IN
IN
IN
IN
OUTOUT
OUT
ININ
OUT
ININ
IN
IN
OUT
OUTOUT
OUTOUT
ININ
ININ
IN
OUTOUT
OUTOUT
ININ
OUT
IN
IN
C



CPU0_P0_TX/RX<0-15> LANE REVERSALCPU0_P1_TX/RX<0-15> LANE REVERSAL
Thu Sep 14 16:12:58 2023MB FABCV02<NAME_2><NAME_1>GT AMD117 OF 365
P5E_CPU0_P0_TX_BUF_C_DN<13>123287287276276286275275276286286275287287287276287287276276287286287276276287287287287276276286286275275287276276286286275287276276286275275275275286286275275275275286286125124286287275286276276286275PRSNT_CABLE_SWB_B2_NNC_J107_A1P5E_CPU0_P1_TX_BUF_C_DP<9>P5E_CPU0_P1_TX_BUF_C_DN<9>P5E_CPU0_P0_TX_BUF_C_DP<9>P5E_CPU0_P0_TX_BUF_C_DN<9>P5E_CPU0_P1_RX_BUF_DP<9>P5E_CPU0_P0_RX_BUF_DP<8>P5E_CPU0_P0_RX_BUF_DN<8>P5E_CPU0_P0_TX_BUF_C_DN<10>P5E_CPU0_P1_RX_BUF_DP<10>P5E_CPU0_P1_RX_BUF_DN<10>P5E_CPU0_P0_RX_BUF_DN<14>P5E_CPU0_P1_TX_BUF_C_DN<15>NC_J107_N4P5E_CPU0_P1_TX_BUF_C_DP<11>P5E_CPU0_P1_TX_BUF_C_DN<11>P5E_CPU0_P0_TX_BUF_C_DP<11>P5E_CPU0_P1_TX_BUF_C_DP<8>P5E_CPU0_P1_TX_BUF_C_DN<8>P5E_CPU0_P0_TX_BUF_C_DP<8>P5E_CPU0_P0_TX_BUF_C_DN<8>P5E_CPU0_P1_TX_BUF_C_DP<10>P5E_CPU0_P1_RX_BUF_DN<9>P5E_CPU0_P1_TX_BUF_C_DN<10>P5E_CPU0_P0_TX_BUF_C_DP<10>P5E_CPU0_P0_TX_BUF_C_DN<11>NC_J107_A5P5E_CPU0_P1_TX_BUF_C_DP<12>P5E_CPU0_P1_TX_BUF_C_DN<12>P5E_CPU0_P1_TX_BUF_C_DP<13>P5E_CPU0_P1_TX_BUF_C_DN<13>P5E_CPU0_P0_TX_BUF_C_DP<13>P5E_CPU0_P1_RX_BUF_DP<13>P5E_CPU0_P1_RX_BUF_DN<13>P5E_CPU0_P0_RX_BUF_DN<13>P5E_CPU0_P0_RX_BUF_DP<13>P5E_CPU0_P1_TX_BUF_C_DN<14>P5E_CPU0_P0_TX_BUF_C_DP<14>P5E_CPU0_P0_TX_BUF_C_DN<14>P5E_CPU0_P1_RX_BUF_DP<14>P5E_CPU0_P1_RX_BUF_DN<14>P5E_CPU0_P0_RX_BUF_DP<14>P5E_CPU0_P1_TX_BUF_C_DP<15>P5E_CPU0_P0_TX_BUF_C_DP<15>P5E_CPU0_P0_TX_BUF_C_DN<15>P5E_CPU0_P1_RX_BUF_DP<15>
PCIE - CPU0_EXAMAX_P0/P1_X16
IOTHLFTHLFIONC_J107_A3NC_J107_N6P5E_CPU0_P0_RX_BUF_DP<11>P5E_CPU0_P0_RX_BUF_DN<11>P5E_CPU0_P0_RX_BUF_DP<15>P5E_CPU0_P0_RX_BUF_DN<15>P5E_CPU0_P1_RX_BUF_DN<11>P5E_CPU0_P1_RX_BUF_DP<11>P5E_CPU0_P0_RX_BUF_DN<10>P5E_CPU0_P0_RX_BUF_DP<10>P5E_CPU0_P0_RX_BUF_DN<9>P5E_CPU0_P0_RX_BUF_DP<9>P5E_CPU0_P1_RX_BUF_DN<8>P5E_CPU0_P1_RX_BUF_DP<8>SWB_HSC_PWRGDSWB_HSC_EN_BUFP5E_CPU0_P1_RX_BUF_DN<15>P5E_CPU0_P1_TX_BUF_C_DP<14>P5E_CPU0_P0_RX_BUF_DN<12>P5E_CPU0_P1_RX_BUF_DP<12>P5E_CPU0_P0_TX_BUF_C_DN<12>P5E_CPU0_P0_TX_BUF_C_DP<12>P5E_CPU0_P1_RX_BUF_DN<12>P5E_CPU0_P0_RX_BUF_DP<12>
N8
N7
N6
N5
M8
M7
M6
M5
L8
L7
L6
L5
K8
K7
K6
K5
J8
J7
J6
J5
I8
I7
I6
I5
H8
H7
H6
H5
G8
G7
G6
G5
F8
F7
F6
F5
E8
E7
E6
E5
D8
D7
D6
D5
C8
C7
C6
C5
B8
B7
B6
B5
A8
A7
A6
A5
N4
N3
N2
N1
M4
M3
M2
M1
L4
L3
L2
L1
K4
K3
K2
K1
J4
J3
J2
J1
I4
I3
I2
I1
H4
H3
H2
H1
G4
G3
G2
G1
F4
F3
F2
F1
E4
E3
E2
E1
D4
D3
D2
D1
C4
C3
C2
C1
B4
B3
B2
B1
A4
A3
A2
A1
J107 J107
1/2
NM
5
LKJC D E F G H IA B
6
7
8
N8
M8
N7
M7
N6
M6
N5
M5
L5
L6
L7
L8
K5
K6
K7
K8
J5
J6
J7
J8
I5
I6
I7
I8
H5
H6
H7
H8
G5
G6
G7
G8
F5
F6
F7
F8
E5
E6
E7
E8
D5
D6
D7
D8
C5
C6
C7
C8
B5
B6
B7
B8
A5
A6
A7
A8
2/2
NM
1
LKJC D E F G H IA B
2
3
4
N4
M4
N3
M3
N2
M2
N1
M1
L1
L2
L3
L4
K1
K2
K3
K4
J1
J2
J3
J4
I1
I2
I3
I4
H1
H2
H3
H4
G1
G2
G3
G4
F1
F2
F3
F4
E1
E2
E3
E4
D1
D2
D3
D4
C1
C2
C3
C4
B1
B2
B3
B4
A1
A2
A3
A4
SHEETDATE
DEPARTMENT
SIZE
PROJECT DOCUMENT NUMBER REV
REVIEWER
DESIGNER
123
7 3 2 1 6 5 4
E
A
B
C
E
D
C
B
A
7 6 5 4
D
IN
OUT
OUT
OUT
IN
OUTOUT
OUTOUT
IN
ININ
OUTOUT
OUT
OUTOUT
ININ
ININ
OUTOUT
OUTOUT
IN
ININ
ININ
OUTOUT
OUTOUTOUT
ININ
ININ
OUTOUT
OUTOUT
ININ
IN
ININ
IN
OUT
OUTOUT
OUTOUT
ININ
IN
ININ
OUTOUT
OUTOUT
IN
IN
IN
IN
C



CPU0_P1_TX/RX<0-15> LANE REVERSALCPU0_P0_TX/RX<0-15> LANE REVERSAL
Thu Sep 14 16:12:58 2023GT AMD<NAME_1><NAME_2>V02MB FABC118 OF 365
P5E_CPU0_P1_TX_BUF_C_DP<5>123287276276275286125275286276287287286 286286286275275275286275276286275276287287275275286276287276276287287276287287286286276276287287275286286276275275125275287276286286276287275125126287275275286276276287PRSNT_CABLE_GPU_A3_NP5E_CPU0_P1_TX_BUF_C_DP<0>P5E_CPU0_P0_TX_BUF_C_DP<0>P5E_CPU0_P0_TX_BUF_C_DN<1>P5E_CPU0_P0_RX_BUF_DP<5>P5E_CPU0_P1_RX_BUF_DN<5>GPU_3V3IO_RSVD5_FFUP5E_CPU0_P0_RX_BUF_DP<4>P5E_CPU0_P1_RX_BUF_DP<4>P5E_CPU0_P0_TX_BUF_C_DN<4>P5E_CPU0_P1_TX_BUF_C_DN<4>P5E_CPU0_P1_TX_BUF_C_DP<4>P5E_CPU0_P1_RX_BUF_DP<5> P5E_CPU0_P1_RX_BUF_DN<1>P5E_CPU0_P1_RX_BUF_DP<1>P5E_CPU0_P1_RX_BUF_DN<7>P5E_CPU0_P0_RX_BUF_DP<3>NC_J108_N6P5E_CPU0_P0_RX_BUF_DN<1>P5E_CPU0_P0_RX_BUF_DN<3>THLFIO IOTHLF
PCIE - CPU0_EXAMAX_P0/P1_X16
P5E_CPU0_P1_RX_BUF_DN<3>P5E_CPU0_P0_RX_BUF_DP<1>P5E_CPU0_P0_TX_BUF_C_DP<4>P5E_CPU0_P1_RX_BUF_DN<4>P5E_CPU0_P0_RX_BUF_DN<4>P5E_CPU0_P0_TX_BUF_C_DP<1>P5E_CPU0_P1_TX_BUF_C_DN<1>P5E_CPU0_P1_TX_BUF_C_DP<1>NC_J108_N2P5E_CPU0_P0_RX_BUF_DN<6>P5E_CPU0_P0_RX_BUF_DP<6>P5E_CPU0_P1_RX_BUF_DN<6>P5E_CPU0_P0_TX_BUF_C_DP<6>P5E_CPU0_P1_TX_BUF_C_DP<6>P5E_CPU0_P0_TX_BUF_C_DN<5>P5E_CPU0_P0_TX_BUF_C_DP<5>P5E_CPU0_P1_TX_BUF_C_DN<5>NC_J108_N4P5E_CPU0_P0_TX_BUF_C_DP<3>P5E_CPU0_P1_TX_BUF_C_DN<3>P5E_CPU0_P1_TX_BUF_C_DP<3>P5E_CPU0_P1_RX_BUF_DN<2>P5E_CPU0_P1_RX_BUF_DP<2>P5E_CPU0_P0_TX_BUF_C_DN<2>P5E_CPU0_P0_TX_BUF_C_DP<2>P5E_CPU0_P1_TX_BUF_C_DN<2>P5E_CPU0_P1_TX_BUF_C_DP<2>P5E_CPU0_P0_RX_BUF_DP<0>P5E_CPU0_P1_RX_BUF_DN<0>P5E_CPU0_P1_RX_BUF_DP<0>P5E_CPU0_P0_TX_BUF_C_DN<0>P5E_CPU0_P0_RX_BUF_DP<2>P5E_CPU0_P0_RX_BUF_DN<2>PRSNT_CABLE_GPU_A2_NP5E_CPU0_P0_RX_BUF_DN<5>P5E_CPU0_P1_TX_BUF_C_DN<6>P5E_CPU0_P0_TX_BUF_C_DN<6>P5E_CPU0_P1_RX_BUF_DP<6>P5E_CPU0_P1_RX_BUF_DP<3>P5E_CPU0_P0_TX_BUF_C_DN<3>P5E_CPU0_P1_TX_BUF_C_DN<0>P5E_CPU0_P0_RX_BUF_DN<0>GPU_3V3IO_RSVD3_FFUGPU_FPGA_OVERT_NP5E_CPU0_P1_TX_BUF_C_DP<7>P5E_CPU0_P0_RX_BUF_DP<7>P5E_CPU0_P0_RX_BUF_DN<7>P5E_CPU0_P1_RX_BUF_DP<7>P5E_CPU0_P0_TX_BUF_C_DN<7>P5E_CPU0_P0_TX_BUF_C_DP<7>P5E_CPU0_P1_TX_BUF_C_DN<7>
N4
N3
N2
N1
M4
M3
M2
M1
L4
L3
L2
L1
K4
K3
K2
K1
J4
J3
J2
J1
I4
I3
I2
I1
H4
H3
H2
H1
G4
G3
G2
G1
F4
F3
F2
F1
E4
E3
E2
E1
D4
D3
D2
D1
C4
C3
C2
C1
B4
B3
B2
B1
A4
A3
A2
A1
N8
N7
N6
N5
M8
M7
M6
M5
L8
L7
L6
L5
K8
K7
K6
K5
J8
J7
J6
J5
I8
I7
I6
I5
H8
H7
H6
H5
G8
G7
G6
G5
F8
F7
F6
F5
E8
E7
E6
E5
D8
D7
D6
D5
C8
C7
C6
C5
B8
B7
B6
B5
A8
A7
A6
A5
J108J108
2/2
NM
1
LKJC D E F G H IA B
2
3
4
N4
M4
N3
M3
N2
M2
N1
M1
L1
L2
L3
L4
K1
K2
K3
K4
J1
J2
J3
J4
I1
I2
I3
I4
H1
H2
H3
H4
G1
G2
G3
G4
F1
F2
F3
F4
E1
E2
E3
E4
D1
D2
D3
D4
C1
C2
C3
C4
B1
B2
B3
B4
A1
A2
A3
A4
1/2
NM
5
LKJC D E F G H IA B
6
7
8
N8
M8
N7
M7
N6
M6
N5
M5
L5
L6
L7
L8
K5
K6
K7
K8
J5
J6
J7
J8
I5
I6
I7
I8
H5
H6
H7
H8
G5
G6
G7
G8
F5
F6
F7
F8
E5
E6
E7
E8
D5
D6
D7
D8
C5
C6
C7
C8
B5
B6
B7
B8
A5
A6
A7
A8
SHEETDATE
DEPARTMENT
SIZE
PROJECT DOCUMENT NUMBER REV
REVIEWER
DESIGNER
123
7 3 2 1 6 5 4
E
A
B
C
E
D
C
B
A
7 6 5 4
D
OUT
OUT
OUT
OUTOUT
OUT
OUTOUT
IN
ININ
IN
OUT
OUTOUT
OUT
OUT
OUT
ININ
ININ
OUTOUT
OUTOUT
OUT
ININ
ININ
OUT
OUTOUT
OUTOUT
ININ
IN
ININ
OUTOUT
OUTOUT
ININ
IN
IN
IN
OUT
OUTOUT
OUTOUT
ININ
ININ
IN
OUTOUT
OUTOUT
ININ
ININ
IN
C



CPU1_P2_TX/RX<0-15> LANE REVERSALCPU1_P3_TX/RX<0-15> LANE REVERSAL
Thu Sep 14 16:12:58 2023119 OF 365MB FABCV02<NAME_2><NAME_1>GT AMD
SMB_BMC_SWB_BUF_SCLP5E_CPU1_P3_RX_BUF_DP<12>341341125342342353353249341341352342353341352341353353342342352352341341353126353342342352352353353342342352352341353353342342352341341352125352341341353353352342353353249125342352341341341127130352352342353352342342P5E_CPU1_P2_RX_BUF_DN<15>P5E_CPU1_P2_RX_BUF_DP<15>PRSNT_CABLE_GPU_B3_NP5E_CPU1_P2_TX_BUF_C_DP<15>P5E_CPU1_P2_TX_BUF_C_DN<15>P5E_CPU1_P3_TX_BUF_C_DN<15>P5E_CPU1_P3_TX_BUF_C_DP<15>SMB_BMC_SWB_BUF_SDAP5E_CPU1_P2_RX_BUF_DN<14>P5E_CPU1_P2_RX_BUF_DP<14>P5E_CPU1_P3_RX_BUF_DN<14>P5E_CPU1_P2_TX_BUF_C_DN<14>P5E_CPU1_P3_TX_BUF_C_DN<14>P5E_CPU1_P2_RX_BUF_DN<13>P5E_CPU1_P3_RX_BUF_DN<13>P5E_CPU1_P2_RX_BUF_DP<13>P5E_CPU1_P3_TX_BUF_C_DP<8>P5E_CPU1_P3_TX_BUF_C_DN<8>P5E_CPU1_P2_TX_BUF_C_DP<8>P5E_CPU1_P2_TX_BUF_C_DN<8>P5E_CPU1_P3_RX_BUF_DP<8>P5E_CPU1_P3_RX_BUF_DN<8>P5E_CPU1_P2_RX_BUF_DP<8>P5E_CPU1_P2_RX_BUF_DN<8>P5E_CPU1_P3_TX_BUF_C_DP<9>GPU_FPGA_EROT_FATALERR_NP5E_CPU1_P3_TX_BUF_C_DN<9>P5E_CPU1_P2_TX_BUF_C_DP<9>P5E_CPU1_P2_TX_BUF_C_DN<9>P5E_CPU1_P3_RX_BUF_DP<9>P5E_CPU1_P3_RX_BUF_DN<9>P5E_CPU1_P3_TX_BUF_C_DP<10>P5E_CPU1_P3_TX_BUF_C_DN<10>P5E_CPU1_P2_TX_BUF_C_DP<10>P5E_CPU1_P2_TX_BUF_C_DN<10>P5E_CPU1_P3_RX_BUF_DP<10>P5E_CPU1_P3_RX_BUF_DN<10>P5E_CPU1_P2_RX_BUF_DN<10>P5E_CPU1_P3_TX_BUF_C_DP<11>P5E_CPU1_P3_TX_BUF_C_DN<11>P5E_CPU1_P2_TX_BUF_C_DP<11>P5E_CPU1_P2_TX_BUF_C_DN<11>P5E_CPU1_P3_RX_BUF_DN<11>P5E_CPU1_P2_RX_BUF_DP<11>P5E_CPU1_P2_RX_BUF_DN<11>P5E_CPU1_P3_RX_BUF_DP<11>GPU_3V3IO_RSVD0_FFUP5E_CPU1_P3_RX_BUF_DN<12>P5E_CPU1_P2_RX_BUF_DP<12>P5E_CPU1_P2_RX_BUF_DN<12>P5E_CPU1_P3_TX_BUF_C_DP<13>P5E_CPU1_P3_TX_BUF_C_DN<13>P5E_CPU1_P2_TX_BUF_C_DN<12>P5E_CPU1_P3_TX_BUF_C_DN<12>P5E_CPU1_P3_TX_BUF_C_DP<12>GPU_3V3IO_RSVD1_FFUP5E_CPU1_P2_TX_BUF_C_DP<13>P5E_CPU1_P3_RX_BUF_DP<14>P5E_CPU1_P2_RX_BUF_DP<9>P5E_CPU1_P2_RX_BUF_DN<9>P5E_CPU1_P2_RX_BUF_DP<10>BIC_MONITERBMC_MONITER_BUFTHLFIO IOTHLF
PCIE - CPU1_EXAMAX_P2/P3_X16
P5E_CPU1_P3_RX_BUF_DN<15>P5E_CPU1_P3_RX_BUF_DP<15>P5E_CPU1_P2_TX_BUF_C_DP<14>P5E_CPU1_P3_TX_BUF_C_DP<14>P5E_CPU1_P3_RX_BUF_DP<13>P5E_CPU1_P2_TX_BUF_C_DN<13>P5E_CPU1_P2_TX_BUF_C_DP<12>
N4
N3
N2
N1
M4
M3
M2
M1
L4
L3
L2
L1
K4
K3
K2
K1
J4
J3
J2
J1
I4
I3
I2
I1
H4
H3
H2
H1
G4
G3
G2
G1
F4
F3
F2
F1
E4
E3
E2
E1
D4
D3
D2
D1
C4
C3
C2
C1
B4
B3
B2
B1
A4
A3
A2
A1
N8
N7
N6
N5
M8
M7
M6
M5
L8
L7
L6
L5
K8
K7
K6
K5
J8
J7
J6
J5
I8
I7
I6
I5
H8
H7
H6
H5
G8
G7
G6
G5
F8
F7
F6
F5
E8
E7
E6
E5
D8
D7
D6
D5
C8
C7
C6
C5
B8
B7
B6
B5
A8
A7
A6
A5
J109
J109
2/2
NM
1
LKJC D E F G H IA B
2
3
4
N4
M4
N3
M3
N2
M2
N1
M1
L1
L2
L3
L4
K1
K2
K3
K4
J1
J2
J3
J4
I1
I2
I3
I4
H1
H2
H3
H4
G1
G2
G3
G4
F1
F2
F3
F4
E1
E2
E3
E4
D1
D2
D3
D4
C1
C2
C3
C4
B1
B2
B3
B4
A1
A2
A3
A4
1/2
NM
5
LKJC D E F G H IA B
6
7
8
N8
M8
N7
M7
N6
M6
N5
M5
L5
L6
L7
L8
K5
K6
K7
K8
J5
J6
J7
J8
I5
I6
I7
I8
H5
H6
H7
H8
G5
G6
G7
G8
F5
F6
F7
F8
E5
E6
E7
E8
D5
D6
D7
D8
C5
C6
C7
C8
B5
B6
B7
B8
A5
A6
A7
A8
SHEETDATE
DEPARTMENT
SIZE
PROJECT DOCUMENT NUMBER REV
REVIEWER
DESIGNER
123
7 3 2 1 6 5 4
E
A
B
C
E
D
C
B
A
7 6 5 4
D
OUT
OUT
OUTOUT
OUTOUT
IN
IN
OUT
IN
IN
OUT
OUT
OUTOUT
OUTOUT
ININ
OUT
ININ
OUTOUT
OUTOUT
ININ
IN
IN
IN
OUT
IN
OUTOUT
OUTOUT
ININ
IN
OUT
IN
OUTOUT
OUTOUT
ININ
ININ
OUT
IN
IN
OUTOUT
OUTOUT
ININ
ININ
OUT
IN
OUT
OUTOUT
IN
IN
IN
IN
BI
IN
C



CPU1_P3_TX/RX<0-15> LANE REVERSALCPU1_P2_TX/RX<0-15> LANE REVERSAL
Thu Sep 14 16:12:59 2023120 OF 365MB FABCGT AMD<NAME_1><NAME_2>V02
P5E_CPU1_P3_RX_BUF_DN<5>P5E_CPU1_P3_TX_BUF_C_DN<5>353342342352353341341129128353353342342352352353341341353342342353353342342352353353342342353353129128341341352352342342353353341341352352342342352352341341352341341127126341341352352352127126341341352352342342353353P5E_CPU1_P3_TX_BUF_C_DP<0>P5E_CPU1_P2_TX_BUF_C_DP<0>P5E_CPU1_P2_TX_BUF_C_DN<0>P5E_CPU1_P3_RX_BUF_DP<0>P5E_CPU1_P3_TX_BUF_C_DN<0>P5E_CPU1_P2_RX_BUF_DP<0>P5E_CPU1_P2_RX_BUF_DN<0>GPU_FPGA_EROT_RECOV_BUF_NGPU_FPGA_BOOT_EN_BUFP5E_CPU1_P3_TX_BUF_C_DP<1>P5E_CPU1_P3_TX_BUF_C_DN<1>P5E_CPU1_P2_TX_BUF_C_DP<1>P5E_CPU1_P2_TX_BUF_C_DN<1>P5E_CPU1_P3_RX_BUF_DP<1>P5E_CPU1_P3_RX_BUF_DN<1>P5E_CPU1_P3_TX_BUF_C_DP<2>P5E_CPU1_P2_RX_BUF_DN<1>P5E_CPU1_P2_RX_BUF_DP<1>P5E_CPU1_P3_TX_BUF_C_DN<2>P5E_CPU1_P2_TX_BUF_C_DP<2>P5E_CPU1_P2_TX_BUF_C_DN<2>P5E_CPU1_P3_TX_BUF_C_DP<3>P5E_CPU1_P3_TX_BUF_C_DN<3>P5E_CPU1_P2_TX_BUF_C_DP<3>P5E_CPU1_P2_TX_BUF_C_DN<3>P5E_CPU1_P3_RX_BUF_DP<3>P5E_CPU1_P3_TX_BUF_C_DP<5>P5E_CPU1_P2_TX_BUF_C_DP<5>P5E_CPU1_P2_TX_BUF_C_DN<5>P5E_CPU1_P3_TX_BUF_C_DP<7>P5E_CPU1_P3_TX_BUF_C_DN<7>GPU_FPGA_EROT_RST_BUF_NGPU_BASE_STBY_EN_BUFP5E_CPU1_P2_RX_BUF_DN<6>P5E_CPU1_P2_RX_BUF_DP<6>P5E_CPU1_P3_RX_BUF_DN<6>P5E_CPU1_P3_RX_BUF_DP<6>P5E_CPU1_P2_TX_BUF_C_DN<6>P5E_CPU1_P2_TX_BUF_C_DP<6>P5E_CPU1_P3_TX_BUF_C_DN<6>P5E_CPU1_P3_TX_BUF_C_DP<6>P5E_CPU1_P2_RX_BUF_DN<5>P5E_CPU1_P2_RX_BUF_DP<5>P5E_CPU1_P3_RX_BUF_DP<5>P5E_CPU1_P2_TX_BUF_C_DP<7>P5E_CPU1_P2_TX_BUF_C_DN<7>P5E_CPU1_P3_RX_BUF_DP<7>P5E_CPU1_P3_RX_BUF_DN<7>
PCIE - CPU1_EXAMAX_P2/P3_X16
IOTHLFTHLFIOP5E_CPU1_P2_RX_BUF_DP<7>P5E_CPU1_P2_RX_BUF_DN<7>P5E_CPU1_P3_RX_BUF_DN<3>P5E_CPU1_P2_RX_BUF_DP<3>P5E_CPU1_P2_RX_BUF_DN<3>FM_SMB_1_ALERT_GPU_NGPU_HMC_PRSNT_NP5E_CPU1_P2_RX_BUF_DN<2>P5E_CPU1_P2_RX_BUF_DP<2>P5E_CPU1_P3_RX_BUF_DN<2>P5E_CPU1_P3_RX_BUF_DP<2>P5E_CPU1_P3_RX_BUF_DN<0>FM_SMB_2_ALERT_GPU_NGPU_BASE_HMC_READYP5E_CPU1_P2_RX_BUF_DN<4>P5E_CPU1_P2_RX_BUF_DP<4>P5E_CPU1_P3_RX_BUF_DN<4>P5E_CPU1_P3_RX_BUF_DP<4>P5E_CPU1_P2_TX_BUF_C_DN<4>P5E_CPU1_P2_TX_BUF_C_DP<4>P5E_CPU1_P3_TX_BUF_C_DN<4>P5E_CPU1_P3_TX_BUF_C_DP<4>
N4
N3
N2
N1
M4
M3
M2
M1
L4
L3
L2
L1
K4
K3
K2
K1
J4
J3
J2
J1
I4
I3
I2
I1
H4
H3
H2
H1
G4
G3
G2
G1
F4
F3
F2
F1
E4
E3
E2
E1
D4
D3
D2
D1
C4
C3
C2
C1
B4
B3
B2
B1
A4
A3
A2
A1
N8
N7
N6
N5
M8
M7
M6
M5
L8
L7
L6
L5
K8
K7
K6
K5
J8
J7
J6
J5
I8
I7
I6
I5
H8
H7
H6
H5
G8
G7
G6
G5
F8
F7
F6
F5
E8
E7
E6
E5
D8
D7
D6
D5
C8
C7
C6
C5
B8
B7
B6
B5
A8
A7
A6
A5
J110
J110
2/2
NM
1
LKJC D E F G H IA B
2
3
4
N4
M4
N3
M3
N2
M2
N1
M1
L1
L2
L3
L4
K1
K2
K3
K4
J1
J2
J3
J4
I1
I2
I3
I4
H1
H2
H3
H4
G1
G2
G3
G4
F1
F2
F3
F4
E1
E2
E3
E4
D1
D2
D3
D4
C1
C2
C3
C4
B1
B2
B3
B4
A1
A2
A3
A4
1/2
NM
5
LKJC D E F G H IA B
6
7
8
N8
M8
N7
M7
N6
M6
N5
M5
L5
L6
L7
L8
K5
K6
K7
K8
J5
J6
J7
J8
I5
I6
I7
I8
H5
H6
H7
H8
G5
G6
G7
G8
F5
F6
F7
F8
E5
E6
E7
E8
D5
D6
D7
D8
C5
C6
C7
C8
B5
B6
B7
B8
A5
A6
A7
A8
SHEETDATE
DEPARTMENT
SIZE
PROJECT DOCUMENT NUMBER REV
REVIEWER
DESIGNER
123
7 3 2 1 6 5 4
E
A
B
C
E
D
C
B
A
7 6 5 4
D
OUT
OUT
OUTOUT
OUTOUT
ININ
OUT
ININ
OUT
OUT
OUTOUT
OUTOUT
IN
IN
OUT
IN
IN
OUTOUT
OUTOUT
IN
IN
IN
IN
IN
IN
IN
OUTOUT
OUTOUT
ININ
ININ
IN
OUTOUT
OUTOUT
ININ
ININ
IN
OUT
IN
OUTOUT
OUTOUT
ININ
ININ
OUT
IN
OUT
OUTOUT
ININ
ININ
OUT
IN
C



CPU1_P1_TX/RX<0-15> LANE REVERSALCPU1_P0_TX/RX<0-15> LANE REVERSAL
Thu Sep 14 16:12:59 2023MB FABC121 OF 365<NAME_1><NAME_2>GT AMDV02331331320320330319319331331320320330330319126319331331320320330319123246130331331320320123246330319330330320319330330330123246123246319319319319330330320320331331319319330330320320127319331331320331331130319319330330320320331331P5E_CPU1_P1_TX_BUF_C_DP<8>P5E_CPU1_P1_TX_BUF_C_DN<8>P5E_CPU1_P0_TX_BUF_C_DP<8>P5E_CPU1_P0_TX_BUF_C_DN<8>P5E_CPU1_P1_RX_BUF_DN<8>P5E_CPU1_P0_RX_BUF_DP<8>P5E_CPU1_P0_RX_BUF_DN<8>P5E_CPU1_P1_TX_BUF_C_DP<9>P5E_CPU1_P1_TX_BUF_C_DN<9>P5E_CPU1_P0_TX_BUF_C_DP<9>P5E_CPU1_P0_TX_BUF_C_DN<9>P5E_CPU1_P1_RX_BUF_DP<9>P5E_CPU1_P1_RX_BUF_DN<9>P5E_CPU1_P0_RX_BUF_DP<9>GPU_PRSNT_NP5E_CPU1_P0_RX_BUF_DN<9>P5E_CPU1_P1_TX_BUF_C_DP<12>P5E_CPU1_P1_TX_BUF_C_DN<12>P5E_CPU1_P0_TX_BUF_C_DP<12>P5E_CPU1_P0_TX_BUF_C_DN<12>P5E_CPU1_P1_RX_BUF_DN<12>P5E_CPU1_P0_RX_BUF_DP<12>GPU_PEX_STRAP0GPU_FPGA_RST_R_BUF_NP5E_CPU1_P1_TX_BUF_C_DP<15>P5E_CPU1_P1_TX_BUF_C_DN<15>P5E_CPU1_P0_TX_BUF_C_DP<15>P5E_CPU1_P0_TX_BUF_C_DN<15>GPU_BASE_ID1P5E_CPU1_P1_RX_BUF_DP<8>P5E_CPU1_P0_RX_BUF_DN<11>P5E_CPU1_P1_RX_BUF_DN<11>P5E_CPU1_P1_RX_BUF_DP<11>P5E_CPU1_P0_TX_BUF_C_DN<11>P5E_CPU1_P0_RX_BUF_DP<11>P5E_CPU1_P1_RX_BUF_DP<12>P5E_CPU1_P1_RX_BUF_DP<15>P5E_CPU1_P1_RX_BUF_DN<15>
PCIE - CPU1_EXAMAX_P0/P1_X16
THLFIOTHLFIOGPU_BASE_ID0GPU_PEX_STRAP1P5E_CPU1_P0_RX_BUF_DN<15>P5E_CPU1_P0_RX_BUF_DP<15>P5E_CPU1_P0_RX_BUF_DN<14>P5E_CPU1_P0_RX_BUF_DP<14>P5E_CPU1_P1_RX_BUF_DN<14>P5E_CPU1_P1_RX_BUF_DP<14>P5E_CPU1_P0_TX_BUF_C_DN<14>P5E_CPU1_P0_TX_BUF_C_DP<14>P5E_CPU1_P1_TX_BUF_C_DN<14>P5E_CPU1_P1_TX_BUF_C_DP<14>P5E_CPU1_P0_RX_BUF_DN<13>P5E_CPU1_P0_RX_BUF_DP<13>P5E_CPU1_P1_RX_BUF_DN<13>P5E_CPU1_P1_RX_BUF_DP<13>P5E_CPU1_P0_TX_BUF_C_DN<13>P5E_CPU1_P0_TX_BUF_C_DP<13>FM_GPU_PWRGDP5E_CPU1_P0_RX_BUF_DN<12>P5E_CPU1_P1_TX_BUF_C_DP<13>P5E_CPU1_P1_TX_BUF_C_DN<13>P5E_CPU1_P0_TX_BUF_C_DP<11>P5E_CPU1_P1_TX_BUF_C_DN<11>P5E_CPU1_P1_TX_BUF_C_DP<11>FM_GPU_PWR_EN_R_BUFP5E_CPU1_P0_RX_BUF_DN<10>P5E_CPU1_P0_RX_BUF_DP<10>P5E_CPU1_P1_RX_BUF_DN<10>P5E_CPU1_P1_RX_BUF_DP<10>P5E_CPU1_P0_TX_BUF_C_DN<10>P5E_CPU1_P0_TX_BUF_C_DP<10>P5E_CPU1_P1_TX_BUF_C_DN<10>P5E_CPU1_P1_TX_BUF_C_DP<10>
N4
N3
N2
N1
M4
M3
M2
M1
L4
L3
L2
L1
K4
K3
K2
K1
J4
J3
J2
J1
I4
I3
I2
I1
H4
H3
H2
H1
G4
G3
G2
G1
F4
F3
F2
F1
E4
E3
E2
E1
D4
D3
D2
D1
C4
C3
C2
C1
B4
B3
B2
B1
A4
A3
A2
A1
N8
N7
N6
N5
M8
M7
M6
M5
L8
L7
L6
L5
K8
K7
K6
K5
J8
J7
J6
J5
I8
I7
I6
I5
H8
H7
H6
H5
G8
G7
G6
G5
F8
F7
F6
F5
E8
E7
E6
E5
D8
D7
D6
D5
C8
C7
C6
C5
B8
B7
B6
B5
A8
A7
A6
A5
J111J111
2/2
NM
1
LKJC D E F G H IA B
2
3
4
N4
M4
N3
M3
N2
M2
N1
M1
L1
L2
L3
L4
K1
K2
K3
K4
J1
J2
J3
J4
I1
I2
I3
I4
H1
H2
H3
H4
G1
G2
G3
G4
F1
F2
F3
F4
E1
E2
E3
E4
D1
D2
D3
D4
C1
C2
C3
C4
B1
B2
B3
B4
A1
A2
A3
A4
1/2
NM
5
LKJC D E F G H IA B
6
7
8
N8
M8
N7
M7
N6
M6
N5
M5
L5
L6
L7
L8
K5
K6
K7
K8
J5
J6
J7
J8
I5
I6
I7
I8
H5
H6
H7
H8
G5
G6
G7
G8
F5
F6
F7
F8
E5
E6
E7
E8
D5
D6
D7
D8
C5
C6
C7
C8
B5
B6
B7
B8
A5
A6
A7
A8
SHEETDATE
DEPARTMENT
SIZE
PROJECT DOCUMENT NUMBER REV
REVIEWER
DESIGNER
123
7 3 2 1 6 5 4
E
A
B
C
E
D
C
B
A
7 6 5 4
D
OUTOUT
OUTOUT
OUT
IN
OUT
IN
OUT
IN
IN
IN
OUT
OUTOUT
OUTOUT
ININ
OUT
ININ
OUTOUT
OUTOUT
ININ
ININ
IN
OUT
OUT
OUTOUT
OUTOUT
ININ
INININ
OUTOUT
OUT
IN
OUT
IN
ININ
IN
OUT
OUT
IN
OUT
OUTOUT
ININ
ININ
IN
OUTOUT
OUTOUT
ININ
ININ
OUT
OUT
C



P/N SWAPP/N SWAPP/N SWAPCPU1_P0_TX/RX<0-15> LANE REVERSALCPU1_P1_TX/RX<0-15> LANE REVERSAL
Thu Sep 14 16:12:59 2023MB FABCGT AMD<NAME_1><NAME_2>V02122 OF 365P5E_CPU1_P1_RX_BUF_DN<5>3313315555320320330330319319128331331320330249249331555533132032031931912312412924933132032033128282493303303203203313303303191131133203313313315353535312831931933033032032033153535353319319330330320331331113113126128319
319319320330319319235235234127234319319330330123330330320320
331P5E_CPU1_P1_TX_BUF_C_DP<0>P5E_CPU1_P1_TX_BUF_C_DN<0>CLK_100M_CPU1_CLK01_DNCLK_100M_CPU1_CLK01_DPP5E_CPU1_P0_TX_BUF_C_DP<0>P5E_CPU1_P0_TX_BUF_C_DN<0>P5E_CPU1_P1_RX_BUF_DP<0>P5E_CPU1_P1_RX_BUF_DN<0>P5E_CPU1_P0_RX_BUF_DP<0>P5E_CPU1_P0_RX_BUF_DN<0>RST_PERST_2_SWB_BUF_NP5E_CPU1_P1_TX_BUF_C_DP<1>P5E_CPU1_P1_TX_BUF_C_DN<1>P5E_CPU1_P0_TX_BUF_C_DN<1>P5E_CPU1_P1_RX_BUF_DN<1>SMB_2_BMC_GPU_BUF_SDASMB_2_BMC_GPU_BUF_SCLP5E_CPU1_P1_TX_BUF_C_DP<2>CLK_100M_CPU1_CLK11_DNCLK_100M_CPU1_CLK11_DPP5E_CPU1_P1_TX_BUF_C_DN<2>P5E_CPU1_P0_TX_BUF_C_DP<2>P5E_CPU1_P0_TX_BUF_C_DN<2>P5E_CPU1_P0_RX_BUF_DP<2>P5E_CPU1_P0_RX_BUF_DN<2>HGX_DETECT_N_ISOGPU_NVS_PWR_BRAKE_N_BUFSMB_1_BMC_GPU_BUF_SDAP5E_CPU1_P1_TX_BUF_C_DP<3>P5E_CPU1_P0_TX_BUF_C_DN<3>P5E_CPU1_P0_TX_BUF_C_DP<3>P5E_CPU1_P1_TX_BUF_C_DN<3>CLK_100M_CPU0_CLK11_DNCLK_100M_CPU0_CLK11_DPSMB_1_BMC_GPU_BUF_SCLP5E_CPU1_P1_RX_BUF_DN<2>P5E_CPU1_P1_RX_BUF_DP<2>P5E_CPU1_P0_TX_BUF_C_DN<4>P5E_CPU1_P0_TX_BUF_C_DP<4>P5E_CPU1_P1_TX_BUF_C_DN<4>P5E_CPU1_P1_RX_BUF_DP<4>P5E_CPU1_P1_RX_BUF_DN<4>P5E_CPU1_P0_RX_BUF_DN<4>P2E_MB_BMC_TX_BUF_C_DN<0>P2E_MB_BMC_TX_BUF_C_DP<0>P5E_CPU1_P0_TX_BUF_C_DN<5>P5E_CPU1_P1_TX_BUF_C_DP<6>P5E_CPU1_P1_TX_BUF_C_DP<7>P5E_CPU1_P1_TX_BUF_C_DN<7>P3E_CPU1_P5_RX_DN<0>P3E_CPU1_P5_RX_DP<0>P3E_CPU1_P5_TX_C_DN<0>P3E_CPU1_P5_TX_C_DP<0>RST_PERST_0_SWB_BUF_NP5E_CPU1_P0_RX_BUF_DN<6>P5E_CPU1_P0_RX_BUF_DP<6>P5E_CPU1_P1_RX_BUF_DN<6>P5E_CPU1_P1_RX_BUF_DP<6>P5E_CPU1_P0_TX_BUF_C_DN<6>P5E_CPU1_P0_TX_BUF_C_DP<6>P5E_CPU1_P1_TX_BUF_C_DN<6>P3E_CPU1_P5_RX_DN<1>P3E_CPU1_P5_RX_DP<1>P3E_CPU1_P5_TX_C_DP<1>P3E_CPU1_P5_TX_C_DN<1>P5E_CPU1_P0_RX_BUF_DN<5>P5E_CPU1_P0_RX_BUF_DP<5>P5E_CPU1_P1_RX_BUF_DP<5>P5E_CPU1_P0_TX_BUF_C_DP<5>P5E_CPU1_P1_TX_BUF_C_DN<5>P5E_CPU1_P1_TX_BUF_C_DP<5>P2E_MB_BMC_RX_DP<0>P2E_MB_BMC_RX_DN<0>GPU_FPGA_THERM_OVERT_NRST_PERST_1_SWB_BUF_NP5E_CPU1_P0_RX_BUF_DP<4>
P5E_CPU1_P0_RX_BUF_DP<7>P5E_CPU1_P0_RX_BUF_DN<7>P5E_CPU1_P0_TX_BUF_C_DP<1>P5E_CPU1_P1_RX_BUF_DP<1>P5E_CPU1_P0_RX_BUF_DP<1>P5E_CPU1_P0_RX_BUF_DN<1>USB2_HUB_BUF_SWB_DNUSB2_HUB_BUF_SWB_DPNC_J112_O5NC_J112_S5CLK_100M_GPU_FPGA_DNNC_J112_N2NC_J112_O2GPU_FPGA_READYCLK_100M_GPU_FPGA_DP
IOTHLFTHLFIO
PCIE - CPU1_EXAMAX_P0/P1_X16
P5E_CPU1_P0_RX_BUF_DN<3>P5E_CPU1_P0_RX_BUF_DP<3>P5E_CPU1_P1_RX_BUF_DN<3>P5E_CPU1_P1_RX_BUF_DP<3>PRSNT_SWB_NP5E_CPU1_P1_RX_BUF_DN<7>P5E_CPU1_P1_RX_BUF_DP<7>P5E_CPU1_P0_TX_BUF_C_DN<7>P5E_CPU1_P0_TX_BUF_C_DP<7>
NC_J112_R5NC_J112_P5P5E_CPU1_P1_TX_BUF_C_DP<4>
T4
T3
T2
T1
S4
S3
S2
S1
R4
R3
R2
R1
Q4
Q3
Q2
Q1
P4
P3
P2
P1
O4
O3
O2
O1
N4
N3
N2
N1
M4
M3
M2
M1
L4
L3
L2
L1
K4
K3
K2
K1
J4
J3
J2
J1
I4
I3
I2
I1
H4
H3
H2
H1
G4
G3
G2
G1
F4
F3
F2
F1
E4
E3
E2
E1
D4
D3
D2
D1
C4
C3
C2
C1
B4
B3
B2
B1
A4
A3
A2
A1
T8
T7
T6
T5
S8
S7
S6
S5
R8
R7
R6
R5
Q8
Q7
Q6
Q5
P8
P7
P6
P5
O8
O7
O6
O5
N8
N7
N6
N5
M8
M7
M6
M5
L8
L7
L6
L5
K8
K7
K6
K5
J8
J7
J6
J5
I8
I7
I6
I5
H8
H7
H6
H5
G8
G7
G6
G5
F8
F7
F6
F5
E8
E7
E6
E5
D8
D7
D6
D5
C8
C7
C6
C5
B8
B7
B6
B5
A8
A7
A6
A5
J112
J112
1/2
TSRQPONM
5
LKJC D E F G H IA B
6
7
8
T8
S8
R8
Q8
P8
O8
T7
S7
R7
Q7
P7
O7
T6
S6
R6
Q6
P6
O6
T5
S5
R5
Q5
P5
O5
N8
M8
N7
M7
N6
M6
N5
M5
L5
L6
L7
L8
K5
K6
K7
K8
J5
J6
J7
J8
I5
I6
I7
I8
H5
H6
H7
H8
G5
G6
G7
G8
F5
F6
F7
F8
E5
E6
E7
E8
D5
D6
D7
D8
C5
C6
C7
C8
B5
B6
B7
B8
A5
A6
A7
A8
2/2
TSRQPONM
1
LKJC D E F G H IA B
2
3
4
T4
S4
R4
Q4
P4
O4
T3
S3
R3
Q3
P3
O3
T2
S2
R2
Q2
P2
O2
T1
S1
R1
Q1
P1
O1
N4
M4
N3
M3
N2
M2
N1
M1
L1
L2
L3
L4
K1
K2
K3
K4
J1
J2
J3
J4
I1
I2
I3
I4
H1
H2
H3
H4
G1
G2
G3
G4
F1
F2
F3
F4
E1
E2
E3
E4
D1
D2
D3
D4
C1
C2
C3
C4
B1
B2
B3
B4
A1
A2
A3
A4
SHEETDATE
DEPARTMENT
SIZE
PROJECT DOCUMENT NUMBER REV
REVIEWER
DESIGNER
123
7 3 2 1 6 5 4
E
A
B
C
E
D
C
B
A
7 6 5 4
D
OUTOUT
IN
IN
IN
IN
ININ
BIIN
OUT
IN
IN
OUTOUT
OUTOUT
ININ
IN
IN
OUT
IN
IN
INBI
OUTOUT
OUTOUT
ININ
ININ
OUT
ININ
OUT
IN
OUT
OUTOUT
IN
ININ
IN
ININ
ININ
OUT
OUT
OUT
OUTOUT
IN
ININ
IN
OUTOUT
IN
IN
IN
IN
OUT
OUTOUT
OUTOUT
ININ
OUT
IN
ININ
OUT
ININ
OUTOUT
OUTOUT
IN
IN
IN
ININ
OUTOUT
ININ
IN
OUT
OUTOUT
OUT
IN
C



Thu Sep 14 16:12:23 2023<NAME_2><NAME_1>MB FABCGT AMDV02123 OF 365
P3V3_AUXP3V3_AUXP3V3_AUXP3V3_AUXP3V3_AUXP3V3_AUXP3V3_AUXP3V3_AUXP3V3_AUXP3V3_AUXP3V3_AUXP3V3_AUX
116122
11724624611881246
124122121246121246121246121246
246CHIP50V5%EMPTYPRSNT_CABLE_SWB_B1_NPRSNT_SWB_N
PRSNT_CABLE_SWB_B2_NPRSNT_CABLE_SWB_B2
PRSNT_SWBPRSNT_CABLE_SWB_B1PRSNT_CABLE_SWB_B1_ISO_NPRSNT_CABLE_SWB_B2_ISO_NPRSNT_CABLE_GPU_A3_NPRSNT_CABLE_GPU_A3PRSNT_SWB_ISO_N
HGX_DETECT_N_ISOGPU_PEX_STRAP0GPU_PEX_STRAP1GPU_BASE_ID1GPU_BASE_ID0
PRSNT_CABLE_GPU_A3_ISO_N
1%1/16W100K0402LFEMPTYPJT138KICSMLF1%CHIP1/16W10K0402LF0402LF1%100KEMPTY1/16W10KCHIP1/16W0402LF1%
1%0402LF1/16W10KCHIP5%1/16WCHIP4.7K0402LF0402LFEMPTY1/16W1%100KICPJT138KSMLFICPJT138KSMLF0402LF1/16WCHIP4.7K5%4.7K5%1/16WCHIP0402LFSMLFPJT138KICPJT138KSMLFICICPJT138KSMLF5%1/16WCHIP0402LF4.7K1000PF0402
5%0402EMPTY50V1000PF5%EMPTY040250V1000PF100K1%EMPTY1/16W0402LF1%1/16WCHIP0402LF10KICSMLFPJT138K5%CHIP4.7K1/16W0402LF4.7K5%1/16W0402LF1/16WCHIP4.7K5%0402LF
0402LF0CHIP 1/16W5%1/16W5%0EMPTY0402LF0402LF CHIP 1/16W05%0402LF0CHIP 1/16W5%1%EMPTY1/16W 0402LF100
50V0402EMPTY5%1000PFCHIP4.7K5%1/16W0402LFICPJT138KSMLF
EXAMAX_PRESENT
G2
G1
G2
G2
G1
G1
G2
G1
S2 D2D1S1
S2 D2S2 D2D1S1D1S1S2 D2D1S1
R2656
R3442
R3443
R3440
R3441
R9016R8002
R9004
R9008
5
2
5
2
5
2
5
2
4 31 6
4 31 64 31 64 31 6
Q9002
Q9002
Q9000
Q8000
Q9001
Q9001
Q8000
Q9000
2
1
2
1
21
21
21
21
21
2
1
2
1
2
1
2
1
2
1
2
1
2
1
2
1
2
1
2
1
2
1
2
1
2
1
2
1
2
1
2
1
2
1
2
1
R9014
R9006
R4058
R9002
SHEETDATE
DEPARTMENT
SIZE
PROJECT DOCUMENT NUMBER REV
REVIEWER
DESIGNER
123
7 3 2 1 6 5 4
E
A
B
C
E
D
C
B
A
7 6 5 4
D
OUT
IN
IN
OUT
OUT
IN
OUT
OUT
OUT
OUT
OUT
OUT
IN
R9017
C9002
R8003
R9015
C9000
C9001
C8000
R9005
R9003
R8001
R9007
R9009
C



PUSH-PULL OUTPUT
Thu Sep 14 16:12:23 2023MB FABC<NAME_2><NAME_1>GT AMDV02124 OF 365GPU_3V3IO_RSVD4_NSMLFPJT138K0.1UFP3V3_AUX
P3V3_AUXP3V3_AUX
P3V3_AUXP3V3_AUXP3V3_AUXP3V3_AUXP3V3_AUXP3V3_AUXP3V3_AUXP3V3_AUXP3V3_AUXP3V3_AUXP3V3_AUXP3V3_AUX81123 122115
81811151158181 117
EMPTYPJT138KSMLF040225VHGX_DETECT_NPJT138K1%1K0402LFCHIP1/16WHGX_DETECT_N_ISO10%0.1UFICIC0402X7R25VIC0.1UF74LVC2G17GW1%EMPTY0402LF5%SMLFICSMLF
EXAMAX_ISO (1/7)
PJT138K4.7KNC_U316_2YICGPU_3V3IO_RSVD4
GPU_3V3IO_RSVD1_ISOGPU_3V3IO_RSVD4_ISOGPU_3V3IO_RSVD1GPU_3V3IO_RSVD1_NGPU_3V3IO_RSVD3GPU_3V3IO_RSVD3_N0402LFCHIP1/16W100KSWB_HSC_EN
HGX_DETECT
GPU_3V3IO_RSVD3_ISOSMLFPJT138K1/16W0402LFEMPTY5%00402LF 1/16WEMPTY5%0
0402LF5%01/16WEMPTY0402LF4.7K5%1/16WEMPTY0.1UF25VX7R040210%EMPTY1/16W1%100K0402LF
EMPTY1/16W1%100K0402LFICSMLF0402LFCHIP
0402LFCHIP1/16W4.7K5%PJT138KSMLFICCHIP4.7K1/16W0402LF5%PJT138KSMLFSMLFICPJT138K0402LFCHIP1/16W4.7K5%IC
0402LF1/16W54.9KEMPTY1%100K0402LFEMPTY1%1/16W0402LFEMPTY1/16W54.9K1%EMPTY1%100K1/16W0402LF0402LFEMPTY1/16W1%54.9K1/16W100K1%0402LFEMPTY
1/16WCHIPSWB_HSC_EN_BUF_R SWB_HSC_EN_BUF49.90402LF0402LF1/16WCHIP100K1%CHIP1/16W0402LF100K1%1/16W0402LFCHIP100K1%
4.7K5%1/16W1%1/16WEMPTY0402LF100K10%0.1UF25V10%X7R040225V10%X7R0402
G1
G2
G2
G2
G1
G2
G1
G1
D1S1S2 D2 S2 D2S2 D2D1S1S2 D2D1S1D1S1
C6
R4546
R4549
R4545
R4167
R4169
R4168
R4164
R4166
R4165
4
6
3
1
2
5
5
5
2
5
2
2
52
1 64 3 4 34 31 64 31 61 6
U316
Q148
Q148
Q135
Q137
Q135
Q136
Q137
Q136
B0
A1
A0
B1
GND VCC
2
1
2
1
21R4570
21R4571
21R4569
2
1
2
1
21R45502
1C8
2
1
2
1
2
1
2
1
2
1
2
1
2
1
2
1
2
1
2
1
2
1
2
1
2
1
2
1
2
1
2
1
2
1
2
1
2
1
2
1
SHEETDATE
DEPARTMENT
SIZE
PROJECT DOCUMENT NUMBER REV
REVIEWER
DESIGNER
123
7 3 2 1 6 5 4
E
A
B
C
E
D
C
B
A
7 6 5 4
D
OUTIN
IN
OUT
IN
OUT
OUT
OUT
IN
IN
R4555
R4547
R4548
R4543
R4544
C4
C7
C5
R4158
R4159
R4162
R4163
R4160
R4161
C



Thu Sep 14 16:13:07 2023<NAME_1>V02125 OF 365MB FABC<NAME_2>GT AMD0402LFCHIPPJT138K4.7KEMPTY0402LF1/16WP3V3_AUXP3V3_AUXP3V3_AUXP3V3_AUXP3V3_AUXP3V3_AUXP3V3_AUXP3V3_AUXP3V3_AUXP3V3_AUXP3V3_AUXP3V3_AUXP3V3_AUXP3V3_AUXP3V3_AUXP3V3_AUXP3V3_AUXP3V3_AUXP3V3_AUXP3V3_AUXP3V3_AUXP3V3_AUXP3V3_AUXP3V3_AUX
1171168124681119119119802468181
118118118818124680
PRSNT_CABLE_GPU_A1SWB_HSC_PWRGDSWB_HSC_PWRGD_NPRSNT_CABLE_GPU_B3GPU_3V3IO_RSVD0_FFU_NGPU_3V3IO_RSVD5_FFU_NPRSNT_CABLE_GPU_A2GPU_3V3IO_RSVD3_FFU_NGPU_3V3IO_RSVD1_FFU_N
PRSNT_CABLE_GPU_A1_NPRSNT_CABLE_GPU_A1_ISO_NSWB_HSC_PWRGD_ISOPRSNT_CABLE_GPU_B3_NGPU_3V3IO_RSVD1_FFUGPU_3V3IO_RSVD0_FFUPRSNT_CABLE_GPU_B3_ISO_NGPU_3V3IO_RSVD1_FFU_ISOGPU_3V3IO_RSVD0_FFU_ISO
GPU_3V3IO_RSVD5_FFUPRSNT_CABLE_GPU_A2_NGPU_3V3IO_RSVD3_FFUGPU_3V3IO_RSVD5_FFU_ISOPRSNT_CABLE_GPU_A2_ISO_NGPU_3V3IO_RSVD3_FFU_ISO
1/16WEMPTY100K1%0402LF0402LF10K1%1/16WCHIPICSMLFPJT138K4.7K5%1/16W0402LFCHIPSMLFPJT138KICCHIP1/16W0402LF1%100K040210%25V0.1UFX7RCHIP1/16W100K0402LF1%1%1/16W100K0402LFSMLFICPJT138KCHIP5%0402LF1/16WICSMLF0402X7R10%25V0.1UFEMPTY100K1%1/16W0402LFCHIP10K0402LF1%1/16W0402LF100K1%EMPTYPJT138KSMLFIC1/16WEMPTY5%00402LF4.7KCHIP5%1/16WICSMLFPJT138K0402LF 1/16WEMPTY05%54.9K1%1/16W0402LFEMPTY0402LF100K1%1/16WEMPTY0402LF1%54.9K1/16WEMPTY4.7KCHIP1/16W0402LF5%0402LFEMPTY1/16W05%SMLFPJT138KIC0402LFCHIP1/16W5%4.7K
PJT138KICSMLF0402LF1/16WCHIP100K1%0.1UF25V0402X7R10%1%100K1/16W0402LFCHIPICPJT138KSMLF1%1/16WCHIP0402LF100K0.1UF040225V10%X7R040225VX7R10%0.1UF1/16W5%EMPTY00402LF
100K1/16WEMPTY1%0402LFEMPTY0402LF1/16W1%54.9K100KEMPTY0402LF1%1/16W10K1%CHIP1/16W0402LF0402LFEMPTY100K1%1/16W1/16WEMPTY0402LF54.9K1%
ICPJT138KSMLF4.7K5%0402LF1/16WCHIP1/16W0EMPTY5%0402LF1/16W100K1%ICPJT138KSMLF0402LF1/16WCHIP100K1%PJT138KSMLFIC0402LFCHIP1/16W4.7K5%ICSMLFPJT138K1/16W0402LF5%0EMPTYICSMLFPJT138K0402LFCHIP1/16W100K1%SMLFPJT138KICCHIP0402LF1/16W4.7K5%5%0EMPTY1/16W0402LFCHIP0402LF1/16W1%100K
0.1UFX7R040210%25VX7R0.1UF25V10%0402X7R040210%0.1UF25VICSMLFPJT138K
EXAMAX_ISO (2/7)
G1
G1
G1
G1
G2
G2
G1
G2
G1
G1
G2
G2
G2
G2
G1
G2
D1S1D1S1
D1S1
D1S1
S2 D2S2 D2D1S1S2 D2D1S1D1S1
S2 D2 S2 D2S2 D2S2 D2D1S1
S2 D2
R4140
R4142
R4141
R4561
R4137
R4128
R4139
R4138
R4130
R4129
R4560
R4156
R4125
R4127
R4126
R4155
5
5
5
5
2
2
2
2
5
5
2
5
2
2
5
2
4 3 4 34 34 31 61 61 61 6
4 34 31 64 31 61 64 31 6
Q146
Q130
Q133
Q129
Q130
Q133
Q129
Q146
Q128
Q131
Q128
Q132
Q131
Q132
Q134
Q134
2
1
2
1
2
1
2
1
2
1
2
1
2
1
2
1
21R4577
2
1
2
1
21R4578
2
1
2
1
2
1
2
1
2
1
21R4576
2
1
2
1
2
1
2
1
2
1
2
1
2
1
2
1
2
1
2
1
2
1
2
1
2
1
2
1
21R4575
21R4572
2
1
2
1
21R4573
21R4574
2
1
2
1
2
1
2
1
2
1
2
1
2
1
2
1
2
1
SHEETDATE
DEPARTMENT
SIZE
PROJECT DOCUMENT NUMBER REV
REVIEWER
DESIGNER
123
7 3 2 1 6 5 4
E
A
B
C
E
D
C
B
A
7 6 5 4
D
IN
OUT
IN
OUT
OUT
IN
IN
OUT
IN
IN
IN
OUT
OUT
OUT
OUT
IN
R4124
C16
C19
C17
R4131
R4132
R4135
R4136
R4133
R4134
C12
C14
C13
C18R4562
R4559
C15
R4119
R4120
R4123
R4121
R4122
R4153
R4154
C



Thu Sep 14 16:12:23 2023<NAME_1><NAME_2>GT AMDMB FABC126 OF 365V02
P3V3_AUXP3V3_AUX
P3V3_AUX
P3V3_AUXP3V3_AUXP3V3_AUXP3V3_AUXP3V3_AUXP3V3_AUXP3V3_AUXP3V3_AUXP3V3_AUX
P3V3_AUX
P3V3_AUXP3V3_AUXP3V3_AUXP3V3_AUXP3V3_AUXP3V3_AUXP3V3_AUXP3V3_AUX
818181122
118120120
81
8111981246242121115811/16WCHIP0402LF1%1KSMLFPJT138K0402X7R10%25V0.1UFSMLF0402X7R10%25V0.1UFICICSMLFPJT138KGPU_FPGA_OVERT_ISO_NGPU_FPGA_OVERTGPU_HMC_PRSNT_ISO_NGPU_BASE_HMC_READY_ISOGPU_FPGA_THERM_OVERT_N
EXAMAX_ISO (3/7)
0402LF1/16WCHIP1%54.9K
54.9KCHIP1%1/16W0402LF1%100KEMPTY1/16W0402LF1/16W0402LF1%10KCHIP1%54.9KCHIPEMPTY0402LF100K1%1/16WICCHIP4.7K1/16W5%0402LFPJT138KSMLFIC4.7K5%1/16W0402LFICSMLFIC1/16WCHIP0402LF5%4.7KICPJT138KSMLF0402LF5%4.7KCHIP1/16WSMLFIC
0402LF1/16WEMPTY100K1%
0402LF100K1%1/16WEMPTYPJT138KGPU_FPGA_OVERT_N
CHIPPJT138K0402LFGPU_BASE_HMC_READY_NGPU_BASE_HMC_READY1/16WGPU_HMC_PRSNTGPU_HMC_PRSNT_N0402LF1/16WCHIP100K1%1/16W0402LFCHIP100K1%GPU_FPGA_THERM_OVERT1%100K1/16WCHIP0402LF1/16W0402LFCHIP100K1%
25V0.1UF10%X7R0402
SMLFGPU_FPGA_THERM_OVERT_ISO_N0.1UF10%X7R040225VPJT138KPJT138KPJT138KSMLFIC0.1UF0402X7R10%25V0402LF1/16W100KCHIP1%0402LFCHIP5%4.7K1/16WPJT138KSMLFIC1/16WCHIP1%54.9K0402LF0402LF100K1%1/16WEMPTYGPU_FPGA_EROT_FATALERR_ISO_NGPU_FPGA_EROT_FATALERR_NGPU_FPGA_EROT_FATALERRPJT138KSMLFICICSMLFPJT138K10%25VX7R04020.1UF1%100K0402LFCHIP1/16W0402LFCHIP1/16W4.7K5%1%CHIP1/16W10K0402LF100K1%EMPTY1/16W0402LFGPU_PRSNT_N_ISOGPU_PRSNTGPU_PRSNT_NSMLFPJT138KIC0402LF5%EMPTY01%1/16W4.7K0402LFEMPTY5%CHIP0402LFICSMLF0402LFEMPTY1%1/16W10KLEAVE GPU_WP_HW_CTRL_ISO_N FLOATING PER NV DESIGN GUIDE REQUIREMENTGPU_WP_HW_CTRL_ISO_NPJT138KGPU_WP_HW_CTRL_ISO1/16W4.7KGPU_WP_HW_CTRL_N
G2
G1
G2
G2
G1
G1
G2
G1
G1
G2
G1
G2
G1
G2
S2 D2D1S1S2 D2S2 D2D1S1D1S1S2 D2D1S1
D1S1S2 D2D1S1S2 D2D1S1S2 D2
R9044
R9043
R3503
C1988
R3474
C1978
C1975
R3439
R3438
R3432
R3433
R3434
C1976
R3435
2
5
2
5
2
5
5
2
5
5
2
2
5
2
1 64 31 64 31 64 3
4 31 64 34 31 61 64 31 6
Q106
Q106
Q108
Q108
Q107
Q107
Q101
Q101
Q102
Q103
Q102
Q103
Q104
Q104
2
1 R3472
2
1
2
1
2
1
2
1
2
1
2
1
2
1
2
1
2
1
2
1
2
1
2
1
2
1
2
1
2
1
2
1
2
1
2
1
2
1
2
1
2
1
2
1
2
1
2
1
2
1
2
1
2
1
2
1
2
1
2
1
2
1
2
1
2
1
DESIGN NOTE:
21
SHEETDATE
DEPARTMENT
SIZE
PROJECT DOCUMENT NUMBER REV
REVIEWER
DESIGNER
123
7 3 2 1 6 5 4
E
A
B
C
E
D
C
B
A
7 6 5 4
D
OUT
OUT
OUT
IN
OUT
OUT
IN
OUT
IN
IN
OUT
IN
OUT
IN
IN
R3470
R3471
R3525
R3502
R3504
R3498
R3487
R3473
R3475
R3464
R3431
R3465
R3463
R3429
C1974
C1973
R3436
R3437
R3428
R3430
C



Thu Sep 14 16:12:23 2023MB FABCV02127 OF 365GT AMD<NAME_2><NAME_1>810402LF1/16W1%100K100K116FM_SWB_PWRGD0402LFIC0402LFP3V3_AUX1/16WCHIP25VCHIP4.7K8110%P3V3_AUXBIC_MONITER
P3V3_AUXP3V3_AUXP3V3_AUX
P3V3_AUXP3V3_AUXP3V3_AUXP3V3_AUXP3V3_AUXP3V3_AUXP3V3_AUXP3V3_AUXP3V3_AUXP3V3_AUXP3V3_AUXP3V3_AUXP3V3_AUXP3V3_AUXP3V3_AUX
P3V3_AUX
P3V3_AUXP3V3_AUXP3V3_AUX81818181
122
8181
234
119115120121
120115 0402X7R10%25V0.1UFPJT138KSMLF0402X7R10%0.1UFIC0402X7R25V0.1UF0402X7R10%0.1UFIC 25V0402X7R10%0.1UF10%0402X7R0.1UFIC
0.1UF25V10%X7R
10%X7R25V0402
0402
25V
25V
0402LFGPU_FPGA_READY_ISOSMLFPJT138K1%100K1/16WCHIP
1%100KCHIP1/16W0402LF1%100KCHIP1/16W0402LF1%100K1/16WCHIP0402LFIC100KFM_SWB_BIC_READY_ISO_N0402LF1/16W1%0402LFCHIP1/16W1%100KFM_SMB_1_ALERT_GPU_ISO_NFM_SWB_BIC_READY4.7K1%FM_SMB_2_ALERT_GPU_ISO_NSMLFPJT138KPJT138KPJT138KPJT138KRST_BMC_FROM_SWB_ISO_NPJT138KBIC_MONITER_ISOSMLFBIC_MONITER_N1/16WCHIP
0402LFGPU_FPGA_READYPJT138K1/16W1/16WPJT138KICCHIPICPJT138K
5%CHIP0402LF5%1/16W0402LFCHIP1/16W5%0402LF1/16WCHIP5%4.7K1/16WCHIP0402LF5%4.7KPJT138KICSMLF100K1%EMPTY1/16W0402LF1/16WEMPTY0402LF1%100K0402LFEMPTY1/16W1%100KCHIP1/16W1%100K0402LF1/16W1%CHIP100KCHIP0402LF100K1%1/16W0402LFCHIP1/16W1%100K0402LFEMPTY1/16W1%5%1/16WCHIP0402LF0402LFEMPTY1/16W1%100K1/16W100KEMPTY1%0402LF4.7K0402LF1/16WCHIP5%ICSMLF5%0402LF4.7KCHIP0402LF1/16W1%EMPTY100K1%1/16WCHIP54.9K54.9K1%0402LFEMPTY1%54.9K0402LF0402LFCHIP1/16W54.9K1%
PJT138KSMLFPJT138KFM_GPU_PWRGD_ISOFM_SWB_PWRGD_ISOSMLFPJT138KGPU_FPGA_READY_NRST_BMC_FROM_SWBFM_GPU_PWRGD_NICSMLFSMLFICSMLFSMLFICICSMLF
FM_SMB_1_ALERT_GPU
SMLFPJT138KRST_BMC_FROM_SWB_NSMLFFM_SMB_2_ALERT_GPU_NFM_GPU_PWRGD
FM_SMB_1_ALERT_GPU_NEXAMAX_ISO (4/7)FM_SWB_BIC_READY_N
FM_SWB_PWRGD_N4.7KIC0402LF100K0402LF1/16WCHIP1%
IC 4.7KSMLFCHIPFM_SMB_2_ALERT_GPU1/16W100KPJT138K0.1UFIC
G2
G2
G1
G1
G1
G2
G1
G1
G2
G2
G1
G2
G2
G1
G1
G2
S2 D2S2 D2
D1S1
D1S1D1S1
S2 D2D1S1
D1S1S2 D2
S2 D2D1S1
S2 D2
S2 D2D1S1
D1S1
S2 D2
R3320
C1881
C1802
R3029
R3034
C1804
C1756
C1754
R2919
R2842
R2841
R2836
R2834
R2835
5
2
2
5
5
2
5
5
2
2
5
5
5
2
2
2
4 31 6
1 64 3
4 31 6
4 3
4 31 6
1 6
4 3
4 34 3
1 6
1 61 6
Q96
Q96
Q75
Q75
Q74
Q74
Q70
Q72
Q71
Q69
Q71
Q69
Q67
Q72
Q70
Q67
2
1 2
1
2
1
R3030
2
1
R2920
2
1
2
1
2
1
2
1
2
1
2
1
2
1
2
1
2
1
2
1
2
1
2
1
2
1
2
1
2
1
2
1
2
1
2
1
2
1
2
1
2
1
2
1
2
1
2
1
2
1
2
1
2
1
2
1
2
1
2
1
2
1
2
1
2
1
2
1
2
1
2
1
SHEETDATE
DEPARTMENT
SIZE
PROJECT DOCUMENT NUMBER REV
REVIEWER
DESIGNER
123
7 3 2 1 6 5 4
E
A
B
C
E
D
C
B
A
7 6 5 4
D
OUT
OUT
OUT
OUT
IN
IN
IN
IN
IN
OUT
IN
OUT
OUT
IN
IN
OUT
OUT
R2933
R3035
R3510
R3514
R3512
R3513
R3511
R3318
R3321
R3028
R3032
C1772
C1773
C1774
R2935
R2934
R2837
R2830
R2832
R2828
R2838
R2833
R2829
R2831
C



FROM CPU0FROM CPU1FROM CPU1TBCPUSH-PULL OUTPUT
PUSH-PULL OUTPUTPUSH-PULL OUTPUTThu Sep 14 16:12:24 2023<NAME_1><NAME_2>GT AMDMB FABC128 OF 365V02P3V3_AUXP3V3_AUX
P3V3_AUXP3V3_AUXP3V3_AUXP3V3_AUX
P3V3_AUXP3V3_AUXP3V3_AUX
1228585 1228581 1151221208181 120
0402LF49.9RST_PERST_2_SWB_BUF_NSMLFRST_PERST_CPU1_SWB_1_R_NRST_PERST_CPU1_SWB_R_NICRST_PERST_1_SWB_BUF_NX7R25V0.1UFRST_PERST_1_SWB_BUF_R_N0402RST_PERST_2_SWB_BUF_R_N74LVC2G17GWRST_PERST_0_SWB_BUF_R_NCHIPCHIP0402LF0402LFRST_PERST_CPU0_SWB_R_N0402LFFM_SWB_PWR_EN_R1/16W74LVC2G17GW100KSMLF
CHIP1/16W1%10KICEMPTY49.9CHIP0402LF
1/16W4.7K10K0402LF49.90402LFCHIPCHIP1/16W0402LFCHIPFM_SWB_PWR_EN_R_BUF4.7K5%RST_PERST_0_SWB_BUF_NEMPTY1/16W0402LF49.90402LFCHIP1/16W1%49.90402LFCHIP10K0402LFEMPTY49.91%X7RGPU_BASE_STBY_EN_BUF1%CHIPGPU_BASE_STBY_ENSMLF74LVC2G17GW0.1UF25V0402X7R10%0402LF100K1/16W0402LF1%100K4.7KEMPTY1/16W5%0402LF10K1%1/16W10%040225V0.1UF0402LF100K1%1/16W0402LF1/16W1K1%CHIP5%1/16W0402LFEMPTY4.7K100KCHIP1%0402LF1/16W
IC10%CHIPEMPTY1/16W1%4.7KCHIP5%0402LF5%CHIP1/16W0402LFEXAMAX_ISO (5/7)FM_SWB_PWR_EN_R1_BUF
GPU_FPGA_BOOT_ENGPU_BASE_STBY_EN_BUF_RGPU_FPGA_BOOT_EN_BUF_RGPU_FPGA_BOOT_EN_BUF
R3515
R2914
R2918
R3468
R3469
R3391
R3392
4
6
3
1
4
6
3
1
4
6
3
1
52 52 52
U256
21R3390
U252
U253
B0
A1
A0
B1
B0
A1
A0
B1
B0
A1
A0
B1 GND VCCGND VCCGND VCC
2
1
21
2
1
2
1
2
1
2
1
21
2
1
21
2
1C1977
2
1
2
1
2
1
2
1
2
1C1957
21
2
1
2
1
2
1
2
12
1
21
2
1C1958
SHEETDATE
DEPARTMENT
SIZE
PROJECT DOCUMENT NUMBER REV
REVIEWER
DESIGNER
123
7 3 2 1 6 5 4
E
A
B
C
E
D
C
B
A
7 6 5 4
D
OUT
IN
IN
OUT
IN
OUT
IN
OUT
IN
IN OUT
OUT
R2932
R2910 R3466
R3467
R3449
R3448
R3454
R3453
R3455
R3451
R3456
R3457
R3452
C



OPEN-DRAIN OUTPUTOPEN-DRAIN OUTPUT
Thu Sep 14 16:12:24 2023<NAME_2><NAME_1>MB FABCGT AMDV02129 OF 365
GPU_NVS_PWR_BRAKE_NGPU_FPGA_EROT_RECOV_NGPU_FPGA_EROT_RST_NP3V3_AUXP3V3_AUXP3V3_AUXP3V3_AUXP3V3_AUXP3V3_AUXP3V3_AUXP3V3_AUX1221201208181811/16WCHIP0402LF1%1K1%1KCHIP1/16W0402LF1%1K0402LFCHIP1/16WGPU_NVS_PWR_BRAKE_N_RGPU_FPGA_EROT_RECOV_BUF_R_NGPU_NVS_PWR_BRAKE_N_BUFGPU_FPGA_EROT_RST_BUF_NGPU_FPGA_EROT_RECOV_BUF_NNC_U257_2YEXAMAX_ISO (6/7)
GPU_FPGA_EROT_RST_BUF_R_NEMPTY0402LF1/16W1%100K10%0.1UF25VX7R0402EMPTY1%1/16W0402LF100K54.9KCHIP1/16W1%0402LFCHIP0402LF33.2IC74LVC2G07DW-7SMLF0402LFEMPTY100K1%1/16W0402LFCHIP1%54.9K1/16WCHIP0402LF33.21%100K1/16W0402LFEMPTYCHIP0402LF33.20402LFCHIP1%54.9K1/16W100K1%1/16WEMPTY0402LFEMPTY0402LF1/16W100K1%ICSMLF74LVC2G07DW-7X7R0.1UF040225V10%
52
43
61
52
43
61
21R3497
U257
21R3496
21R3397
U255
VCCGND
2Y
1Y
2A
1A
VCCGND
2Y
1Y
2A
1A
2
1
2
1
2
1C1979
2
1
2
1
2
1
R3494
2
1
2
1
R3492
2
1
2
1
2
1
R3461
2
1
2
1
2
1C1963
SHEETDATE
DEPARTMENT
SIZE
PROJECT DOCUMENT NUMBER REV
REVIEWER
DESIGNER
123
7 3 2 1 6 5 4
E
A
B
C
E
D
C
B
A
7 6 5 4
D
IN OUT
OUTIN
OUTIN
R3459
R3491
R3495
R3490
R3493
R3489
R3488
R3462
R3460
C



PUSH-PULL OUTPUTPUSH-PULL OUTPUTThu Sep 14 16:12:24 2023MB FABC<NAME_2><NAME_1>GT AMDV02130 OF 365
4.7K0402LF
CHIPRST_SWB_BIC_BUF_NBMC_MONITER_BUFP3V3_AUXFM_GPU_PWR_EN_R1100KUART_BMC_BIC_RXFM_PDB_BUF_EN_R1CHIPEMPTYCHIP1/16WGPU_FPGA_RST_R1_BUF_N74LVC1G126SE-70402LF100K0402
IC74LVC2G17GW1%1/16WEMPTY0402LF100K0402LF5%1/16WEMPTY4.7K0.1UF25V10%X7R04024.7K5%1/16WCHIP5%EMPTY1/16W4.7KCHIP
SMLFIC74LVC2G17GW040225V10%X7R0.1UF5%4.7K1/16WEMPTY0402LF5%EMPTY0402LF1/16W5%CHIP0402LF4.7K1/16W0402LF1%100KEMPTY1/16W10%25V0.1UFX7R000402LF33.20402LFEMPTY1/16W4.7K5%10K1%0402LF10KCHIP1%1/16W1/16W5%0402LF4.7K1/16WCHIP0402LF1%54.9KCHIP1/16W0402LF100K1%
IC0402LF1%CHIPFM_GPU_PWR_EN_R1/16WSMLF
BMC_MONITER_BUF_RBMC_MONITER_R0402LFCHIP5%
EXAMAX_ISO (7/7)
SMLFRST_SWB_BIC_BUF_R_N49.94.7KCHIP0402LF49.91/16W5%CHIP0402LF0402LFCHIP49.9FM_GPU_PWR_EN_R_BUFGPU_FPGA_RST_R_BUF_N1/16W1%8181116150
11981 115121121241
P3V3_AUXP3V3_AUXP3V3_AUX
P3V3_AUX
P3V3_AUXP3V3_AUX
P3V3_AUXP3V3_AUX0402LFP3V3_AUX0402LFP3V3_AUX2461/16W4.7KRST_SWB_BIC_R_NEMPTYGPU_FPGA_RST_R_NP3V3_AUXUART_BMC_BIC_R_BUF_RXUART_BMC_BIC_BUF_RX0402LF0402LFP3V3_AUXCHIP0402LFUART_BMC_BIC_R_RXFM_UART_EN0402LF33.2CHIP
R3036
R3317
R3315
R3063
R2937
R2924
R2911
R2912
R2916
R2915
R2820
4
1
2
4
6
3
1
4
6
3
1
53 52 52
U204
R3033
21R2917
U196
U195
B0
A1
A0
B1
OE
Y
A
B0
A1
A0
B1
GND VCCGND VCCGND VCC
2
1
2
1
2
1
R4515
2
1
21
2
1
2
1
2
1
2
1
2
1
21
21
21
2
1C1803
2
1
2
1
21R2925
21
2
1
2
1
2
1C1770
2
1
2
1
2
1
2
1C1769
2
1
2
1
SHEETDATE
DEPARTMENT
SIZE
PROJECT DOCUMENT NUMBER REV
REVIEWER
DESIGNER
123
7 3 2 1 6 5 4
E
A
B
C
E
D
C
B
A
7 6 5 4
D
OUT
OUT
IN
IN
OUTIN
IN
IN OUT
IN OUT
R4173
R2927
R2909
R3508
R3506
R3507
R3509
R2936
R2926
R2815
C



P/N SWAPP/N SWAPP/N SWAPP/N SWAPP/N SWAPP/N SWAPP/N SWAPP/N SWAPP/N SWAPP/N SWAPP/N SWAPP/N SWAPP/N SWAPP/N SWAPP/N SWAPP/N SWAPTO CPU0 PCIE G3 [15:0]FROM CPU0 PCIE G3 [15:0]
Thu Sep 14 16:12:25 2023<NAME_1>MB FABC131 OF 365V02GT AMD<NAME_2>
OCP_SFF_MAIN_PWR_EN131
P12V_OCP_SFF_R
P12V_OCP_SFF_R
P3V3_OCP_SFF
P3V3_OCP_SFF
P3V3_OCP_SFFP3V3_OCP_SFF
1%1%2002001/16WCLK_50M_NCSI_OCP_SFF_ISONCSI_OCP_SFF_TXD1CLK_100M_CPU0_CLK05_DN0402LFCHIPSMB_OCP_SFF_3V3AUX_BUF_R_SCL SMB_OCP_SFF_3V3AUX_BUF_SCL0402LF133CHIP 1/16WCLK_100M_CPU0_CLK05_DPSMB_OCP_SFF_3V3AUX_BUF_R_SDA SMB_OCP_SFF_3V3AUX_BUF_SDACLK_100M_CPU0_CLK03_DN28CLK_100M_CPU0_CLK03_DP13182132132801311318013113613113223236565282882 131131 82 132131136132133 248248
13113113414380131131808013180131
1321321321341431328013180131132134 1432813328134 1431311321321321322828
2929133
82 28132132133133133
IO_SLOTCHIP1/16W0402LFCHIP
OCP_SFF_MAIN_PWR_EN_RFM_OCP_SFF_PWR_GOODNCSI_OCP_SFF_RXD0SGPIO_OCP_SFF_DATAOUTSGPIO_OCP_SFF_CLKOCP_SFF_ID01/16WOCP_SFF_AUX_PWR_ENP5E_CPU0_G3_RX_DP<15:0>P5E_CPU0_G3_RX_DN<15:0>P5E_CPU0_G3_TX_C_DN<15:0>P5E_CPU0_G3_TX_C_DP<15:0>CLK_100M_CPU0_CLK02_DPCLK_100M_CPU0_CLK02_DN0402LF10K1%CHIPOCP_SFF_MAIN_PWR_ENFM_OCP_SFF_PWR_GOOD1%OCP_SFF_AUX_PWR_EN05%0402LFRST_PERST0_OCP_SFF_NOCP_SFF_BIF2_R_N0402LF0OCP_SFF_AUX_PWR_EN_ROCP_SFF_BIF1_R_NIO_SLOTSCONN168_ME1016810202011
CHIP1%OCP_SFF_ID0OCP_SFF_ID1OCP_SFF_PRSNT3_R_NTP_OCP_SFF_B68TP_OCP_SFF_B69SGPIO_OCP_SFF_DATAINSGPIO_OCP_SFF_CLKSGPIO_OCP_SFF_DATAOUTSGPIO_OCP_SFF_LD_N
OCP_SFF_ISO_BIF2_ENOCP_SFF_ISO_BIF0_ENOCP_SFF_ISO_BIF1_ENOCP_SFF_PRSNT0_R_NNCSI_OCP_SFF_CRS_DVSGPIO_OCP_SFF_LD_NSGPIO_OCP_SFF_DATAINNCSI_OCP_SFF_RXD1OCP_SFF_PRSNT2_R_NRST_PERST1_OCP_SFF_NOCP_SFF_PRSNT1_R_NOCP_SFF_ID1NCSI_OCP_SFF_TXD0RST_SMB_OCP_SFF_NNCSI_OCP_SFF_TX_EN
IO_SLOT IO_SLOT10K1%CHIP1K 1%10K1%0402LF 1/16W1KIO_SLOTIO_SLOTIO_SLOTIO_SLOT
IOSMLF
PCIE - SFF OCP3.0_X16_CPU0 (1/3)
OCP_SFF_BIF0_R_N
5%01/16WCHIP0402LFX7R0.1UF10%25V0402X7R040225V0.1UF10%X7R040210%25V0.1UF05%0402LFC080522UF20%X6S16VX6SC080520%16V22UF
0402LF05%0402LFCHIP5%00402LF05%5%
1%4.7K1/16WEMPTY0402LF4.7KCHIP0402LF1%1/16W
1/16W10KCHIP1%EMPTY0402LF4.7K1/16W04020.1UFX7R10%25VX7R10%25V0.1UF04020.1UF25V10%0402X7RX7R040210%25V0.1UF10%25V0.1UFX7R04020402LF1%CHIP100K1/16W4.7K1/16W1%CHIP0402LF
CLK_100M_CPU0_CLK04_DPCLK_100M_CPU0_CLK04_DN
USB2_CPU0_P11_DNUSB2_CPU0_P11_DPPLACE THE BULK CAPS CLOSE TO SLOTOCP_SFF_PWRBRK_NUSB2_P11_DNUSB2_P11_DP
OCP_SFF_ISO2_RBT_ARB_OUTOCP_SFF_ISO1_RBT_ARB_INIRQ_LVC3_OCP_SFF_WAKE_NRST_PERST3_OCP_SFF_NRST_PERST2_OCP_SFF_NOCP_SFF_PRSNTA_R_N0402LF05%CHIP1/16W
21
21
R42
R46
R38
R8420
R8421
R8423
R8422
OA3
A69
A68
A9
A8
A7
OA6
OB7
B69
B68
OA12OB12
A15B15
OA11OB11
A14B14
OA8
OA9
OA7
OB8
OB9
OB14 OA14
OA5
OA4
A70B70
A12
A42B42
A10
B66
B63
B60
B57
B54
B51
B48
B45
B40
B37
B34
B31
B27
B24
B21
B18
B65
B62
B59
B56
B53
B50
B47
B44
B39
B36
B33
B30
B26
B23
B20
B17
OA2
OA1
A11
B10
A66
A63
A60
A57
A54
A51
A48
A45
A40
A37
A34
A31
A27
A24
A21
A18
A65
A62
A59
A56
A53
A50
A47
A44
A39
A36
A33
A30
A26
A23
A20
A17
OB1
OB2
OB3
OB13
OB10
OA13
OA10
B67
B64
B61
B58
B55
B52
B49
B46
B43
B41
B38
B35
B32
B29
B28
B25
B22
B19
B16
B13
A67
A64
A61
A58
A55
A52
A49
A46
A43
A41
A38
A35
A32
A29
A28
A25
A22
A19
A16
A13
A6
A5
A4
A3
A2
A1
G5
G4
G3
G2
G1
OB5
OB4
OB6
B9
B8
B7
B12
B6
B5
B4
B3
B2
B1
B11
15
14
14
15
12
13
11
13
11
8
10
9
10
9
8
6
7
5
7
6
5
4
3
4
3
2
1
2
1
14
12
13
12
11
10
9
8
10
9
8
7
6
5
7
5
6
4
3
4
3
2
1
0
2
1
0
15
12
0
0
15
11
14
13
J38
KEY
KEY
KEY
G5
G4
G3
G2
G1
PRSNTB3#
RFU1_NC_B69
RFU1_NC_B68
GND_B67
PETp15
PETn15
GND_B64
PETp14
PETn14
GND_B61
PETp13
PETn13
GND_B58
PETp12
PWRBRK0#
USB_DATp
USB_DATn
GND_A67
PERp15
PERn15
GND_A64
PERp14
PERn14
GND_A61
PERp13
PERn13
GND_A58
PERp12
PERn12
GND_A55
PERp11
PERn11
GND_A52
PERp10
PERn10
GND_A49
PERp9
PERn9
GND_A46
PERp8
PERn8
GND_A43
PRSNTB1#
GND_A41
PERp7
PERn7
GND_A38
PERp6
PERn6
GND_A35
PERp5
PERn5
GND_A32
PERp4
PERn4
GND_A29
GND_A28
PERp3
PERn3
GND_A25
PERp2
PERn2
GND_A22
PERp1
PERn1
GND_A19
PERp0
PERn0
GND_A16
REFCLKp1
REFCLKn1
GND_A13
PRSNTB2#
PERST1#
PRSNTA#
SMRST#
SMDAT
SMCLK
GND_A6
GND_A5
GND_A4
GND_A3
GND_A2
GND_A1
RBT_CLK_IN
GND_OA13
REFCLKp3
REFCLKn3
GND_OA10
RBT_TXD0
RBT_TXD1
RBT_TX_EN
SLOT_ID1
RBT_ARB_OUT
RBT_ARB_IN
WAKE#
PERST3#
PERST2#
PETn12
GND_B55
PETp11
PETn11
GND_B52
PETp10
PETn10
GND_B49
PETp9
PETn9
GND_B46
PETp8
PETn8
GND_B43
PRSNTB0#
GND_B41
PETp7
PETn7
GND_B38
PETp6
PETn6
GND_B35
PETp5
PETn5
GND_B32
PETp4
PETn4
GND_B29
GND_B28
PETp3
PETn3
GND_B25
PETp2
PETn2
GND_B22
PETp1
PETn1
GND_B19
PETp0
PETn0
GND_B16
REFCLKp0
REFCLKn0
GND_B13
AUX_PWR_EN
+3.3V_EDGE
PERST0#
BIF2#
BIF1#
BIF0#
+12V_EDGE_B6
+12V_EDGE_B5
+12V_EDGE_B4
+12V_EDGE_B3
+12V_EDGE_B2
+12V_EDGE_B1
RBT_CRS_DV
GND_OB13
REFCLKp2
REFCLKn2
GND_OB10
RBT_RXD0
RBT_RXD1
SLOT_ID0
CLK
DATA_OUT
DATA_IN
LD#
MAIN_PWR_EN
NIC_PWR_GOOD
2
1
21
2
1C1236
2
1C27
2
1C1239
21
2
1C34
2
1C1213
21
21R39 21R40 21R41
21
21
21
21
2
1
2
1
21R1929
21R1930
2
1
2
1C1240
2
1C1238
2
1C1237
2
1C1235
2
1C21
21R1671
21R3132
2
1
CAD NOTE:
R47R48
SHEETDATE
DEPARTMENT
SIZE
PROJECT DOCUMENT NUMBER REV
REVIEWER
DESIGNER
123
7 3 2 1 6 5 4
E
A
B
C
E
D
C
B
A
7 6 5 4
D
IN
ININ
INOUTINOUTOUT
OUT
ININ
IN
ININ
IN
OUT
OUT
OUT
OUT
ININ
IN
IN
IN
OUT IN
OUTOUT OUT
BIIN
IN
ININ
OUTOUTIN
OUT
ININ
ININ
ININ
IN
ININ
OUT
IN
OUTOUT
IN
OUT
OUT
ININ
OUT
R1895
R33
R34
R31
R32
C



Thu Sep 14 16:12:25 2023GT AMD<NAME_2><NAME_1>MB FABCV02132 OF 365P3V3_AUXP3V3_AUXP3V3_AUXP3V3_AUX
131136132801392412462512531311318213113613213381 143132 150 138132 138 150132 138150132 138 150143131131131131131131131150132138150132138132138150131132 150 138150132138150132138150150132138131132 150 138131131
OCP_SFF_AUX_PWR_ENRST_SMB_SWITCH_NIC1/16W1%0402LF100KCHIPRST_SMB_OCP_SFF_NCHIPRST_HP_OCP_SFF_R_N74LVC1G126SE-7PCIE - SFF OCP3.0 (2/3)OCP_SFF_AUX_PWR_EN_R20402LF 1/16WCHIPICFM_OCP_SFF_PWR_GOODOCP_SFF_AUX_PWR_EN_R1OCP_SFF_AUX_PWR_EN1%33.20402LF1/16WCHIP0402X7R10%25V0.1UFFB_BMC_ISOLATE_R11/16WFB_BMC_ISOLATE0402LF0EMPTY5%FM_NCSI_OCP_SFF_R_OE01/16WCHIP0402LF5%0402LF74LVC1G126SE-7NCSI_BMC_TX_EN_ROCP_SFF_RBT_ARB_OUTRMII_BMC_OCP_TXD_0SMLFCHIPRMII_OCP_BMC_RXD_0RMII_OCP_BMC_CRSDVRMII_OCP_BMC_RXD_1CHIPNCSI_BMC_RXD0_RNCSI_BMC_RXD1_ROCP_SFF_RBT_ARB_INEMPTY0402LF1/16W222222NCSI_BMC_TXD1_R74CBTLV3126PW
1%10%NCSI_OCP_SFF_TXD1OCP_SFF_ISO_BIF0_ENOCP_SFF_ISO_BIF1_ENOCP_SFF_ISO_BIF2_ENNCSI_OCP_SFF_TXD0NCSI_OCP_SFF_TX_ENOCP_SFF_ISO2_RBT_ARB_OUTRMII_BMC_OCP_TXD_0RMII_BMC_OCP_TX_ENRMII_OCP_BMC_RXD_1OCP_SFF_ISO1_RBT_ARB_IN OCP_SFF_RBT_ARB_IN_RRMII_BMC_OCP_TX_ENNCSI_BMC_CRS_DV_R
RMII_BMC_OCP_RX_ERRMII_OCP_BMC_CRSDVRMII_OCP_BMC_RXD_0RMII_BMC_OCP_TXD_1NCSI_OCP_SFF_RXD1RMII_BMC_OCP_TXD_1SMLF
NCSI_OCP_SFF_RXD0NCSI_BMC_TXD0_RNCSI_OCP_SFF_CRS_DV
33.21/16W
0
5%0X7R0.1UFCHIP1K1/16W1%0402LF100K1%CHIP100K1%CHIP1%CHIP100K100K CHIP1%0402LF1%CHIP1/16W100K1%100K CHIP0402LFCHIP1001%1/16W1%CHIP1/16W0402LF1%1001/16WCHIP0402LF
CHIP00CHIPCHIP0CHIP22CHIP1%CHIP100K1/16W
10%0402X7R0.1UF25V0.1UF25VX7R040210%ICSMLFIC74CBTLV3126PWSMLF
25V10004020402LF
R87
R3231
R83
R82
R80
R79
R77
R84
R1897R1896 R1898
R1719
4
1
2
4
1
2
R76
R75
R74
R73
R72
R59
R1290
5353
U224
U66
U7
U67
VCC
4OE
4A4B
3OE
3A
GND
1A
2B
1B
2OE
1OE
3B
2A
OE
Y
A
OE
Y
A
VCC
4OE
4A4B
3OE
3A
GND
1A
2B
1B
2OE
1OE
3B
2A
GND VCCGND VCC
21R2474
21R2473
21 21R3233
2
1
R3232
2
1
21
21
21
21
21
21
21
2
1
2
1
2
1
21
2
1
2
1
R1289
2
1
2
1
21
14
7
1311 12
108 9
46 5
13 2
14
7
1311 12
108 9
46 5
13 2
SHEETDATE
DEPARTMENT
SIZE
PROJECT DOCUMENT NUMBER REV
REVIEWER
DESIGNER
74CBTLV3126
74CBTLV3126
123
7 3 2 1 6 5 4
E
A
B
C
E
D
C
B
A
7 6 5 4
D
OUT
IN
IN
IN
OUT
OUT
OUT
IN
IN
OUT
OUT
OUT
OUT
IN
IN
IN
IN
OUT
IN OUTIN
OUT
OUT
OUT
OUT
OUT
OUT
OUT
IN
IN
OUT
OUT
OUT
R3237
C1840
C639
C640
C641
C



POP
Thu Sep 14 16:12:25 2023MB FABC133 OF 365<NAME_2><NAME_1>GT AMDV02CHIPCLK_50M_RMII_BMC_OCPCLK_50M_NCSI_OCP_SFFCLK_50M_NCSI_OCP_V3_2ICP3V3_AUX1/16WCHIPSMLF
RST_PERST_OCP_SFF_BUF_NSMLFP3V3_AUXP3V3_AUXP3V3_AUX
P3V3_AUXP3V3_OCP_SFFP3V3_AUXP3V3_AUXP3V3_AUXP3V3_AUXP3V3_AUX0402LF136131131131131
1391311318083139
150133
1311321331550000IC74LVC1G17GWRST_PERST_OCP_SFF_BUF2_NRST_PERST3_OCP_SFF_NRST_PERST0_OCP_SFF_NRST_PERST1_OCP_SFF_NRST_PERST2_OCP_SFF_N1/16WCHIPCLK_50M_RMII10K1%10K X7R0.1UFCLK_50M_BMC_MAC_RCLK_50M_NCSI_OCP_1TP_CLK_50M_Y3CLK_50M_NCSI_OCP_20402LF1%CHIPCLK_50M_NCSI_OCP_SFF_ISO
X7R0.1UF040225V10%4.7K0.1UF25VCHIP0402LF1%IC
CLK_50M_ENPU_OCP_SFF_WAKE_OEIRQ_LVC3_OCP_SFF_WAKE_NNC_U104_NC1FM_SYS_THROTTLE_N
CLK_50M_RMII_ROCP_SFF_WAKE_BUFF_N OCP_SFF_WAKE_BUFF_R_NOCP_SFF_PWRBRK_NIRQ_LVC3_WAKE_BUF_N0402LFCHIP10K1%1/16WIO_SLOT0402X7R25V0.1UF10%OSC50MHZSMLFIO_SLOT5%0CHIP0402LF1/16WICSMLF74LVC1G126SE-70402LF1%1/16WCHIPIO_SLOTSMLFPI6CV304LEIC040210%0.1UFX7R25V1%27.4 CHIPCHIP27.41/16W27.41%ICSMLF74LVC1G07GV0CHIP1%33.20402LF 1/16W25V0402X7R10%0.1UF4.7K1%0402LFCHIP1/16WSMLF10%X7R040233.2 0402LF1/16W1%0402X7R25V0.1UF10%0402LF1%1/16W33.2 CHIP10%25V04024.7K1/16W1%0402LFEMPTYPCIE - SFF OCP3.0 (3/3)FB_BMC_ISOLATECLK_50M_NCSI_OCP_SFF_ISO_RCLK_50M_NCSI_OCP_SFFPLACE R2487 CLOSE TO U157IRQ_OCP_SFF_WAKE_BUF_N74LVC1G66GVNC_U157_NC1OCP_SFF_PWRBRK_BUFF_N74LVC1G07GV
21 R956
21 R905
21 R877
21 R899
R2489
R1594
R4601
R1140
R1141
R3181
R1139
R1595
2
1 5
3
4
4
5
13
2
4
51
3
2
4
51
3
24
1
2
4 3
1 2
53
U320
U75
U104
U157
U90
U8082
OSC1
VCC
E
GND
Z
Y
OE
Y
A
NC
Y
GND
A
VCC
VDD OUT
GNDOE
NC1
YGND
A
VCC
NC1
YGND
A
VCC
GND
VDD
Y3
Y2
Y1
Y0
OE
CLK_IN
GND VCC
2
1
21
2
12
1
2
1
21
21
21 21 21
2
1
2
1
2
1
R1824
21
2
1C1274
2
1
R1138
2
1
2
1
21
2
1
R53
2
1
CAD NOTE:
8753
6
2
4
1
R45
SHEETDATE
DEPARTMENT
SIZE
PROJECT DOCUMENT NUMBER REV
REVIEWER
DESIGNER
123
7 3 2 1 6 5 4
E
A
B
C
E
D
C
B
A
7 6 5 4
D
OUTOUTOUT
OUT
IN
OUT
IN
OUT
IN
OUTOUTOUT
OUT
IN
IN
C10
C1663
R2488
C36
C1275
R2487
C2344
C72
C



START UP TIME:3.94MSVIMON(MAX)= 1.594V @ IOUT=1.6AVIMON(MAX)= 1.679V @ IOUT=9.03AUVP: 2.63VOVP: 3.89VSTART UP TIME:8.21MSFROM CPLDFROM CPLDFROM OCP_12V_PGIMAX=1.1ADESIGN SPECIFICATIONOCP=IMAX*1.3=1.43AP3V3_OCP_V3P12V_OCP_V3IMAX=6.6AOCP=IMAX*1.3=8.58A
OVP: 14.91VUVP: 10.17VFROM PRSNT BUFFERFROM PRSNT BUFFERThu Sep 14 16:12:38 2023MB FABCGT AMDV02<NAME_1><NAME_2>134 OF 365P3V3_AUXNIC_P12V_MAM_TIC_BOM11KP3V3_AUX1K1/16WCHIP0402LF1/16WNIC_P12V_MAM_TIC_BOM1SFF_OCP3.0 HSC(1/3)143131CHIP1/16WOCP_SFF_PRSNT1_R_NOCP_SFF_PRSNT0_R_NNIC_P12V_MAM_TIC_BOM1P3V3_AUXP12V_AUXP12V_AUXP12V_AUXP12V_OCP_SFFP3V3_AUXP3V3_OCP_SFF_R
P3V3_AUXP3V3_AUXP3V3_AUX
P3V3_AUX8083135248 258135 134 1362482581361341352481341351362488083135136136134135248 136
13114313114313114313681
05%1/16WCHIP0402LFNIC_P3V3_BOM10402LFSMLFNIC_P12V_MAM_TIC_BOM1MAX15090BEWI+TC04020402LF1%1/16WNIC_P12V_MAM_TIC_BOM1NIC_P12V_MAM_TIC_BOM13900PFC04021/16WP12V_OCP_FAULT_1CHIP0402LF0402LFNIC_P12V_MAM_TIC_BOM11%1/16WP12V_OCP_PWRGD_1NIC_P12V_MAM_TIC_BOM1EMPTYP12V_OCP_GATE_10.01UFICB340A-13-F1UFNIC_P12V_MAM_TIC_BOM10402LFSMLF0402LFP3V3_OCP_EN_1_RC0402P3V3_OCP_SENSE_1NIC_P12V_MAM_TIC_BOM1P12V_OCP_VCC_1PJT138KP3V3_OCP_SFF_EN_REMPTYNIC_P3V3_BOM10402LFNIC_P3V3_BOM1NIC_P3V3_BOM1CHIP5%0402LF5%0402LFP12V_OCP_SFF_ISENSE_MAM_MAMHP_LVC3_OCP_V3_1_P12V_PWRGD0402LFCHIPNIC_P12V_MAM_TIC_BOM10402LFCHIPEMPTYNIC_P12V_MAM_TIC_BOM11/16WP12V_OCP_SFF_ISENSE_MAM_TIC100KNIC_P12V_MAM_TIC_BOM10402LFCHIPNIC_P12V_MAM_TIC_BOM11%0402LF5%0C0402P3V3_OCP_FAULT_15%1/16W5%NIC_P12V_MAM_TIC_BOM10402LFNIC_P3V3_BOM1EMPTY0402LFP12V_OCP_SFF_BUF_EN_REMPTYIC 10M1/16WCHIP845P12V_OCP_SENSE_1X6S25VP12V_OCP_UV_1_RSMLFPJT138K0402LFHP_LVC3_OCP_V3_1_P12V_PWRGD05%NIC_P3V3_BOM15%P3V3_OCP_1_EN_GP12V_OCP_SFF_EN_RPJT138KPJT138KICNIC_P12V_MAM_TIC_BOM1P12V_OCP_REG_1ICNIC_P3V3_BOM1P12V_OCP_SFF_BUF_EN_R0402LFNIC_P3V3_BOM1CHIP5%1/16W0CHIP1%IC1%6.8K1/16W5%CHIP0CHIPIC0.1UFNIC_P12V_MAM_TIC_BOM1C040225V1UFCHIPC0402SMF14A1/16WX6S0402LF1%50VNIC_P12V_MAM_TIC_BOM15%NIC_P12V_MAM_TIC_BOM100CHIP0NIC_P12V_MAM_TIC_BOM150V16VX6SOCP_V3_1_P3V3_PWRGDC0805NIC_P3V3_BOM14.53KP3V3_OCP_OV_10402LFEMPTYSMLFNIC_P3V3_BOM110NIC_P3V3_BOM10402LF1/16W100KNIC_P3V3_BOM11/16W1%CHIP6800PFNIC_P3V3_BOM11/16W10M1%0.01UF0402LFNIC_P3V3_BOM11/16W50VEMPTYNIC_P3V3_BOM1CHIPC0402EMPTY100K1%1/16WEMPTYNIC_P3V3_BOM10.1UFX7RB340A-13-F0402LF
OCP_SFF_PRSNT3_R_NOCP_SFF_PRSNT2_R_NHP_LVC3_OCP_SFF_PRSNT2_NHP_LVC3_OCP_V3_1_PRSNT2_N_R HP_LVC3_OCP_SFF_PRSNT2_PLD_N
IC
0402LF1%1K X6S0402LFCHIP0402LF10KCHIP1%1/16W
CHIP1UF25VX6S10K101%1/16W0402LF0CHIP 1/16W5%1UF1%15K25V0.1UFX7R10%0402X7R10%25V0.1UF040274LVC2G07DW-7IC1K1%0402LFCHIPSMLFIC74LVC2G07DW-71%1%1/16W4.7K00 1%1/16WCHIP10K0402LFCHIP0402LF1/16W5%0
15K0402LF5.36K1%1/16WIC
16V10UFX6S25V50V0402LF0402 C080525VC04021%1/16WCHIP1%CHIP0402LF1UFNIC_P3V3_BOM1C04027.15K1%ICCHIP1/16W1%NIC_P3V3_BOM11/16W25.5K0402LFMAX15090BEWI+TSMLFNIC_P3V3_BOM11/16WNIC_P3V3_BOM1C040225VX6S1UFNIC_P3V3_BOM1P3V3_OCP_VCC_1P3V3_OCP_CB_11/16W0402LFCHIP22UF16V10UFC080525VX7R0402CHIPR3869/R3870 CO-LAYOUTEMPTYCHIP1/16W1%1/16W30.1K0402LFCHIP1%1/16WCHIPCHIPP12V_OCP_UV_1NIC_P12V_MAM_TIC_BOM1NIC_P12V_MAM_TIC_BOM1NIC_P12V_MAM_TIC_BOM1P12V_OCP_CB_1P12V_OCP_OV_125VP3V3_OCP_GATE_PU202_1P3V3_OCP_PWRGD_1100K1/16W1/16W1%160K1%1/16W10K5%0402LF1/16WSMLF5%P12V_OCP_EN_1_R0402LFP12V_OCP_1_EN_G4.7K0NIC_P3V3_BOM1P3V3_OCP_UV_1_R1NIC_P3V3_BOM1P3V3_OCP_REG_1P3V3_OCP_UV_1SMLF
G1
G2
G2
G1
D1S1S2 D2CAS2 D2D1S1
PR4525
PC4056
PC2088
PD101
R1136
R3794
R3783
R5487
R561
R4061
R576
PR3791 PR3780
PC2086
PC2091
R3796
PC2089
PR5481
PC2144
PC2080PC2092
R3797R3799
R3869
R3870
R3144
PR3781
PR3798
PC2093
PR3789
PR3790
PC5328
R4070
PR3792
PC2085
PC2087
PR5484
R1148
PC2079
PR3786
PR3787
R3784
PR3788
R4068
A2
D2
D1 D7
D3
D6
D4
C6
C4
B6
B4
A4
A1
D5
C5
C3
B5
B3
A5
A3
C2
C1
B2
A6
C7
B7
A7B1
5
PC2081
PC2082
A2
D2
D1 D7
D3
D6
D4
C6
C4
B6
B4
A4
A1
D5
C5
C3
B5
B3
A5
A3
C2
C1
B2
A6
C7
B7
A7B1
52
43
61
52
43
61
2
5
2
4 31 64 31 6
PU202
Q124
PD103
PD102
PU203
U211
U8
Q124
Q123
Q123
PG
FAULT#
GND_C2
GND_C1
GND_B2
CDLY
GATE
OUT_D6
OUT_D4
OUT_C6
OUT_C4
OUT_B6
OUT_B4
OUT_A4
ISENSEOV
UV
REG
EN#
CB
IN_D5
IN_C5
IN_C3
IN_B5
IN_B3
IN_A5
IN_A3
VCC
VCCGND
2Y
1Y
2A
1A
VCCGND
2Y
1Y
2A
1A
PG
FAULT#
GND_C2
GND_C1
GND_B2
CDLY
GATE
OUT_D6
OUT_D4
OUT_C6
OUT_C4
OUT_B6
OUT_B4
OUT_A4
ISENSEOV
UV
REG
EN#
CB
IN_D5
IN_C5
IN_C3
IN_B5
IN_B3
IN_A5
IN_A3
VCC
CACA
CAD NOTE:
21
21
21
2
1
2
1
2
1
21
21
21
2
1
21
2
1
2
1
2
1
2
1
2
1
2
1
21
21
2
1
PR4524
2
1
2
1
2
1
2
1
21
2
1
2
1
2
1
2
1
2
1
2
1
2
1
R6045
R4069
CA
CACA
SHEETDATE
DEPARTMENT
SIZE
PROJECT DOCUMENT NUMBER REV
REVIEWER
DESIGNER
123
7 3 2 1 6 5 4
E
A
B
C
E
D
C
B
A
7 6 5 4
D
OUT
OUT
OUT
IN
IN
OUT
IN
IN
IN
IN
IN
IN
IN
OUT
OUT
R1486
R577 R1150
R3785
C592
C593
R1907
R1908
R1905
R1906
C



2ND SOURCE OF PU203VTH>1.391V(HIGH)FROM PRSNT BUFFERPU204 OPTIONAL BOMDE-POPPOPPR3841FROM CPLDPC2158DE-POPMP5025C/PR3843PR3838PR3840FROM OCP_12V_PGFROM PRSNT BUFFER
FROM CPLD
2ND SOURCE OF PU202
START UP TIME:8.62MSDE-POPPOPMP5022CDE-POPPOPPOPSTART UP TIME:4.7MSOCP=IMAX*1.3=8.58AMP5022AMP5025A/VIMON(MAX)= 1.582V @ IOUT=9.09ATDELAY: 6.29MSTFAULT: 1.27MSENABLE:
IMAX=1.1AIMAX=6.6AP12V_OCP_V3P3V3_OCP_V3CURRENT LIMIT=1.6APOPDE-POPOCP=IMAX*1.3=1.43ADESIGN SPECIFICATION
Thu Sep 14 16:12:39 2023V02135 OF 365GT AMDMB FABC<NAME_2><NAME_1>P12V_AUXP3V3_OCP_SFF_RP12V_OCP_SFFP12V_AUXP3V3_AUX
P3V3_AUXP3V3_AUXHP_LVC3_OCP_V3_1_P12V_PWRGDP12V_OCP_IMON_1NIC_P12V_MPS_MAM_BOM2SMLFICRS31312RP12V_OCP_AVIN_PD_1P12V_OCP_OV_FB_1P12V_OCP_FLTB_1P12V_OCP_EN_1_R2P12V_OCP_TIMER_1P12V_OCP_ISET_1P12V_OCP_SS_10402LFNIC_P12V_MPS_MAM_BOM2NIC_P12V_MPS_MAM_BOM2CHIPNIC_P12V_MPS_MAM_BOM2005%
NIC_P12V_MPS_MAM_BOM20.047UFX7R25VCHIPNIC_P12V_MPS_MAM_BOM2X7R10K1/16WNIC_P12V_MPS_MAM_BOM21/16WNIC_P12V_MPS_MAM_BOM2100NFC0603P12V_OCP_AVIN_PD_1NIC_P12V_MPS_MAM_BOM20402X7R10%2.2UF16V20%X7R0402LF0402LF1%CHIP0402LF1%0402LFEMPTYNIC_P12V_MPS_MAM_BOM21/10WCHIP0603LF0402LF1%NIC_P12V_MPS_MAM_BOM2X7RNIC_P12V_MPS_MAM_BOM2C0402CHIP50VCHIP1%17.4K1/16W0.1UFNIC_P12V_MPS_MAM_BOM21001%16V0402NIC_P3V3_BOM2CHIPX7RX6SNIC_P3V3_BOM2100PF50VC080516V
16V0.22UFC04020402LF1%025VSFF_OCP3.0 HSC CO-LAYOUT(2/3)
5%X7R0402IC10UFX6SNIC_P3V3_BOM2P3V3_OCP_MODE_171.5K1UF25VC0402P3V3_OCP_ILIMIT_1P3V3_OCP_GATE_1P3V3_OCP_DVDT_10.068UFNIC_P3V3_BOM21/16W1%CHIP10K71.5K1/16W1%CHIP0402LFEMPTY49.91%NIC_P12V_MPS_MAM_BOM210K1/16W120K05%040214.3K1%0402LF1/16WNIC_P12V_MPS_MAM_BOM2
P3V3_OCP_EN_1_R2EMPTYNIC_P3V3_BOM2MP5016GQH-L-ZSMLFNIC_P3V3_BOM20402LF5%P12V_OCP_SFF_BUF_EN_R
P12V_OCP_SFF_BUF_EN_RNIC_P3V3_BOM2EMPTY0402LFHP_LVC3_OCP_V3_1_P12V_PWRGD1.33KP3V3_OCP_SFF_EN_RNIC_P3V3_BOM20 1%0402LFCHIPNIC_P3V3_BOM25%EMPTYP12V_OCP_SFF_EN_R
NIC_P3V3_BOM25%0CHIP
135135258258248135 134 136
248135 134 136248136 135 134248134 83 80248136136 13483 8050V39PFNIC_P3V3_BOM2NPO0402
R3871/R3872 CO-LAYOUT1/16WCHIPNIC_P12V_MPS_MAM_BOM2NIC_P12V_MPS_MAM_BOM21/16W0EMPTY0402LF5%P12V_OCP_SFF_ISENSE_MPS_MAMNIC_P12V_MPS_TIC_BOM3P12V_OCP_SFF_ISENSE_MPS_TIC0402LF5%NIC_P12V_MPS_MAM_BOM2NIC_P12V_MPS_MAM_BOM2135134C040225VX6S1UF
R1137
R1487
R3845
R591
R3834
PC2159
PC2160
PR3843
PC2158
PR3841
PR3842
PR3838
R4532
PR3839
PC2156PR3837
PC2154
PC2155
PR3835
PC2153
20
19
18
17
16
15
14
13
26
25
24
23
21_22
4
6
10
11
2
5
87
9
3
1
12
PU204
PU205
PC2163
PC2161
PR3844PC2157
PR3840
GND
SS
ISET
TIMER
ENTM
LOADEN
EN
VIN_26
VIN_25
VIN_24
VIN_23
IMON
FLTB
PG
OV
VOUT_13
AVIN
VOUT_14
VOUT_15
VOUT_16
VOUT_17
VOUT_18
VOUT_19
VIN_21_22
VOUT_20
SOURCE
GATE
DV_DT
VCC
GND
ILIMIT
MODE
EN
21
21
21
21
21
PC2162
2
1
2
1
21
21
2
1
2
1
2
1
2
1
2
1
CAD NOTE:
1_2 6_7
54 3
8
9
10
PR3846
SHEETDATE
DEPARTMENT
SIZE
PROJECT DOCUMENT NUMBER REV
REVIEWER
DESIGNER
123
7 3 2 1 6 5 4
E
A
B
C
E
D
C
B
A
7 6 5 4
D
IN
OUT
OUT
OUT
OUT
IN
IN
IN
IN
IN
R3871
R3872
C



P3V3_OCP_SFF PWRGDPUSH PULLPUSH PULLOPEN DRAIN
PUSH PULL OUTPUT
PUSH PULLTO OCP_HSC ENOPEN DRAINOCP CARD PRSNTFROM CPLD
Thu Sep 14 16:13:10 2023<NAME_1>MB FABCV02GT AMD<NAME_2>136 OF 365
I31P3V3_AUXP3V3_AUX
P3V3_AUXP3V3_AUXP3V3_AUXP3V3_AUX
P3V3_AUXP3V3_AUXP3V3_AUXP3V3_AUX
P3V3_OCP_SFF_R
P3V3_AUXP3V3_AUXP3V3_OCP_SFF_R0402HP_LVC3_OCP_V3_1_PWRGD_R1FM_PLD_OCP_SFF_AUX_PWR_EN SET TO HIGH BY DEFAULT0402LFFM_PLD_OCP_SFF_AUX_PWR_EN1%5%0.1UFCHIPOCP_V3_1_P3V3_R3_PWRGDRST_PERST_OCP_SFF_N0402LFCHIP10KHP_LVC3_OCP_V3_1_P12V_R2_PWRGDHP_LVC3_OCP_V3_1_PWRGD_R2OCP_V3_1_P3V3_PWRGDP12V_OCP_V3_1_PLD_PWRGDCHIPBSS138KBSS138KHP_LVC3_OCP_SFF_PRSNT2P12V_OCP_SFF_EN_R134136134136136134135136248136134136
134 136828281 1331348083134135 80131132
134 13524813413513624825V74LVC1G08W5-7OCP_V3_1_P3V3_PWRGDHP_LVC3_OCP_V3_1_P12V_R2_PWRGD1/16WHP_LVC3_OCP_V3_1_P12V_PWRGD0402LF05%IC0402LFCHIPP12V_OCP_SFF_EN_R31%
05%0402LF1/16W0EMPTY0.1UFP12V_OCP_V3_1_PLD_R_PWRGDSN74LVC1G07DBVROCP_V3_1_P3V3_PWRGDRST_PERST_OCP_SFF_R_N1/16WOCP_V3_1_P3V3_PWRGD0402LFCHIPEMPTYCHIP5%0402LF0402LF0.1UF04025%X7RSMLF10%1/16WCHIPEMPTY1/16WHP_LVC3_OCP_V3_1_P12V_R_PWRGDSMLFAPX809-29SAG-70402LFCHIP00402LF1/16W5%74LVC1G08W5-725V0.1UF10%0402X7RIC33.233.2RST_PERST_OCP_SFF_BUF_N10%33.2CHIP0402LFOCP_SFF_AUX_PWR_EN_R325VIC0402LF0402LFHP_LVC3_OCP_SFF_PRSNT2_N1/16W1K1%SMLF10%X7R0.1UF0402CHIP1/16W0402LF1K05%05%EMPTY
SFF_OCP3.0 HSC(3/3)33.2040225V10%0P12V_OCP_SFF_BUF_EN25VOCP_V3_1_P3V3_PLD_PWRGD OCP_V3_1_P3V3_PLD_R_PWRGD1%CHIPOCP_SFF_AUX_PWR_EN5%1/16WEMPTY0402LF10K5%00.1UFX7RIC0402LF1/16W5%00402LF1/16WCHIP1%1KSMLFCHIP1/16W33.2ICP12V_OCP_SFF_BUF_EN_R74LVC1G08W5-7IC
10KCHIP1/16WCHIP0402LF1%IC0.1UF25V040210%X7RCHIP74LVC1G32GW0EMPTY
25VSMLFOCP_V3_1_P3V3_R2_PWRGDSMLFX7RSMLFX7RCHIPHP_LVC3_OCP_V3_1_P12V_PWRGD040210%CHIP 1/16WSN74LVC1G07DBVRRST_PERST_OCP_SFF_BUF_R_N00402LF
00402LF
1KCHIP 1/16WHP_LVC3_OCP_V3_1_PWRGD0402LFIC1/16WOCP_V3_1_P3V3_R1_PWRGD100K
R9029
R9030
R1519
C9050
C9008
R1144
R1133
R1130
G
S D
4
5
3
2
1
3
2
1
5
4
2
1
3
4
5
13
2
4
5
13
2
4
5
3
2
1
4
5
3
2
1
U9050
U8001
U9002
U30
U28
U23
U24
R9033
U9001
R9031
R9023
R9022
R9034
VCC
Y
GND
B
A
GND
RESET_L
VCC
GND
O
I1
VCC
I0
NC
Y
GND
A
VCC
NC
Y
GND
A
VCC
VCC
Y
GND
B
A
VCC
Y
GND
B
A
21
2 1
21
2
1
2
1
R8092
21R8094
2
1
2
1C8008
2
1
2
1
21
2
1
21
2
1
2
1
2121
2
1
21
21
2
1
2
1
C1059
2
1
21
2
1C9007
21
2 1
2 1
21
21
21
2
1
DESIGN NOTE:
R9032
SHEETDATE
DEPARTMENT
SIZE
PROJECT DOCUMENT NUMBER REV
REVIEWER
DESIGNER
123
7 3 2 1 6 5 4
E
A
B
C
E
D
C
B
A
7 6 5 4
D
IN
OUTIN
OUT
IN
IN OUT
OUTIN
IN
OUT
IN
OUT
OUT
IN
IN
IN
R1518
R1509
R8093
R1145
R1142
C1060
R1143
R1132R1129
C1058
R1134
R1131
R1128
C



P/N SWAPP/N SWAPP/N SWAPP/N SWAPFROM CPU1 PCIE G1 [15:0]P/N SWAPP/N SWAPP/N SWAPP/N SWAPP/N SWAPP/N SWAPP/N SWAPP/N SWAPP/N SWAPP/N SWAPP/N SWAPP/N SWAPTO CPU1 PCIE G1 [15:0]
Thu Sep 14 16:12:25 2023MB FABCGT AMDV02137 OF 365<NAME_2><NAME_1>
OCP_V3_2_ISO_BIF0_EN1/16WP3V3_OCP_V3_2NCSI_OCP_V3_2_CRS_DVNCSI_OCP_V3_2_TXD0NCSI_OCP_V3_2_TXD1139139139138138137138138138IOFM_OCP_V3_2_PWR_GOODOCP_V3_2_MAIN_PWR_EN_R80137
P12V_OCP_V3_2_R
P12V_OCP_V3_2_R
P3V3_OCP_V3_2P3V3_OCP_V3_2P3V3_OCP_V3_2
CLK_100M_CPU1_CLK05_DPCLK_50M_NCSI_OCP_V3_2_ISO1%200CHIP 1/16W0402LFSMB_OCP_V3_2_3V3AUX_BUF_R_SCL SMB_OCP_V3_2_3V3AUX_BUF_SCLCHIP1%2001/16W0402LFCLK_100M_CPU1_CLK03_DNOCP_V3_2_PRSNT2_R_NCLK_100M_CPU1_CLK03_DPP5E_CPU1_G1_RX_DP<15:0>P5E_CPU1_G1_RX_DN<15:0>RST_PERST1_OCP_V3_2_NRST_SMB_OCP_V3_2_NSMB_OCP_V3_2_3V3AUX_BUF_R_SDA139OCP_V3_2_PRSNTA_R_NSMB_OCP_V3_2_3V3AUX_BUF_SDA55491434955CLK_100M_CPU1_CLK05_DN13780138
29140 143140138138675555
80137801378013713780137137142 137 138 139137 80 13880 13767140143
137137808013780137
139
555513813714213813913814014329
2482485513913913813880137 5%0CHIP1/16W0402LFUSB2_CPU0_P10_DN
NCSI_OCP_V3_2_TX_EN
CHIPOCP_V3_2_PRSNT1_R_NNCSI_OCP_V3_2_RXD1NCSI_OCP_V3_2_RXD0IRQ_LVC3_OCP_V3_2_WAKE_NP5E_CPU1_G1_TX_C_DP<15:0>CLK_100M_CPU1_CLK02_DPCLK_100M_CPU1_CLK02_DN0402LF5%OCP_V3_2_ISO1_RBT_ARB_IN
0402X7R10%0.1UF25V0.1UF25V10%X7R04024.7KCHIP1%0402LF1/16W1%CHIP10K0
4.7K1%0402LFEMPTY1/16WCHIP1/16W1%4.7K0402LF0402LF1K1%C080516V20%X6S22UF 22UF16V20%X6SC08050.1UF10%X7R25V040210%25V0402X7R0.1UF10%25VX7R0.1UF040225VX7R10%04020.1UF 0.1UFX7R040210%25V 25V04020.1UF10%X7R04020.1UFX7R10%25V1/16WEMPTY0402LF1%4.7K1/16W1%10K0402LFCHIP000402LF05%
5%01/16WCHIPCHIPSGPIO_OCP_V3_2_LD_NSGPIO_OCP_V3_2_DATAINSGPIO_OCP_V3_2_DATAOUTSGPIO_OCP_V3_2_CLKOCP_V3_2_ID0OCP_V3_2_ID1OCP_V3_2_AUX_PWR_ENFM_OCP_V3_2_PWR_GOODOCP_V3_2_MAIN_PWR_EN
IO_SLOT IO_SLOT10K1%CHIP10K1%1/16W1K1%0402LFIO_SLOT IO_SLOT
1/16W0402LFCHIP1%100KPLACE THE BULK CAPS CLOSE TO SLOTPCIE - V3_2 OCP3.0_X16_CPU1 (1/3)
CHIP0402LF5%05%0402LFP5E_CPU1_G1_TX_C_DN<15:0>OCP_V3_2_PRSNT3_R_NTP_OCP_V3_2_B69
OCP_V3_2_AUX_PWR_EN_ROCP_V3_2_ID0SGPIO_OCP_V3_2_CLKSGPIO_OCP_V3_2_DATAOUTSGPIO_OCP_V3_2_DATAINSGPIO_OCP_V3_2_LD_N
OCP_V3_2_PWRBRK_NUSB2_P10_DPUSB2_P10_DN
CLK_100M_CPU1_CLK04_DNCLK_100M_CPU1_CLK04_DP0402LF5%OCP_V3_2_AUX_PWR_ENOCP_V3_2_ISO_BIF1_ENOCP_V3_2_PRSNT0_R_NTP_OCP_V3_2_B681/16WCHIP5%0402LFUSB2_CPU0_P10_DP0402LF0IO_SLOTSMLFSCONN168_ME1016810202011RST_PERST3_OCP_V3_2_NRST_PERST2_OCP_V3_2_NOCP_V3_2_ID1OCP_V3_2_ISO2_RBT_ARB_OUTOCP_V3_2_BIF2_R_NOCP_V3_2_BIF1_R_NOCP_V3_2_BIF0_R_NRST_PERST0_OCP_V3_2_NOCP_V3_2_ISO_BIF2_ENOCP_V3_2_MAIN_PWR_EN55139
21R3228 21
R3180
R3177
R3178
R3168
R3176
R3175
R3174
OA3
A69
A68
A9
A8
A7
OA6
OB7
B69
B68
OA12OB12
A15B15
OA11OB11
A14B14
OA8
OA9
OA7
OB8
OB9
OB14 OA14
OA5
OA4
A70B70
A12
A42B42
A10
B66
B63
B60
B57
B54
B51
B48
B45
B40
B37
B34
B31
B27
B24
B21
B18
B65
B62
B59
B56
B53
B50
B47
B44
B39
B36
B33
B30
B26
B23
B20
B17
OA2
OA1
A11
B10
A66
A63
A60
A57
A54
A51
A48
A45
A40
A37
A34
A31
A27
A24
A21
A18
A65
A62
A59
A56
A53
A50
A47
A44
A39
A36
A33
A30
A26
A23
A20
A17
OB1
OB2
OB3
OB13
OB10
OA13
OA10
B67
B64
B61
B58
B55
B52
B49
B46
B43
B41
B38
B35
B32
B29
B28
B25
B22
B19
B16
B13
A67
A64
A61
A58
A55
A52
A49
A46
A43
A41
A38
A35
A32
A29
A28
A25
A22
A19
A16
A13
A6
A5
A4
A3
A2
A1
G5
G4
G3
G2
G1
OB5
OB4
OB6
B9
B8
B7
B12
B6
B5
B4
B3
B2
B1
B11
15
12
0
00
1
15
15
14
14
12
11
12
10
11
10
9
8
8
9
7
6
7
6
5
4
5
4
3
2
3
15
14
13
11
12
10
9
13
14
11
8
9
6
4
5
6
5
4
3
2
1
2
3
13
13
2
0
1
1
10
8
7
7
J35
KEY
KEY
KEY
G5
G4
G3
G2
G1
PRSNTB3#
RFU1_NC_B69
RFU1_NC_B68
GND_B67
PETp15
PETn15
GND_B64
PETp14
PETn14
GND_B61
PETp13
PETn13
GND_B58
PETp12
PWRBRK0#
USB_DATp
USB_DATn
GND_A67
PERp15
PERn15
GND_A64
PERp14
PERn14
GND_A61
PERp13
PERn13
GND_A58
PERp12
PERn12
GND_A55
PERp11
PERn11
GND_A52
PERp10
PERn10
GND_A49
PERp9
PERn9
GND_A46
PERp8
PERn8
GND_A43
PRSNTB1#
GND_A41
PERp7
PERn7
GND_A38
PERp6
PERn6
GND_A35
PERp5
PERn5
GND_A32
PERp4
PERn4
GND_A29
GND_A28
PERp3
PERn3
GND_A25
PERp2
PERn2
GND_A22
PERp1
PERn1
GND_A19
PERp0
PERn0
GND_A16
REFCLKp1
REFCLKn1
GND_A13
PRSNTB2#
PERST1#
PRSNTA#
SMRST#
SMDAT
SMCLK
GND_A6
GND_A5
GND_A4
GND_A3
GND_A2
GND_A1
RBT_CLK_IN
GND_OA13
REFCLKp3
REFCLKn3
GND_OA10
RBT_TXD0
RBT_TXD1
RBT_TX_EN
SLOT_ID1
RBT_ARB_OUT
RBT_ARB_IN
WAKE#
PERST3#
PERST2#
PETn12
GND_B55
PETp11
PETn11
GND_B52
PETp10
PETn10
GND_B49
PETp9
PETn9
GND_B46
PETp8
PETn8
GND_B43
PRSNTB0#
GND_B41
PETp7
PETn7
GND_B38
PETp6
PETn6
GND_B35
PETp5
PETn5
GND_B32
PETp4
PETn4
GND_B29
GND_B28
PETp3
PETn3
GND_B25
PETp2
PETn2
GND_B22
PETp1
PETn1
GND_B19
PETp0
PETn0
GND_B16
REFCLKp0
REFCLKn0
GND_B13
AUX_PWR_EN
+3.3V_EDGE
PERST0#
BIF2#
BIF1#
BIF0#
+12V_EDGE_B6
+12V_EDGE_B5
+12V_EDGE_B4
+12V_EDGE_B3
+12V_EDGE_B2
+12V_EDGE_B1
RBT_CRS_DV
GND_OB13
REFCLKp2
REFCLKn2
GND_OB10
RBT_RXD0
RBT_RXD1
SLOT_ID0
CLK
DATA_OUT
DATA_IN
LD#
MAIN_PWR_EN
NIC_PWR_GOOD
2
1
21 21
21
21R3171
21R3170
21R3172
21R3164
2
1
2
1C1838
2
1C1836
2
1C1835
2
1
2
1C1833
2
1C1832
2
1C1831
2
1C1830
2
1C1829
21
21
21R3173
21
2
1
2
1
21R3169
21R8413
21R3165
2
1
2
1C1837
2
1C1834
CAD NOTE:
R3229
SHEETDATE
DEPARTMENT
SIZE
PROJECT DOCUMENT NUMBER REV
REVIEWER
DESIGNER
123
7 3 2 1 6 5 4
E
A
B
C
E
D
C
B
A
7 6 5 4
D
ININ
INOUTIN
OUTOUT
ININ
OUT
OUTIN
OUT
OUT
ININ
OUT
OUT
OUT
OUT
OUT
OUT
OUT
ININ
IN
ININ
IN
IN
OUTOUT
ININ
ININ
OUTOUT
INININININ
ININ
IN
BIIN
IN
INOUT
ININ
OUTOUT
OUT
IN
R3166
C1839
R3167R3163
R3162
C



Thu Sep 14 16:12:24 2023<NAME_1>MB FABC<NAME_2>V02GT AMD138 OF 365
P3V3_AUXP3V3_AUXP3V3_AUX
13981
13713713780137142139137132 150143132 150143132150132 150132 150137137137
137137137137137 132150FB_BMC_ISOLATE1EMPTY1/16W0402LF05%FM_NCSI_OCP_V3_2_R_OE1/16W5%CHIP0402LF0FB_BMC_ISOLATE_R20402LFCHIP1/16W100KSMLFOCP_V3_2_ISO1_RBT_ARB_IN040274CBTLV3126PWNCSI_BMC_RXD1_R1NCSI_OCP_V3_2_TXD1OCP_V3_2_AUX_PWR_EN_R1FM_OCP_V3_2_PWR_GOODX7ROCP_V3_2_AUX_PWR_EN74LVC1G126SE-71%25V0.1UF10%0402ICSMLF74CBTLV3126PW04020.1UF25VX7R10%
1001%1/16W0402LFCHIP CHIP1001%1/16W0402LF1%100CHIP1/16W0402LF
EMPTY00EMPTY0EMPTY22EMPTY22EMPTY1/16W220402LFEMPTY22EMPTYX7R0.1UF25V10%ICSMLF0CHIP
IC33.21%CHIP0402LF1/16WOCP_V3_2_ISO2_RBT_ARB_OUTRMII_OCP_BMC_RXD_1NCSI_BMC_TX_EN_R1OCP_V3_2_RBT_ARB_OUTRMII_BMC_OCP_TXD_1OCP_V3_2_RBT_ARB_INCO-LAYOUTRMII_OCP_BMC_RXD_0NCSI_BMC_TXD0_R1NCSI_BMC_TXD1_R1RMII_BMC_OCP_TX_ENRMII_BMC_OCP_TXD_0OCP_V3_2_ISO_BIF0_ENOCP_V3_2_ISO_BIF1_ENOCP_V3_2_ISO_BIF2_EN
NCSI_OCP_V3_2_TX_ENNCSI_OCP_V3_2_TXD0
PCIE - V3_2 OCP3.0 (2/3)
OCP_V3_2_RBT_ARB_IN_RNCSI_OCP_V3_2_RXD1NCSI_OCP_V3_2_RXD0NCSI_OCP_V3_2_CRS_DVNCSI_BMC_RXD0_R1NCSI_BMC_CRS_DV_R1 RMII_OCP_BMC_CRSDV
R3203
R3217R3216R3208
4
1
2
R3210
R3209
R3211
R3212
R3213
R3214
R3215
53
U286
U223
U222
OE
Y
A
VCC
4OE
4A4B
3OE
3A
GND
1A
2B
1B
2OE
1OE
3B
2A
VCC
4OE
4A4B
3OE
3A
GND
1A
2B
1B
2OE
1OE
3B
2A
GND VCC
21R3205
21R3206
21
2
1
2
1
2
1
2
1
2
1
2
1
2
1
R3207
21
14
7
1311 12
108 9
46 5
13 2
14
7
1311 12
108 9
46 5
13 2
SHEETDATE
DEPARTMENT
SIZE
PROJECT DOCUMENT NUMBER REV
REVIEWER
DESIGNER
74CBTLV3126
74CBTLV3126
123
7 3 2 1 6 5 4
E
A
B
C
E
D
C
B
A
7 6 5 4
D
IN
OUTIN
OUT
OUT
OUT
OUT
IN
IN
IN
IN
OUT
OUT
OUT
IN
IN
IN
IN
IN
OUT
OUT
OUT
OUT
R3244
C1827
C1826
C1825
C



RST FOR OCP V3_2POP
20220120 ADD R4602Thu Sep 14 16:12:26 2023<NAME_2><NAME_1>MB FABCGT AMDV02139 OF 365
74LVC1G17GWP3V3_OCP_V3_2P3V3_AUXP3V3_AUXP3V3_AUXP3V3_AUXP3V3_AUX
P3V3_AUXP3V3_AUXP3V3_AUXP3V3_AUX142
1331381371371421388013224124625125380831331371371551371371371371370000RST_PERST_OCP_V3_2_BUF_NRST_PERST_OCP_V3_2_BUF2_N
CLK_50M_NCSI_OCP_V3_274LVC1G66GVICCLK_50M_NCSI_OCP_V3_2_ISO_RSMLFFB_BMC_ISOLATE1
1/16W0402LFCHIP1%4.7KOCP_V3_2_PWRBRK_BUFF_NIRQ_LVC3_OCP_V3_2_WAKE_NPU_OCP_V3_2_WAKE_OEOCP_V3_2_AUX_PWR_ENRST_SMB_SWITCH_NOCP_V3_2_AUX_PWR_EN_R3FM_SYS_THROTTLE_NNC_U218_NC1OCP_V3_2_WAKE_BUFF_NRST_HP_OCP_V3_2_R_N RST_SMB_OCP_V3_2_NNC_U219_NC1CLK_50M_NCSI_OCP_V3_2_ISOIRQ_LVC3_V3_2_WAKE_BUF_NIRQ_OCP_V3_2_WAKE_BUF_N10K1%1/16W0402LFCHIP0402LF1%10K1/16WCHIP1%33.2CHIP 1/16W0402LF74LVC1G126SE-7SMLFIC10%0402X7R25V0.1UFSMLF74LVC1G126SE-7IC0.1UF10%X7R040225V4.7K0402LF1%1/16WCHIPICSMLF74LVC1G07GV
100K0402LFCHIP1/16W1%1/16W5%CHIP0402LF00402LF 1/16W1%33.225V0.1UFX7R10%0402IC1%1/16W33.2CHIP0402LF0CHIP0402X7R0.1UF10%25V1/16WCHIP0402LF1/16W4.7K1%EMPTY0.1UF25V10%X7R0402PCIE - V3_2 OCP3.0 (3/3)33.21%0402LFOCP_V3_2_PWRBRK_NOCP_V3_2_WAKE_BUFF_R_NCHIP74LVC1G07GVSMLFPLACE R3192 CLOSE TO U219ICSMLFX7R040210%25V0.1UFRST_PERST0_OCP_V3_2_NRST_PERST1_OCP_V3_2_NRST_PERST2_OCP_V3_2_NRST_PERST3_OCP_V3_2_N
21 R6059
21 R6058
21 R6057
21 R6056
R3193
R3185
R3191
R3234
2
1 5
3
4
4
5
13
2
4
51
3
2
4
51
3
2
4
1
2
4
1
2
5353
U321
U207
U219
U218
U217
U225
OE
Y
A
VCC
E
GND
Z
Y
NC
Y
GND
A
VCC
NC1
YGND
A
VCC
NC1
YGND
A
VCC
OE
Y
A
GND VCCGND VCC
2
1
21
21R4602
2
1
R3190
21
21R3236
2
1
2
1
2
1
2
1
R3182
2
1
2
1
2
1
21
2
1
2
1
R3235
2
1
21
CAD NOTE:
R3183
SHEETDATE
DEPARTMENT
SIZE
PROJECT DOCUMENT NUMBER REV
REVIEWER
DESIGNER
123
7 3 2 1 6 5 4
E
A
B
C
E
D
C
B
A
7 6 5 4
D
OUT
OUT
IN
OUT
OUT
IN
OUT
IN
OUT
IN
OUT
OUT
IN
IN
IN
C1821
R3184C1822
C38
R3192
C1824
C1823
C1841
C



OCP=IMAX*1.3=8.58AFROM PRSNT BUFFERFROM PRSNT BUFFERUVP: 10.17VOVP: 14.91VSTART UP TIME:8.21MSSTART UP TIME:3.94MSFROM CPLDVIMON(MAX)= 1.679V @ IOUT=9.03A
IMAX=6.6AOCP=IMAX*1.3=1.43AP12V_OCP_V3_2P3V3_OCP_V3_2_RDESIGN SPECIFICATIONIMAX=1.1AOVP: 3.89VUVP: 2.63VVIMON(MAX)= 1.594V @ IOUT=1.6A
Thu Sep 14 16:12:26 2023<NAME_2><NAME_1>MB FABCGT AMDV02140 OF 3650402LF 0402LFP3V3_AUXIC0402LFCHIP1/16W1%1KP3V3_AUXV3_2_OCP3.0 HSC(1/3)137NIC_P12V_MAM_TIC_BOM1P3V3_AUXP12V_AUXP3V3_AUXP3V3_OCP_V3_2_R
P3V3_AUXP3V3_AUXP3V3_AUXP12V_AUXP3V3_AUXP12V_OCP_V3_2P12V_AUX14014114224881831412481421401412481421401412488183141142 141 140 142248142
801371431371431431371431422582585%0CHIPNIC_P3V3_BOM1HP_LVC3_OCP_V3_2_P12V_PWRGDNIC_P3V3_BOM1P3V3_OCP_V3_2_EN_RP12V_OCP_V3_2_BUF_EN_RP12V_OCP_V3_2_BUF_EN_RNIC_P3V3_BOM1CHIPNIC_P12V_MAM_TIC_BOM10402LFP12V_OCP_V3_2_EN_REMPTY10KPJT138KSMLFNIC_P12V_MAM_TIC_BOM1P12V_OCP_UV_2_RC0402CHIP1/16WC0402NIC_P12V_MAM_TIC_BOM10402LF6.8K1/16WCHIP0402LFNIC_P12V_MAM_TIC_BOM1NIC_P12V_MAM_TIC_BOM1EMPTY 3900PFNIC_P12V_MAM_TIC_BOM150V1/16WCHIP1%ICC0402NIC_P12V_MAM_TIC_BOM1101%1/16WNIC_P12V_MAM_TIC_BOM1CHIP0402LFP12V_OCP_UV_2P12V_OCP_REG_2P12V_OCP_OV_2P12V_OCP_CB_2NIC_P12V_MAM_TIC_BOM1NIC_P12V_MAM_TIC_BOM11/16WCHIPCHIP1%1/16W30.1K0402LF50VHP_LVC3_OCP_V3_2_P12V_PWRGDNIC_P12V_MAM_TIC_BOM10402LF0402LFCHIP05%0402LF8451/16W0402LFNIC_P12V_MAM_TIC_BOM1R3867/R3868 CO-LAYOUTCHIP0402LFCHIP0NIC_P12V_MAM_TIC_BOM11%C0805NIC_P3V3_BOM1NIC_P3V3_BOM1PJT138KSMLFP3V3_OCP_UV_2_R1CHIP0NIC_P3V3_BOM11/16W5%0402LFNIC_P3V3_BOM1C04021%NIC_P3V3_BOM1CHIPNIC_P3V3_BOM1NIC_P3V3_BOM16800PFNIC_P3V3_BOM1P3V3_OCP_GATE_2P3V3_OCP_OV_20402LF1%15KC0402NIC_P3V3_BOM1C040225VX6SNIC_P3V3_BOM1101%CHIP1UFNIC_P3V3_BOM10402LF1/16WP3V3_OCP_SENSE_2P3V3_OCP_FAULT_20402LFEMPTY100K1/16WCHIP0402LFOCP_V3_2_P3V3_PWRGD1%10M1/16W040250V0.01UFB340A-13-FX6S16V10UF25VC0805
0CHIP5%0402LF1/16W1K0402LF1%1/16WCHIP05%EMPTYEMPTY0 100K1/16WEMPTY1%0402LF
1/16WCHIP1K1%1K1%1/16WCHIP1/16W1%ICICSMLF74LVC2G07DW-70.1UF25V10%0402X7RSMLFIC74LVC2G07DW-70.1UF25V0402X7R10%15K0402LF1%1K1%1/16W
1%ICSMF14A1UF25VX6SCHIP1/16WC040225V1UF1/16W0402LF25.5K1%
0402LF1/16WCHIP05%CHIP0402LFCHIP1/16W1%0402LF1K5%0100K1/16W1%CHIP1/16WCHIP5.36K1%IC4.53K1%CHIP25VX6S16VC0805HP_LVC3_OCP_V3_2_PRSNT2_PLD_NOCP_V3_2_PRSNT1_R_NOCP_V3_2_PRSNT0_R_NHP_LVC3_OCP_V3_2_PRSNT2_N_ROCP_V3_2_PRSNT3_R_NOCP_V3_2_PRSNT2_R_NHP_LVC3_OCP_V3_2_PRSNT2_N
X7R0.1UF 10UF16VX6SC0402P3V3_OCP_PWRGD_20402LF05%NIC_P3V3_BOM1EMPTY1/16WNIC_P3V3_BOM150VMAX15090BEWI+TCHIPX6S0402LFNIC_P3V3_BOM1SMLF1/16WNIC_P3V3_BOM1NIC_P3V3_BOM125V1UF1%CHIP7.15KP3V3_OCP_CB_2P3V3_OCP_VCC_2P3V3_OCP_REG_2P3V3_OCP_UV_2NIC_P3V3_BOM11/16W0402LFNIC_P3V3_BOM1SMLFNIC_P3V3_BOM1IC4.7K5%1/16W0402LF0402LFP3V3_OCP_2_EN_GNIC_P3V3_BOM11/16W100K22UF0402LF0.1UFP12V_OCP_GATE_2ICB340A-13-FX7R1/16WP12V_OCP_V3_2_ISENSE_MAM_MAM5%P12V_OCP_V3_2_ISENSE_MAM_TICEMPTY0402LFC04020402LF1/16WNIC_P12V_MAM_TIC_BOM1CHIP0402P12V_OCP_FAULT_2P12V_OCP_SENSE_2P12V_OCP_PWRGD_225VC04021UFX6SNIC_P12V_MAM_TIC_BOM1SMLFMAX15090BEWI+TNIC_P12V_MAM_TIC_BOM11/16W1%1UFP12V_OCP_VCC_225V1%0402LF1%160KCHIP1/16W10M0.01UF1/16WNIC_P12V_MAM_TIC_BOM1CHIPIC5%0NIC_P12V_MAM_TIC_BOM1NIC_P12V_MAM_TIC_BOM1P12V_OCP_2_EN_G5%CHIPNIC_P12V_MAM_TIC_BOM14.7K5%1/16W0402LFSMLFPJT138KNIC_P12V_MAM_TIC_BOM1P12V_OCP_EN_2_RNIC_P12V_MAM_TIC_BOM1PJT138K0EMPTY5%P3V3_OCP_EN_2_R10K05%EMPTY
G2
G1
G2
G1
CAS2 D2D1S1S2 D2D1S1
PC2149
C40
PR3829
PD107
R1182
R3826
R3832
R1181
R4060
R4059
R1191
PC2137
PC2151
PR3782
R3816
R3831
PC2150
PC2140
R3807
PR3828
R4065
R3833
PC2141PC2152
PR3824
C39
PR3822
PC2147
PR3830
R3825
21 R3868
PR3823
PC2146
PC2098
PR3821
R3142
PR3795
PR3812
PC2139
R4067
PR3805
PR3806
PC2142
52
43
61
PC2143
A2
D2
D1 D7
D3
D6
D4
C6
C4
B6
B4
A4
A1
D5
C5
C3
B5
B3
A5
A3
C2
C1
B2
A6
C7
B7
A7B1
A2
D2
D1 D7
D3
D6
D4
C6
C4
B6
B4
A4
A1
D5
C5
C3
B5
B3
A5
A3
C2
C1
B2
A6
C7
B7
A7B1
5
2
52
43
61
5
2
4 31 64 31 6
PD109
U59
PD108
PU200
PU201
Q119
Q119
U58
Q118
Q118
PG
FAULT#
GND_C2
GND_C1
GND_B2
CDLY
GATE
OUT_D6
OUT_D4
OUT_C6
OUT_C4
OUT_B6
OUT_B4
OUT_A4
ISENSEOV
UV
REG
EN#
CB
IN_D5
IN_C5
IN_C3
IN_B5
IN_B3
IN_A5
IN_A3
VCC
PG
FAULT#
GND_C2
GND_C1
GND_B2
CDLY
GATE
OUT_D6
OUT_D4
OUT_C6
OUT_C4
OUT_B6
OUT_B4
OUT_A4
ISENSEOV
UV
REG
EN#
CB
IN_D5
IN_C5
IN_C3
IN_B5
IN_B3
IN_A5
IN_A3
VCC
VCCGND
2Y
1Y
2A
1A
VCCGND
2Y
1Y
2A
1A
CACA
21
21
2
1
21
21
21
2
1
2
1
21
2
1
21
2
1
2
1
2
1
2
1
21
2
1
PR4522
2
1
2
1
21
2
1
2
1
2
1
2
1
2
1
2
1
2
1
2
1
2
1
2
1
2
1
2
1
2
1
21
2
1
2
1
2
1
2
1
21
2
1
2
1
2
1
2
1
2
1
21
2
1
2
1
2
1
CAD NOTE:
21212121
R4066
R6060
CACA
CA
SHEETDATE
DEPARTMENT
SIZE
PROJECT DOCUMENT NUMBER REV
REVIEWER
DESIGNER
123
7 3 2 1 6 5 4
E
A
B
C
E
D
C
B
A
7 6 5 4
D
OUT
OUT
OUT
OUT
IN
IN
IN
IN
IN
IN
IN
OUT
OUT
IN
IN
R1520
R1192
C1809
C1810
R3134
PR4523
R3867
R3147
R3827
R3135R3133
R3136
C



2ND SOURCE OF PU201PR3853PR3850DE-POPMP5025C/DE-POPDE-POPPOPMP5022CTFAULT: 1.27MSTDELAY: 6.29MS
OCP=IMAX*1.3=1.43AIMAX=1.1AP3V3_OCP_V3_2_ROCP=IMAX*1.3=8.58AIMAX=6.6ADESIGN SPECIFICATION
ENABLE:POPVIMON(MAX)= 1.582V @ IOUT=9.09APOPDE-POPPC1320CURRENT LIMIT=1.6APU206 OPTIONAL BOMVTH>1.391V(HIGH)FROM PRSNT BUFFERFROM CPLDMP5022APOPPOP DE-POPMP5025A/2ND SOURCE OF PU200PR3852PR3857START UP TIME:8.62MS
START UP TIME:4.7MSP12V_OCP_V3_2
Thu Sep 14 16:12:26 2023GT AMD141 OF 365V02MB FABC<NAME_1><NAME_2>P3V3_AUX
P3V3_OCP_V3_2_R
P12V_AUX
P3V3_AUX
P3V3_AUXP12V_OCP_V3_2P12V_AUXNIC_P12V_MPS_MAM_BOM2HP_LVC3_OCP_V3_2_P12V_PWRGDICSMLFRS31312RNIC_P12V_MPS_MAM_BOM2P12V_OCP_AVIN_PD_2P12V_OCP_OV_FB_2P12V_OCP_FLTB_2P12V_OCP_IMON_2P12V_OCP_V3_2_EN_2_R3P12V_OCP_TIMER_2P12V_OCP_ISET_2P12V_OCP_SS_21%1/16WNIC_P12V_MPS_MAM_BOM2NIC_P12V_MPS_MAM_BOM210KNIC_P12V_MPS_MAM_BOM2142040250VNPO39PFNIC_P3V3_BOM2142140141248140141142248
8183140142142140141248 258258141141140141248
81831402480NIC_P3V3_BOM25%CHIPP12V_OCP_V3_2_BUF_EN_RHP_LVC3_OCP_V3_2_P12V_PWRGD
P12V_OCP_V3_2_EN_REMPTYX7R16V0.22UF05%P12V_OCP_V3_2_BUF_EN_R040220%1%120K1%1%1/16W49.9100EMPTY
1%1.33KC04021%0402LFP3V3_OCP_GATE_PU207_2040210%X6S100PF
V3_2_OCP3.0 HSC-CO-LAYOUT(2/3)25VC0402NPO5%
50V0402IC
10%1/16W04020402LF25V1UFX6SX7RNIC_P3V3_BOM2C0805X6SNIC_P3V3_BOM2X7RSMLFNIC_P3V3_BOM2NIC_P3V3_BOM2CHIP0402LF71.5KCHIPNIC_P3V3_BOM2MP5016GQH-L-Z25VNIC_P3V3_BOM216V0.068UFP3V3_OCP_DVDT_2P3V3_OCP_ILIMIT_2P3V3_OCP_MODE_2CHIP10K71.5K1/10W0603LF16V1/16W1%CHIPNIC_P12V_MPS_MAM_BOM2CHIPCHIP2.2UF0402LF1%0402LFNIC_P12V_MPS_MAM_BOM250V0402LFCHIP1%10K1/16WEMPTY1%CHIP1/16W0402LF0402LF5%0CHIPC0402NIC_P12V_MPS_MAM_BOM21%14.3K0.047UFX7R0402LFNIC_P12V_MPS_MAM_BOM2CHIPNIC_P12V_MPS_MAM_BOM2NIC_P12V_MPS_MAM_BOM2
P3V3_OCP_V3_2_EN_REMPTY05%NIC_P3V3_BOM21UFP3V3_OCP_EN_2NIC_P3V3_BOM205%EMPTYNIC_P3V3_BOM2
01/16WNIC_P12V_MPS_MAM_BOM25%R3873/R3874 CO-LAYOUTX7R1/16WNIC_P12V_MPS_MAM_BOM2NIC_P12V_MPS_MAM_BOM217.4K0402LFCHIP0.1UF0402P12V_OCP_V3_2_ISENSE_MPS_MAM1/16WEMPTY05%0402LFP12V_OCP_V3_2_ISENSE_MPS_TICNIC_P12V_MPS_TIC_BOM3C0603NIC_P12V_MPS_MAM_BOM20402LFNIC_P12V_MPS_MAM_BOM2P12V_OCP_AVIN_PD_2X7R25VNIC_P12V_MPS_MAM_BOM210%16V10UF
100PFNIC_P12V_MPS_MAM_BOM2NIC_P12V_MPS_MAM_BOM2
R3848
R3873
R3874
R1196
R3631
R3630
PC2169
PR3856
PC2174
PR3857PR3853
PC1320PR3854
PR3851
PR3849
PR3847
20
19
18
17
16
15
14
13
26
25
24
23
21_22
4
6
10
11
2
5
87
9
3
1
12
PU206
PC1322
PU207
PC1321PR3855PC2168
PR3852
GND
SS
ISET
TIMER
ENTM
LOADEN
EN
VIN_26
VIN_25
VIN_24
VIN_23
IMON
FLTB
PG
OV
VOUT_13
AVIN
VOUT_14
VOUT_15
VOUT_16
VOUT_17
VOUT_18
VOUT_19
VIN_21_22
VOUT_20
SOURCE
GATE
DV_DT
VCC
GND
ILIMIT
MODE
EN
21
21
21R1193
21
21
2
1
PC2173
2
1
2
1
2
1
2
1
2
1
21
21
2
1
PC2165
PC2166
2
1
CAD NOTE:PC2167
1_2 6_7
54 3
8
9
10
PC2164
SHEETDATE
DEPARTMENT
SIZE
PROJECT DOCUMENT NUMBER REV
REVIEWER
DESIGNER
123
7 3 2 1 6 5 4
E
A
B
C
E
D
C
B
A
7 6 5 4
D
IN
IN
IN
IN
OUT
IN
OUT
IN
OUT
OUT
R1521
PR3850
C



OPEN DRAINTO OCP_12V_HSC ENPUSH PULLFROM CPLDOCP CARD PRSNTPUSH PULLOPEN DRAINPUSH PULLP3V3_OCP_V3_2 PWRGDPUSH PULL OUTPUTThu Sep 14 16:13:10 2023<NAME_2><NAME_1>MB FABCGT AMDV02142 OF 365
I24P3V3_AUXP3V3_AUXP3V3_AUX
P3V3_AUXP3V3_AUXP3V3_AUXP3V3_AUXP3V3_AUXP3V3_AUXP3V3_OCP_V3_2_RP3V3_AUXP3V3_OCP_V3_2_RP3V3_AUXP3V3_AUX8180140142142 140 1412481408183140141 8014014213980 137 138 139140141142248140 1421401411422481421401420.1UF1/16WCHIPRST_PERST_OCP_V3_2_NEMPTY5%00.1UF25V04020402LFP12V_OCP_V3_2_PLD_PWRGDSMLF040210%25VOCP_V3_2_P3V3_PWRGDHP_LVC3_OCP_V3_2_P12V_PWRGD_R2P12V_OCP_V3_2_BUF_EN_RP12V_OCP_V3_2_BUF_ENHP_LVC3_OCP_V3_2_PRSNT2_NP12V_OCP_V3_2_EN_R3HP_LVC3_OCP_V3_2_PRSNT2P12V_OCP_V3_2_EN_ROCP_V3_2_P3V3_PLD_R_PWRGDOCP_V3_2_P3V3_PWRGDRST_PERST_OCP_V3_2_BUF_NFM_OCP_V3_2_AUX_PWR_EN SET TO HIGH BY DEFAULTHP_LVC3_OCP_V3_2_PWRGD_R1FM_OCP_V3_2_AUX_PWR_R_ENOCP_V3_2_AUX_PWR_ENOCP_V3_2_AUX_PWR_EN_R2OCP_V3_2_P3V3_R2_PWRGDHP_LVC3_OCP_V3_2_P12V_PWRGDHP_LVC3_OCP_V3_2_P12V_R_PWRGDSMLFICSMLFIC1/16WCHIP1%1K0402LF0402LF5%1/16W0402LF1/16W5%CHIP010%X7R5%1/16WEMPTY10K0402LF0402LF33.2CHIPSMLFSN74LVC1G07DBVRIC
CHIP0402LF33.274LVC1G32GWSMLFIC
10%X7R040225V0.1UF5%0CHIP 1/16WCHIP1/16W1%1K0402LF74LVC1G08W5-7ICSMLF0402LF1/16WCHIP1K1%BSS138KBSS138KIC1KCHIP0402LF1/16WCHIP05%1/16W0402LF33.2CHIP0402LF33.210%25V04020.1UFX7R0402LFCHIP33.2CHIP1%0.1UF0402X7R25V10%00402LF5%EMPTYCHIP5%01%IC0.1UF25VX7R10%0402100K1/16WCHIP0402LFV3_2_OCP3.0 HSC(3/3)
OCP_V3_2_P3V3_PLD_PWRGD0CHIP1%HP_LVC3_OCP_V3_2_PWRGDOCP_V3_2_P3V3_R1_PWRGD0402LFSMLF0402LF0EMPTY0EMPTYICRST_PERST_OCP_V3_2_R_N0402LF74LVC1G08W5-70402X7R10%0.1UF25VRST_PERST_OCP_V3_2_BUF_R_NSN74LVC1G07DBVR
OCP_V3_2_P3V3_PWRGD1/16WAPX809-29SAG-7HP_LVC3_OCP_V3_2_P12V_PWRGD5%10K1/16WOCP_V3_2_P3V3_R3_PWRGDX7RHP_LVC3_OCP_V3_2_P12V_PWRGD_R2CHIPHP_LVC3_OCP_V3_2_PWRGD_R274LVC1G08W5-70402LFCHIP 1/16W05%5%0CHIP5%00402LF1/16WP12V_OCP_V3_2_PLD_R_PWRGD0402LF1/16W10KEMPTYOCP_V3_2_P3V3_PWRGD
R1146
R1147
R1525
R1171
R1164
R1167
C1065
G
S D
4
5
3
2
1
3
2
1
4
5
13
2
4
5
3
2
1
4
5
13
2
5
4
2
1
3
4
5
3
2
1
U9051
U8002
U33
U35
R1177
U34
R1175
U37
U31
U32
R1174
R1173
R1178
VCC
Y
GND
B
A
GND
RESET_L
VCC
NC
Y
GND
A
VCC
VCC
Y
GND
B
A
NC
Y
GND
A
VCC
GND
O
I1
VCC
I0
VCC
Y
GND
B
A
21
21
21
2
1C9051
2
1
R8095
21R8097
2
1
2
1C8009
2
1
21
21
2
1
2
1
21
2
1C1064
21
2 1
2 1
2
1
C1062
21
2
1
21
2
1
2
1
21
21
21
2
1
21
2
1
2
1
21
DESIGN NOTE:
R1176
SHEETDATE
DEPARTMENT
SIZE
PROJECT DOCUMENT NUMBER REV
REVIEWER
DESIGNER
123
7 3 2 1 6 5 4
E
A
B
C
E
D
C
B
A
7 6 5 4
D
IN
IN
OUTIN
IN
OUT
IN
OUT
OUT
OUT
OUT
IN
IN
IN
OUT
IN
IN
R1524
R1523
R8096
R1170
R1168
C1063
R1172
R1169
R1165
R1149
R1166
C1061
R1163
C



Thu Sep 14 16:12:27 2023<NAME_2><NAME_1>MB FABCGT AMDV02143 OF 365
74LVC2G08DPOCP_V3_2_PRSNT01_R1_NP3V3_AUXP3V3_AUXP3V3_AUXP3V3_AUXP3V3_AUXP3V3_AUXP3V3_AUX137140131134131134143137140 13813214314313813214313113413113413714013714074LVC2G08DP1/16WOCP_V3_2_PRSNT23_R1_N10%EMPTY25V0.1UF0402LF5%0402LFEMPTY0402EMPTY10%25V0.1UFOCP_SFF_PRSNT23_R1_N0402LF00402LFEMPTYOCP_SFF_PRSNT01_R_NSMLF10%X7ROCP_V3_2_PRSNT01_R_N5%EMPTYOCP_V3_2_PRSNT23_R_N
1/16W74LVC2G08DPOCP_SFF_PRSNT_ALL_R_NOCP_V3_2_PRSNT_ALL_R_NOCP_V3_2_PRSNT1_R_N74LVC2G08DP25V10%OCP_SFF_PRSNT1_R_NOCP_SFF_PRSNT0_R_N5%OCP_SFF_RBT_ARB_IN_MUX21/16W0OCP_V3_2_PRSNT0_R_NNC7SB3157P6XEMPTYNC7SB3157P6XEMPTYEMPTYNC7SB3157P6XEMPTYX7R10%25V0.1UF25V0402X7R10%0.1UFX7R10%25V0.1UF040225V0402X7R10%0.1UF25V10%CHIP05%1/16W0402LFCHIP01/16W5%0402LFCHIP1/16W5%CHIP0402LF00402LF 1/16W5%0CHIP0402LF5%CHIP01/16WOCP_V3_2_NOT_PRSNT_RBT_ARB_INOCP_V3_2_PRSNT_ALL_R1_NOCP_SFF_PRSNT_ALL_R3_NOCP_SFF_RBT_ARB_IN_MUX1_ROCP_V3_2_RBT_ARB_OUTOCP_SFF_NOT_PRSNT_RBT_ARB_INOCP_SFF_RBT_ARB_INOCP_SFF_RBT_ARB_IN_MUX2 OCP_SFF_RBT_ARB_IN_MUX2_ROCP_V3_2_PRSNT_ALL_R3_NOCP_SFF_RBT_ARB_IN_MUX1OCP_SFF_PRSNT_ALL_R1_N
OCP_V3_2_RBT_ARB_INOCP_SFF_RBT_ARB_OUT
OCP3.0 NCSI
OCP_SFF_RBT_ARB_IN_MUX10402LF25VSMLFSMLFEMPTYOCP_SFF_PRSNT2_R_NOCP_SFF_PRSNT3_R_NOCP_V3_2_PRSNT3_R_NOCP_V3_2_PRSNT2_R_N0402NC7SB3157P6X0.1UF04020.1UFEMPTYEMPTY5%01/16W00EMPTY04020.1UFX7RX7REMPTY74LVC2G08DPOCP_SFF_PRSNT23_R_N1/16W5%EMPTY040225V0.1UFOCP_SFF_PRSNT01_R1_N0.1UF25V040204020402EMPTY74LVC2G08DPSMLF10%EMPTY10%EMPTYSMLF
R3307
R3306
R3308
21
21
R3305
R3304
R3303
C1878
C1877
C1879
C1880
5
6
2
1
34
5
6
2
1
34
5
6
2
1
34
5
6
2
1
34
S
B0
B1
VCC GND
A
S
B0
B1
VCC GND
A
S
B0
B1
VCC GND
A
S
B0
B1
VCC GND
A
3
6
5
7
2
1
3
6
5
7
2
1
3
6
5
7
2
1
848484
U245
U246
U244
U243
U242
U242
U240
U240
U241
U241
2Y
2B
2A
2Y
2B
2A
1Y
1B
1A
2Y
2B
2A
1Y
1B
1A
1Y
1B
1A
GND VCCGND VCCGND VCC
2
1
2
1
2
1C8002
2
1
21R8016
21R8015
R8014
R8013
21
21
21
21
21
21
2
1
2
1
2
1
2
1
2
1
2
1
2
1
C8001
SHEETDATE
DEPARTMENT
SIZE
PROJECT DOCUMENT NUMBER REV
REVIEWER
DESIGNER
123
7 3 2 1 6 5 4
E
A
B
C
E
D
C
B
A
7 6 5 4
D
IN
IN
IN
IN
IN
OUT
OUTIN
OUT
IN
IN
OUT IN
IN
IN
IN
C8004
C8003
C1876
C1874
C1875
C



TO SCM HDD ACTIVITY LEDThu Sep 14 16:12:27 2023GT AMDMB FABC<NAME_2>V0201010101144 OF 365<NAME_1>25V10%5%CHIP74LVC1G126SE-7SMLFICPJT138KSMLFHDD_ACTIVITY_BUF_N1/16WPCIE_M2_SSD0_PRSNT_NP3E_CPU1_P4_RX_DP<0>20%
0402LFLED_M2_SSD_0_ACT_NNC_M2_0_NC1SMB_M2_P1_1V8AUX_SCLP3E_CPU1_P4_TX_C_DP<0>LED_HDD_ACTIVITY_NPU_BUFFER_HDD_ACTIVITYNC_M2_0_NC4NC_M2_0_NC310K
RST_PERST_BUF_M2_0_NCHIP1/16W4.7KCHIP1/16W0402LF33.2
NC_Q95_G2PJT138KNC_Q95_D2SMLFICICRST_PERST_BUF_M2_0_R_NNC_Q95_S20402LF
04.7KCHIP1%CHIP1/16W05%CHIP1/16W5%01UF10%CHIP
1%CHIP
SMLF25VX6S4.7K
EMPTY0402LF5%0402LF
1%1%CHIP1/16WCHIP0402LF10K01/16W0402LF5%
CHIP1%0402LF1K1%1/16WCHIPPD_M2_0_DEVSLPC0603X6S22UF6.3V 6.3VX6SC06036.3V20%22UF040210%X7R0.1UF25V10%25VX7R0.1UF04020.1UFX7R040225V10%
C0402ICCHIP1/16W1%0402LF1K0402HDD_ACTIVITY_BUF
CLK_100M_CPU1_CLK12_DNNC_M2_0_NC6NC_M2_0_NC7NC_M2_0_NC9SMB_M2_P1_1V8AUX_SDANC_M2_0_NC14NC_M2_0_NC15NC_M2_0_NC16NC_M2_0_NC17NC_M2_0_NC10NC_M2_0_NC2FM_M2_SSD_0_PEDETNC_M2_0_NC19P3E_CPU1_P4_TX_C_DN<0>P3E_CPU1_P4_RX_DN<0>NC_M2_0_NC18LED_M2_SSD_0_ACT_N
CPU1 - M.2 - 0 CONN (EMPTY)RST_PERST_M2_0_NM2_SSD0_CLKREQ_EN_N
CLK_100M_CPU1_CLK12_DPM2_0_PEWAKE_NNC_M2_0_SUSCLKP3E_CPU1_P4_TX_C_DP<3:1>P3E_CPU1_P4_TX_C_DN<3:1>P3E_CPU1_P4_RX_DP<3:1>1%M2_SSD0_CLKREQ_EN_NPD_M2_0_DEVSLPNC_M2_0_NC8NC_M2_0_NC111/16WEMPTY
15085805314414867144144144144551486753144
838182 144
55144155676753144 8214453P3E_CPU1_P4_RX_DN<3:1>1%RST_PERST_BUF_M2_0_R_NM2_SSD0_CLKREQ_EN_N_BUFM2_0_PEWAKE_R_N1/16W1/16W1KEMPTYP3V3_AUXP3V3_AUXP3V3_AUXP3V3_AUX
P3V3_AUXP3V3_M2_0SMLFSCONN75K_APCI0155-P004A0402LF20%X6SC0603P3V3_M2_022UF
PU_BUFFER_HDD_ACTIVITY0.1UFX7R0402LFLED_HDD_ACTIVITY_B_NP3V3_AUX10KP3V3_AUXSN74LVC2G07DCKR1%4.7KP3V3_M2_00402LFNC_M2_0_NC5P3V3_AUX
G2
G1
S2 D2D1S1
R3301
KEY M
R1396
R155
R2113
R2121
5
4
1
2
2
52
43
61
1
1
1
3
1
2
2
3
3
2
3
2
4 3531 6
Q95
R5377
U239
Q95
U259
J59
REFCLKP
REFCLKN
PETP1
PETN1
PERP1
PERN1
PETP2
PETN2
PERP2
PERN2
PETP3
PETN3
PERP3
PERN3
GND10
GND9
GND8
GND7
GND6
GND5
GND4
GND3
GND2
GND1
NC4
NC5
NC6
NC7
NC8
NC9
NC11
NC12
NC13
NC14
NC15
NC16
NC17
NC10
NC3
NC2
NC1
G2
G1
GND14
GND13
GND12
PEDET
NC19
GND11
PETP0||SATA-A+
PETN0||SATA-A-
PERP0||SATA-B-
PERN0||SATA-B+
3.3V_9
3.3V_8
3.3V_7
SUSCLK
NC18PEWAKE#
CLKREQ#
PERST#
DEVSLP
3.3V_6
3.3V_5
3.3V_4
3.3V_3
DAS_DSS#||LED1#
3.3V_2
3.3V_1
OE
Y
A
VCCGND
2Y
1Y
2A
1A
GND VCC
2
1
2
1
2
1
2
1
2
1
2
1
2
1
21
2
1
2
1
2
1
2
1
2
1
2121R153
2
1
R178
2
1
21
2
1
21
2
1
2
1
68
5553
54
13
25
37 49
11
23
35 47
50
7
19
31 43
5
17
29 41
69
675856484644424036343230282624222086
7573715751453933272115931
G2G1
38 10
52
7472701816141242
SHEETDATE
DEPARTMENT
SIZE
PROJECT DOCUMENT NUMBER REV
REVIEWER
DESIGNER
123
7 3 2 1 6 5 4
E
A
B
C
E
D
C
B
A
7 6 5 4
D
OUT
OUT
OUTOUT
ININ
OUT
BIIN
OUT
ININ
OUTOUT
IN
ININ
IN
OUT
IN
IN
IN
OUTOUT
OUT
IN
C1925C1924C1923
R1605
C9922C1921C1920
R3297
R3298
C1873
R3296
R3295
R3294
R138
C2007
C



RX[3:0] PN SWAPTX[2:0] PN SWAP
Thu Sep 14 16:12:36 2023<NAME_2><NAME_1>MB FABCGT AMDV02145 OF 365
DP/DN SWAP TX[0:1] RX[0]P12V_E1S_0_RP3V3_E1S_0P12V_E1S_0_RP3V3_E1S_0P3V3_E1S_0
P3V3_AUX
P3V3_E1S_0P3V3_AUXP3V3_E1S_0P3V3_E1S_0P3V3_AUX
1451458083 80 821481482626
148
145676728
8580
288183145145145
IORST_SMB_E1S_0_NFM_LED_ACTIVE_E1S_0_BUFE1S_0_PERST1_CLKREQ_NE1S_0_PRSNT_NSMB_E1S_3V3AUX_ISO_SCLSMB_E1S_3V3AUX_ISO_SDATP_CLK_100M_E1S_0_DNTP_CLK_100M_E1S_0_DPP3E_CPU0_P4_RX_DP<3:0>P3E_CPU0_P4_RX_DN<3:0>SCONN56_1-2327679-3SMLF1/16W0402LFCHIP10K1%PLACE THE BULK CAPS CLOSE TO SLOTIO_SLOT
SMB_PCIE_E1S_ISO_ENCHIP
1%0402LF5%1/16WE1S_0_PWRDISP3E_CPU0_P4_TX_C_DP<3:0>P3E_CPU0_P4_TX_C_DN<3:0>CLK_100M_CPU0_CLK12_DNRST_PCIE_E1S_PERST_N
FM_SMB_RST_E1S_0_R_NFM_LED_ACTIVE_E1S_0CHIP0FM_LED_ACTIVE_E1S_0_R_BUFCHIP00402LF1/16W4.7KCHIP5%CHIP4.7K0402LF1/16W5%
CLK_100M_CPU0_CLK12_DPIO_SLOTPU_E1S_0_DUALPORT_EN_NRST_PERST_E1S_0_N1/16W0402LF
FM_LED_ACTIVE_E1S_0_R1/16WSMLF04020.1UFX7R
1%
05%CHIP
1%1/16WCHIP0402LF10KCHIP0
0402X7R0.1UF25V10%5%01/16WCHIP5%00402LF0402LF4.7KCHIP5%20%C0805X6S22UF20%X6SC080516V040225V0.1UF10%X7R10%X7R25V0.1UF040210%X7R04020.1UF25V10%0402X7R25V0.1UF
RST_SMB_E1S_N
E1S_0_PWRDIS
RST_SMB_BUF_E1S_0_NSMB_PCIE_E1S_ISO_EN_R2SMLFIC74LVC2G07DW-71KCHIP1/16W0402LF1%IO_SLOT10K1000402LFEMPTY1/16W1%IO_SLOTIO_SLOT
CPU0 - E1S - 0 CONNIC
CHIPTP_E1S_0_MFGTP_E1S_0_RFU
25V74LVC1G17GW10%FM_LED_ACTIVE_E1S_0_BUF
CHIP1/16W0402LF10K
4.7K5%0402LF1/16WEMPTYRST_SMB_E1S_0_N
16V22UF
2
1
R1000
21
R1038
2
1
C508
4
5
13
2
U44
2
1
R999
21
R955
R3773
R1673 R10287
R2426
R2125
R3772
R2114
R3779
A9
A8
A7
B8
A15B15
A14B14
B12 A12
B27
B24
B21
B18
B26
B23
B20
B17
A11
B10
A27
A24
A21
A18
A26
A23
A20
A17
B6
B5
B4
B3
B2
B1
B11
B7
A10
B28
B25
B22
B19
B16
B13
A28
A25
A22
A19
A16
A13
A6
A5
A4
A3
A2
A1
G2 G1
B9
52
43
61
1
3
3
1
2
2
1
0
0
2
0
2
1
0
3
3
J90
R2317
R3771
U134
NC
Y
GND
A
VCC
G1G2
PER_p3
PER_n3
PER_p2
PER_n2
PER_p1
PER_n1
PER_p0
PER_n0
REFCLK_p1
REFCLK_n1
GND_A28
GND_A25
GND_A22
GND_A19
GND_A16
GND_A13
PRSNT0#
PERST1#_CLKREQ#
PERST0# LED#_ACTIVITY
SMBRST#
SMBDAT
SMBCLK
PET_p3
PET_n3
PET_p2
PET_n2
PET_p1
PET_n1
PET_p0
PET_n0
REFCLK_p0
REFCLK_n0
GND_B28
GND_B25
GND_B22
GND_B19
GND_B16
GND_B13
PWRDIS
P3V3_AUX
DUALPORTEN#
RFU
MFG
GND_A6
GND_A5
GND_A4
GND_A3
GND_A2
GND_A1
P12V_B6
P12V_B5
P12V_B4
P12V_B3
P12V_B2
P12V_B1
VCCGND
2Y
1Y
2A
1A
2
1
2
1
2
1C1283
2
1C1282
2
1
2
1
2
1C1279
2
1C1278
2
1C1277
2
1C1276
2
1
21
21
2
1
2
1
21
2
1
2
1
21
CAD NOTE:
DESIGN NOTE:
SHEETDATE
DEPARTMENT
SIZE
PROJECT DOCUMENT NUMBER REV
REVIEWER
DESIGNER
123
7 3 2 1 6 5 4
E
A
B
C
E
D
C
B
A
7 6 5 4
D
IN
OUT
OUT
INBIININ
OUT
OUTOUT
OUT
OUT
IN
IN
ININ
ININ
OUT
IN
C1592
R10296
R3775
C



UVP: 10.17VOVP: 14.91VSTART UP TIME:8.21MSUVP: 2.63VOVP: 3.89VVIMON(MAX)= 1.604V @ IOUT=0.75A
DESIGN SPECIFICATIONIMAX=0.025AOCP=0.75AP12V_E1S_0IMAX=2.083AOCP=MAX*1.3=2.71AP3V3_E1S_0_RVIMON(MAX)= 1.641V @ IOUT=2.79ASTART UP TIME:3.94MSThu Sep 14 16:12:27 2023GT AMD<NAME_1><NAME_2>V02146 OF 365MB FABC
P3V3_AUXP12V_E1S_0P3V3_E1S_0_RP3V3_AUXP12V_AUXP12V_AUX
P3V3_AUXP12V_AUX2581478181831478183147 25814781E1S_P12V_MAM_TIC_BOM1E1S_P12V_MAM_TIC_BOM1CHIPP12V_E1S_EN_0_R0402LF1/16WE1S_P12V_MAM_TIC_BOM1IC0402LFE1S_P12V_MAM_TIC_BOM1160K01/16W1/16W1%0402LFCHIP10M04021UFP12V_E1S_VCC_0MAX15090BEWI+TSMLF0402LF1/16W1%P12V_E1S_UV_0E1S_P12V_MAM_TIC_BOM1EMPTY0402LFP12V_E1S_0_ISENSE_MAM_MAM05%1%2.67KB340A-13-F0.01UFCHIP0402LF1/16W50VX7R10UF16VIC100KB340A-13-FE1S_P3V3_BOM1E1S_P3V3_BOM1P3V3_E1S_EN_0_R1/16W0402LFP3V3_E1S_0_EN_G00402LFCHIPE1S_P3V3_BOM1SMLF4.7KSMLFPJT138KE1S_P3V3_BOM1IC0.1UF1%E1S_P3V3_BOM1P3V3_E1S_UV_0_RE1S_P3V3_BOM1PJT138KE1S_P3V3_BOM11%1/16WCHIP25VP3V3_E1S_VCC_01UFC04021/16WCHIP0402LF0402LFCHIP25.5KX6SE1S_P3V3_BOM11/16W9.76K0402LF0402LF50VCHIPEMPTY25V1%P3V3_E1S_PWRGD_0_R0402LF1%CHIP1%05%CHIP 1/16W25V1UFC04020CHIP1/16W1%10K5%1%0402LFICSMF14AX6S25VC0402
0402LF1%CHIP0402LF5%CHIP0402LF16V10UFX6SIC9.31K1%1/16WCHIPIC05%10K
X6S16V10UF1%CHIP
E1S_HSC
P12V_E1S_UV_0_R
E1S_0_P3V3_ENE1S_0_P12V_EN50VC080510M100K1/16WCHIP1/16W15K7.15K1%CHIPP3V3_E1S_REG_00402LFC0402CHIP1/16WE1S_P3V3_BOM1E1S_P3V3_BOM1100K1%1/16WCHIP5%0E1S_P3V3_BOM1C04026800PFE1S_P3V3_BOM1E1S_P3V3_BOM1P3V3_E1S_SENSE_0P3V3_E1S_FAULT_0P3V3_E1S_PWRGD_0X7R0402ICSMLF101%E1S_P3V3_BOM10402LF2.49K1/16WCHIPP3V3_E1S_CB_0E1S_P3V3_BOM10402LFE1S_P3V3_BOM11/16W1UFX6S25VC04025%P3V3_E1S_UV_0P3V3_E1S_GATE_00402LFE1S_P3V3_BOM11/16W1%0.01UFE1S_P3V3_BOM1CHIPE1S_P3V3_BOM1MAX15090BEWI+TE1S_P3V3_BOM1E1S_P3V3_BOM11/16WP3V3_E1S_OV_01/16WIC
0.1UF25VX6SC0805 C0805100K0402LF1/16WE1S_P12V_MAM_TIC_BOM10402LFCHIPP12V_E1S_SENSE_0P12V_E1S_0_ISENSE_MAM_TICE1S_P12V_MAM_TIC_BOM1C0402EMPTYCHIPE1S_P12V_MAM_TIC_BOM10402LFHP_LVC3_E1S_0_HSC_PWRGDE1S_P12V_MAM_TIC_BOM11/16W0402LF1/16WR3974/R3975 CO-LAYOUTE1S_P12V_MAM_TIC_BOM1CHIP1/16WE1S_P12V_MAM_TIC_BOM105%1%1/16W3900PF50VCHIP0402LFE1S_P12V_MAM_TIC_BOM1E1S_P12V_MAM_TIC_BOM1C0402P12V_E1S_FAULT_0P12V_E1S_PWRGD_0P12V_E1S_GATE_01/16W0402LFE1S_P12V_MAM_TIC_BOM1CHIP15K0402LFE1S_P12V_MAM_TIC_BOM1CHIP1/16W1%P12V_E1S_OV_0P12V_E1S_CB_0P12V_E1S_REG_025VE1S_P12V_MAM_TIC_BOM11UFCHIP101%E1S_P12V_MAM_TIC_BOM11/16W0402LFE1S_P12V_MAM_TIC_BOM11UFX6S25VC0402E1S_P12V_MAM_TIC_BOM1C04026.8KCHIP5%1/16W0402LFE1S_P12V_MAM_TIC_BOM1SMLFPJT138KPJT138KIC4.7K5%SMLFE1S_P12V_MAM_TIC_BOM1P12V_E1S_0_EN_GE1S_P12V_MAM_TIC_BOM1
G2
G1
G2
G1
S2 D2D1S1CAS2 D2D1S1
PC2215
PC2213
PD114
R3978
PC2219
PC2209
PC2218
R3977
PC2216
PC2212
PR3961
R4064
R3959
R4072
PC2217
R3976
R3972
PR3970
PR3966
PR3968
PC2211
R3979
R3973
PR3971
PR3967
PC2210
PR3969
PR3960
PC2207
PR3962
R4074
PR3963
PC2208
PR3964
PR3965
R4063
A2
D2
D1 D7
D3
D6
D4
C6
C4
B6
B4
A4
A1
D5
C5
C3
B5
B3
A5
A3
C2
C1
B2
A6
C7
B7
A7B1
2
5
PC2280
A2
D2
D1 D7
D3
D6
D4
C6
C4
B6
B4
A4
A1
D5
C5
C3
B5
B3
A5
A3
C2
C1
B2
A6
C7
B7
A7B1
PC2220
5
2
1 64 3CA4 31 6
PU295
Q127
Q126
PD112
PU294
PD113
Q127
Q126
PG
FAULT#
GND_C2
GND_C1
GND_B2
CDLY
GATE
OUT_D6
OUT_D4
OUT_C6
OUT_C4
OUT_B6
OUT_B4
OUT_A4
ISENSEOV
UV
REG
EN#
CB
IN_D5
IN_C5
IN_C3
IN_B5
IN_B3
IN_A5
IN_A3
VCC
PG
FAULT#
GND_C2
GND_C1
GND_B2
CDLY
GATE
OUT_D6
OUT_D4
OUT_C6
OUT_C4
OUT_B6
OUT_B4
OUT_A4
ISENSEOV
UV
REG
EN#
CB
IN_D5
IN_C5
IN_C3
IN_B5
IN_B3
IN_A5
IN_A3
VCC
CACA
21
2
12
1
2
1
2
1
2
1
2
1
21
2
1
2
1
2
1
2
1
21
21
2
1
2
1
2
1
2
1
21
2
1
2
1
2
1
2
1
2
1
2
1
2
1
2
1
21
2
1
2
1
2
1
2
1
2
1
2
1
CAD NOTE:
2121 2121
PC2214
CACA
SHEETDATE
DEPARTMENT
SIZE
PROJECT DOCUMENT NUMBER REV
REVIEWER
DESIGNER
123
7 3 2 1 6 5 4
E
A
B
C
E
D
C
B
A
7 6 5 4
D
OUT
OUT
OUT
OUT
IN
IN
R3975
PR4528
R3974
PR4527
R3958
R4073
R6049
C



ENABLE:P12V_E1S_0IMAX=0.025AP3V3_E1S_0_RIMAX=2.083AOCP=MAX*1.3=2.71ADESIGN SPECIFICATIONOCP=0.75APOPPOPDE-POPPOPPOPPR3957TFAULT: 1.27MSTDELAY: 6.29MSSTART UP TIME:4.7MS=0.75ACURRENT LIMITPUSH PULL OUTPUT
DE-POPDE-POPVIMON(MAX)= 1.569V @ IOUT=2.8APOPPC22052ND SOURCE OF PU295
DE-POPMP5022APU292 OPTIONAL BOMPR3953PR3952MP5025C/ MP5025A/MP5022CDE-POPPR3950START UP TIME:8.62MSVTH>1.391V(HIGH)2ND SOURCE OF PU294
Thu Sep 14 16:12:27 2023<NAME_2>MB FABCV02147 OF 365GT AMD<NAME_1>
P12V_AUXP3V3_AUXP3V3_E1S_0_RP3V3_AUXP3V3_E1S_0_RP3V3_E1S_0_R
P12V_E1S_0P12V_AUXP3V3_AUXE1S_P12V_MPS_MAM_BOM2HP_LVC3_E1S_0_HSC_PWRGDP12V_E1S_IMON_0P12V_E1S_ISET_0ICSMLFRS31312RP12V_E1S_AVIN_PD_0P12V_E1S_OV_FB_0P12V_E1S_FLTB_0P12V_E1S_EN_0_R2P12V_E1S_TIMER_0P12V_E1S_SS_0E1S_P12V_MPS_MAM_BOM201/16WCHIP1/16WE1S_P12V_MPS_MAM_BOM2E1S_P12V_MPS_MAM_BOM2560PFP12V_E1S_ISET_0_RX7R50V1%CHIP20K1/16WE1S_P12V_MPS_MAM_BOM2CHIP0.22UFE1S_P12V_MPS_MAM_BOM2E1S_P12V_MPS_MAM_BOM20402LFEMPTY1/16WCHIP0402LF0402LF1/16W71.5K0402LFCHIP1%1/16WE1S_P12V_MPS_MAM_BOM21%E1S_P12V_MPS_MAM_BOM249.91%120K1/16W0.1UFE1S_P12V_MPS_MAM_BOM20402LF10KE1S_P3V3_BOM2P3V3_E1S_EN_0_R2P3V3_E1S_MODE_0P3V3_E1S_ILIMIT_0P3V3_E1S_DVDT_0E1S_P3V3_BOM2E1S_P3V3_BOM2R3955/R3956 CO-LAYOUTE1S_P3V3_BOM2SMLF0402LF5%E1S_0_P3V3_ENE1S_P3V3_BOM2E1S_P3V3_BOM21%56KCHIP10KE1S_P3V3_BOM21/16W1/16WCHIP0402LFP3V3_E1S_PWRGD_0_R1E1S_P3V3_BOM20402LFE1S_HSC_CO_LAYOUTCHIPE1S_P3V3_BOM20402X7R16V0.068UF100PFE1S_P3V3_BOM20402X7R50VE1S_P3V3_BOM2P3V3_E1S_GATE_0_PU2931%CHIPCHIP2.8KMP5016GQH-L-ZX6S10UF16V0402C04025%IC5%16VC0805
EMPTY1005%0X7R25V
1%0402LFSMLFAPX809-29SAG-7IC100K1%1/16W5%0CHIP5%0402LF25V1UFP3V3_E1S_PWRGD_0_REMPTY0402LFX6SC040271.5K1/16WE1S_P3V3_BOM20402X7R25V0.1UF10%E1S_P3V3_BOM2
1%040210K1%X7R10%0603LF2.2UF20%16VCHIP10K100NF50VX7RC0402E1S_P12V_MPS_MAM_BOM20C06030402LFE1S_P12V_MPS_MAM_BOM2P12V_E1S_AVIN_PD_01%1/10WCHIP1/16W1%0402LF25V1UFCHIP1%1/16WE1S_0_P12V_EN0.047UFX7R25V46.4KX7RE1S_P12V_MPS_MAM_BOM2C04020402LFE1S_P12V_MPS_MAM_BOM20402LFE1S_P12V_MPS_MAM_BOM2146 83818114625814725814781146 8381
39PFE1S_P3V3_BOM250VNPO0402E1S_P12V_MPS_MAM_BOM20402LFE1S_P12V_MPS_MAM_BOM2146E1S_P12V_MPS_MAM_BOM2E1S_P12V_MPS_MAM_BOM2E1S_P12V_MPS_MAM_BOM2CHIPP12V_E1S_0_ISENSE_MPS_TIC5%1/16W0402LFP12V_E1S_0_ISENSE_MPS_MAM0402LF0E1S_P12V_MPS_TIC_BOM3EMPTY1/16WC0402X6S
PR3957PR3953
PR3952
PC2201
PR3945PC2197
PC2206
PC2205PR3954
PR3950
PR3951
PC2202
R3948
PR3949
PC2203
PC2198
PC2281
PR4541
PC2341
PR3944
PC2196
PC2200
PR3947
20
19
18
17
16
15
14
13
26
25
24
23
21_22
4
6
10
11
2
5
87
9
3
1
12
3
2
1
PU292
U8003
PC2204
PU293
GND
SS
ISET
TIMER
ENTM
LOADEN
EN
VIN_26
VIN_25
VIN_24
VIN_23
IMON
FLTB
PG
OV
VOUT_13
AVIN
VOUT_14
VOUT_15
VOUT_16
VOUT_17
VOUT_18
VOUT_19
VIN_21_22
VOUT_20
GND
RESET_L
VCC
SOURCE
GATE
DV_DT
VCC
GND
ILIMIT
MODE
EN
21
2
1
2
12
1C8010
2
1
2
1
21
21
2
1
2
1
2
1
2
1
21R3943
2
1
2
1
2
1
21R3946
CAD NOTE:
1_2 6_7
54 3
8
9
10
SHEETDATE
DEPARTMENT
SIZE
PROJECT DOCUMENT NUMBER REV
REVIEWER
DESIGNER
123
7 3 2 1 6 5 4
E
A
B
C
E
D
C
B
A
7 6 5 4
D
OUT
OUT
OUT
OUT
OUT
IN
IN
IN
R8100
R8098
R8099
R3955
R3956
C



TBC
Thu Sep 14 16:12:28 2023<NAME_2><NAME_1>MB FABCGT AMDV02148 OF 365
10K1/16WCHIP0402LF1%P3V3_AUXP3V3_E1S_0PCA9617ADPSMLFSMB_E1S_3V3AUX_ISO_SCLSMB_E1S_3V3AUX_ISO_SDASMB_PCIE_E1S_ISO_ENSMB_SENSOR_E1S_3V3AUX_SCLSMB_SENSOR_E1S_3V3AUX_SDA SMB_E1S_3V3AUX_ISO_SDA_RCPU - SATA / RAID KEY0402LF 1/16W200K1%EMPTYSMLFICX7R10%0.1UF25V04020.1UF10%X7R25V04021/16W5%0402LFCHIP4.7KCHIP1/16W0402LF5%4.7KCHIP33.21%33.20402LF 1/16WCHIP200K1/16W0402LF1%200K1%33.21%0402LF33.20402X7R25V0.1UF10%1/16W4.7K5%CHIP0402LF1/16WCHIP5%4.7K0.1UF25V10%SMB_PCIE_M2_0_EN0402CHIPPCA9306DP1SMB_PCIE_E1S_ISO_EN_RSMB_E1S_3V3AUX_ISO_SCL_R1%CHIP1%CHIPSMB_M2_P1_1V8AUX_SDA1/16WSMB_M2_P1_1V8AUX_SDA_R0402LFX7RICSMB_SENSOR_M2_P1_3V3AUX_SDASMB_SENSOR_M2_P1_3V3AUX_SCL0402LF 1/16WSMB_M2_P1_1V8AUX_SCL_REMPTYPWRGD_P1V8_AUX_RSMB_M2_P1_1V8AUX_SCL14514514525125114425125127125581270144P3V3_E1S_0P1V8_AUXP1V8_AUXP3V3_AUX
R3529 R3530 R3532
R3534
R3533
R1700
R2411
R2410
R1703R1702
8 1
6 3
7 2
45
7 2
5 4
6 3
1 8
U98
U279
GND
SCLB
SDAB SDAA
SCLA
VCCB VCCA
EN
GND EN
VREF2
SCL2
SDA2 SDA1
SCL1
VREF1
2
1
21R3531
2
1
2
1
2
1
2
1
21
21
2
1
21R2476
21 21
2
1
2
1
2
1
2
1
SHEETDATE
DEPARTMENT
SIZE
PROJECT DOCUMENT NUMBER REV
REVIEWER
DESIGNER
123
7 3 2 1 6 5 4
E
A
B
C
E
D
C
B
A
7 6 5 4
D
IN
IN
BI OUT
BI
IN
OUTBIINBI
C1997 C1998
C1305 C1323
C



Thu Aug 24 10:14:39 2023149 OF 365V02GT AMDMB FABC<NAME_1><NAME_2>Blank
SHEETDATE
DEPARTMENT
SIZE
PROJECT DOCUMENT NUMBER REV
REVIEWER
DESIGNER
123
7 3 2 1 6 5 4
E
A
B
C
E
D
C
B
A
7 6 5 4
D
C



SPI FROM SCM TO MB FPGARERSERVETBCSPI FROM MB TO SCM_BIOS FLASH
Thu Sep 14 16:12:32 2023150 OF 365V02MB FABC<NAME_2>GT AMD<NAME_1>
I3C_SCM_2_R_SCLI3C_SCM_1_R_SCLI3C_SCM_0_R_SDA159 SCM_VDD_RTCP12V_SCM P12V_SCM
P3V3_AUXP3V3_AUX0402LF1/16W801721518080249249SCM_ROT_CPU_RST_R_N8025VX7R8015115180SGPIO_SCM_DI_<0>15180151151808015115124180243808015115115100FM_AC_PWR_BTN_R_N801511537777777777298118018018029298129812981
1508017125415182113234113
298129 7681807780130
29113113235171151151171164151151 16480
1448525125126262626234
159159159159159159801592828151249151249151151151160151160253151248151248151249151249151248151248151151151241151241235151160151160253180132 138132 138132 138132 138132132 138132 138298111613377151151151858183 00000 0000000000005%CHIPCHIPESPI_CPU0_ALERT_NSPI_CPU0_LVC3_SCM_CLKSGPIO_SCM_CLK_R_<1>SGPIO_SCM_DI_R_<1>TP_SPI_2_PLD_CS_NSGPIO_SCM_INTR_NSGPIO_SCM_LD_<1>SGPIO_SCM_DO_R_<1>SGPIO_SCM_CLK_R_<0>SGPIO_SCM_LD_R_<1>TP_PVCCIO_PECI_BMCSPI_CPU0_LVC3_SCM_D2SPI_CPU0_LVC3_SCM_D1SPI_CPU0_LVC3_SCM_D0SPI_CPU0_LVC3_SCM_CS0_NESPI_CPU0_D3USB3_CPU0_BMC_TX_BUF_C_DPUSB2_HUB_EXT_DNUSB2_HUB_EXT_DPUSB2_CPU0_P1_DNRST_ESPI_CPU0_RSTOUT_NFM_SOL_UART_CH_SEL_R
1%1K1/16WCHIP0402LF5%SMB_1_BMC_GPU_SCL1/16WFM_SCM_PRSNT1_NP2E_MB_BMC_RX_BUF_DP<0>CHIP0CHIPP2E_MB_BMC_RX_BUF_DN<0>
CLK_ESPI_CPU0_CLK1FPGA_IO3V3_RSVD_1SPI_CPU0_LVC3_TPM_CS_NRST_SRST_PLD_BMC_NUART_CPU0_SCM_LVC3_UART1_RXUART_BMC_BIC_BUF_RXUART_2 BMC TO MB (BMC HOST)UART_1 MB TO BMC (BMC SLAVE)PRSNT0_NUART_CPU0_SCM_LVC3_UART1_R1_TX
USB2_CPU0_P1_DPTP_SPI_2_PLD_IO1P2E_MB_BMC_TX_C_DP<0>P2E_MB_BMC_TX_C_DN<0>TP_PCIE_TXP[3]USB2_HOST_BMC_B_DN5%1%
SCM CONN
SMB_1_PLD_3V3AUX_SDA_R3SMB_PCIE2_3V3AUX_SDA_R0JTAG_SCM_TCKJTAG_SCM_TDO_RJTAG_SCM_TDI_RJTAG_SCM_TMSSMB_PCIE2_3V3AUX_SCL_R0UART_CPU0_SCM_LVC3_UART1_TXUART_CPU0_SCM_LVC3_UART1_R_RX00402LFCHIP1/16W5%00EMPTYFM_SOL_UART_CH_SEL1/16WTP_PCIE_TXP[1]TP_PCIE_TXN[1]TP_BEEP_LEDLED_HDD_ACTIVITY_B_NSMB_PCIE0_3V3AUX_SDASMB_PCIE0_3V3AUX_SCLP2E_CPU0_P5_TX_C_DPSMB_1_PLD_3V3AUX_SCL_R3P2E_CPU0_P5_RX_DNP2E_CPU0_P5_RX_DPP2E_CPU0_P5_TX_C_DN5%05%5%01%CHIP33.21%CHIP33.21%5%01/16W0402LFEMPTY33.21%CHIPCHIP1%CHIP33.233.21%33.2 CHIP33.2 CHIP1%CHIP1%33.2 CHIP1%CHIP1%CHIP33.21%CHIP00402LFCHIP5%IO
00
EMPTY33.2CHIPCHIP1%33.21%33.21%SMB_PMBUS_3V3AUX_SCL_R0SMB_PMBUS_3V3AUX_SDA_R0CHIP1%33.2SMB_PCIE3_3V3AUX_SDA_RSMB_HOST_CLK_3V3AUX_SDA_R04.7K5%
I3C_SCM_3_SCLI3C_SCM_3_R_SCLI3C_SCM_2_SDAI3C_SCM_2_R_SDAI3C_SCM_3_SDAI3C_SCM_3_R_SDAI3C_SCM_1_SDAI3C_SCM_1_SCLI3C_SCM_0_SDASGPIO_SCM_CLK_<0>SGPIO_SCM_DO_<0>I3C_SCM_0_SCLSGPIO_SCM_LD_<0>I3C_SCM_1_R_SDA33.233.2VIRTUAL_RESEATI3C_SCM_0_R_SCLSMB_OCP_SFF_3V3AUX_SCL_R0SMB_OCP_SFF_3V3AUX_SDA_R0SMB_CPU0_CPU1_APML_SCL_RSMB_CPU0_CPU1_APML_SDA_RSMB_VR_3V3AUX_SCL_R0SMB_OCP_V3_2_3V3AUX_SCL_R0SMB_OCP_V3_2_3V3AUX_SDA_R0CLK_100M_CPU0_CLK01_DPCLK_100M_CPU0_CLK01_DNCHIP33.2CHIP1/16W0402LF33.2SMB_2_BMC_GPU_SCLSMB_2_BMC_GPU_SDASMB_1_PLD_3V3AUX_SCLSMB_1_PLD_3V3AUX_SDASMB_CPU0_CPU1_APML_SCLSMB_CPU0_CPU1_APML_SDASMB_VR_SENSOR_3V3AUX_SCLSMB_OCP_V3_2_3V3AUX_SDASMB_OCP_V3_2_3V3AUX_SCLCHIPSMB_VR_3V3AUX_SDA_R0SMB_CPU0_CPU1_SEC_SCL_RI3C_BMC_SWB_SCLI3C_BMC_SWB_SDA1%1%SMB_OCP_SFF_3V3AUX_SDASMB_OCP_SFF_3V3AUX_SCLSMB_CPU0_CPU1_SEC_SDA_RSMB_PMBUS_3V3AUX_SCLSMB_PMBUS_3V3AUX_SDA33.21%CHIPSMB_FAN_3V3AUX_SCLSMB_FAN_3V3AUX_SDA0SMB_PCIE3_3V3AUX_SCL_RSMB_HOST_CLK_3V3AUX_SCL_R0USB2_HOST_BMC_B_DPTP_SPI_2_PLD_IO3SMB_CPU0_CPU1_SEC_SDASMB_CPU0_CPU1_SEC_SCLSMB_VR_SENSOR_3V3AUX_SDAI3C_SCM_2_SCL
USB3_CPU0_BMC_TX_BUF_C_DN1%RMII_OCP_BMC_CRSDVRMII_BMC_OCP_TX_ENRMII_BMC_OCP_TXD_0RMII_BMC_OCP_TXD_1RMII_BMC_OCP_RX_ERRMII_OCP_BMC_RXD_0RMII_OCP_BMC_RXD_1TP_PECI_BMCSGPIO_SCM_DO_R_<0>ESPI_CPU0_D0UART_BMC_BIC_TXSCONN168_ME10168102020110CHIPFM_LPC_ESPI_SELCLK_50M_RMII_BMC_OCPSPI_CPU0_LVC3_SCM_D3SMLF
5%CHIPTP_PCIE_RXP[1]TP_PCIE_RXN[1]5%CHIPSMB_1_BMC_GPU_SDASCM_IRQ_N33.2SMB_HOST_CLK_3V3AUX_SDA4.7K05%CHIPFM_UARTSW_MSB_REMPTYPWRGD_PS_PWROK_RTP_STBY_ENCHIP5%0SCM_SYS_PWRBTN_N0402LFSGPIO_SCM_DI_R_<0>SGPIO_SCM_LD_R_<0>TP_SPI_2_PLD_IO2TP_SPI_2_PLD_IO0SGPIO_SCM_CLK_<1>0.1UF10%0402SGPIO_SCM_RESET_NSGPIO_SCM_DI_<1>SGPIO_SCM_DO_<1>FW_RECOVERY0JTAG_SCM_DBREQ_NFM_UARTSW_LSB_NCHIP80CHIPPU_JTAG_DBP_BMC_PRDY_NFM_UARTSW_MSB_NSCM_ROT_CPU_RST_NSCM_HDT_DBREQ_NFM_RST_PERST_SCM_NUSB3_CPU0_BMC_RX_DN180152FM_UARTSW_LSB_RIRQ0_A56SCM_SYS_PWROK_R1SCM_SYS_PWRBTN_R_NRST_MB_STBY_R_NUSB3_CPU0_BMC_RX_DP180150CLK_100M_BMC_RC_DNCLK_100M_BMC_RC_DPTP_SPI_2_PLD_CLKFM_AC_PWR_BTN_NSGPIO_SCM_INTR_R1_NSGPIO_SCM_RESET_R_NESPI_CPU0_CS1_NESPI_CPU0_D1ESPI_CPU0_D233.2SMB_HOST_CLK_3V3AUX_SCLFW_RECOVERY_RPWRGD_PS_PWROKRST_MB_STBY_N8084SCM_ROT_CPU_RST_R_N1/16WEMPTY0402LFTP_CHASICHIP5%0
R8101
2 1 R6008
R6009
R6010
R6011
2 1 R6012
2 1R6000
R6026
R6013
R6015
R6014
2 1R6001
2 1R6002
2 1R6003
2 1R6004
2 1R6007
2 1R6005
2 1R6006
R6025
C6000
R6071
R2423
R2424
R4506
R4507
R6065
R6064
R6028
R3778
R2420
R2419
R3238
R3239
R2422
R2415
R2417
R2418
R2416
R1801
R2421
R2425
R3858
R2413
R2414
R3254
R1816
R4087
R6033
R1815
R6032
R3776 21R1798
R3777
OA3
A69
A68
A9
A8
A7
OA6
OB7
B69
B68
OA12 OB12
A15 B15
OA11 OB11
A14 B14
OA8
OA9
OA7
OB8
OB9
OB14OA14
OA5
OA4
A70 B70
A12
A42 B42
A10
B66
B63
B60
B57
B54
B51
B48
B45
B40
B37
B34
B31
B27
B24
B21
B18
B65
B62
B59
B56
B53
B50
B47
B44
B39
B36
B33
B30
B26
B23
B20
B17
OA2
OA1
A11
B10
A66
A63
A60
A57
A54
A51
A48
A45
A40
A37
A34
A31
A27
A24
A21
A18
A65
A62
A59
A56
A53
A50
A47
A44
A39
A36
A33
A30
A26
A23
A20
A17
OB1
OB2
OB3
OB13
OB10
OA13
OA10
B67
B64
B61
B58
B55
B52
B49
B46
B43
B41
B38
B35
B32
B29
B28
B25
B22
B19
B16
B13
A67
A64
A61
A58
A55
A52
A49
A46
A43
A41
A38
A35
A32
A29
A28
A25
A22
A19
A16
A13
A6
A5
A4
A3
A2
A1
G5
G4
G3
G2
G1
OB5
OB4
OB6
B9
B8
B7
B12
B6
B5
B4
B3
B2
B1
B11
R321
J41
KEY
KEY
KEY
G5
G4
G3
G2
G1
PRSNTB3#
RFU1_NC_B69
RFU1_NC_B68
GND_B67
PETp15
PETn15
GND_B64
PETp14
PETn14
GND_B61
PETp13
PETn13
GND_B58
PETp12
PWRBRK0#
USB_DATp
USB_DATn
GND_A67
PERp15
PERn15
GND_A64
PERp14
PERn14
GND_A61
PERp13
PERn13
GND_A58
PERp12
PERn12
GND_A55
PERp11
PERn11
GND_A52
PERp10
PERn10
GND_A49
PERp9
PERn9
GND_A46
PERp8
PERn8
GND_A43
PRSNTB1#
GND_A41
PERp7
PERn7
GND_A38
PERp6
PERn6
GND_A35
PERp5
PERn5
GND_A32
PERp4
PERn4
GND_A29
GND_A28
PERp3
PERn3
GND_A25
PERp2
PERn2
GND_A22
PERp1
PERn1
GND_A19
PERp0
PERn0
GND_A16
REFCLKp1
REFCLKn1
GND_A13
PRSNTB2#
PERST1#
PRSNTA#
SMRST#
SMDAT
SMCLK
GND_A6
GND_A5
GND_A4
GND_A3
GND_A2
GND_A1
RBT_CLK_IN
GND_OA13
REFCLKp3
REFCLKn3
GND_OA10
RBT_TXD0
RBT_TXD1
RBT_TX_EN
SLOT_ID1
RBT_ARB_OUT
RBT_ARB_IN
WAKE#
PERST3#
PERST2#
PETn12
GND_B55
PETp11
PETn11
GND_B52
PETp10
PETn10
GND_B49
PETp9
PETn9
GND_B46
PETp8
PETn8
GND_B43
PRSNTB0#
GND_B41
PETp7
PETn7
GND_B38
PETp6
PETn6
GND_B35
PETp5
PETn5
GND_B32
PETp4
PETn4
GND_B29
GND_B28
PETp3
PETn3
GND_B25
PETp2
PETn2
GND_B22
PETp1
PETn1
GND_B19
PETp0
PETn0
GND_B16
REFCLKp0
REFCLKn0
GND_B13
AUX_PWR_EN
+3.3V_EDGE
PERST0#
BIF2#
BIF1#
BIF0#
+12V_EDGE_B6
+12V_EDGE_B5
+12V_EDGE_B4
+12V_EDGE_B3
+12V_EDGE_B2
+12V_EDGE_B1
RBT_CRS_DV
GND_OB13
REFCLKp2
REFCLKn2
GND_OB10
RBT_RXD0
RBT_RXD1
SLOT_ID0
CLK
DATA_OUT
DATA_IN
LD#
MAIN_PWR_EN
NIC_PWR_GOOD
2
1
2
1
2 1
2
1
21 21
21 21
21 21
2
1
21
2 12 12 1
21 21
21 21
21
21
2 121 21
21
2
1
2 1
2 12 1
21
21 21
21R4508 21R4509
21 21
21
2 1
21 21
21 21
21
21
21
2
1
2
1
DESIGN NOTE:
SHEETDATE
DEPARTMENT
SIZE
PROJECT DOCUMENT NUMBER REV
REVIEWER
DESIGNER
123
7 3 2 1 6 5 4
E
A
B
C
E
D
C
B
A
7 6 5 4
D
BIBI
BIBI
IN
OUT
BI
BI
IN
BI
BI
BI
BI
BI
OUT
BIOUT
IN
BI
OUT
IN
OUTIN
BIBI
BIBIIN BIBI
ININ
OUT
OUTOUT
OUT
ININ
ININ
IN
OUT
IN
OUTOUT
OUT
IN
OUT
OUT
OUT
OUT
OUT
OUT
OUT
OUT
OUT
OUT
IN
IN
OUT
OUT
BI
BI
BI
INOUT
OUT
INOUT
IN
ININ
IN
BIBIBIBI
IN
ININ
IN
IN
ININ
OUTOUT
OUTIN
OUTOUTINOUT
IN
IN
OUT
BI
OUT
OUTOUT
IN
OUT
BI
OUT
OUT
OUTOUT
OUT
BIBI
OUT
IN
ININ
IN
IN
OUT
R4809
R6034
R6035
C



HSCDEFAULT: POP R6067 & R6069, DE-POP R6066 & R6068
<NAME_2>V02151 OF 365GT AMDMB FABC<NAME_1>Thu Sep 14 16:12:33 2023
SCM_VDD_RTCP3V_BAT_RP3V3_AUX
P3V3_AUXP5V_AUX
P3V3_AUXP3V3_AUXPVDD18_S5_P0249249I3C_BMC_SWB_SCL1515%00402LF CHIP 1/16W151150RST_MB_STBY_N1K80
SCM SMBUS BUS
SGPIO_SCM_DO_<0>EMPTY28 151185185234234183183253 210253 210150193193
15015115015118218226326328 151171150160150160150150150160
217224217224200
18418480268 269268 26980
150248150249150249
151150150150 80
258171200
150151150151
150818180 15015080150 172150 8080 150150 808080
150248164150
150 8080 150150 80150 80150249150248150164150248150151150151150249258365365288080150151150151151150150151150241150241150160
207363363207
28 151CHIPCHIP 2.2K2.2KSMB_CPU_5_SCLCHIP33SMB_MUX_RT_ROM_R1_SDASMB_HOST_CLK_3V3AUX_SDA_R1SMB_MUX_RT_ROM_R1_SCLCHIP0402LFSMB_HOST_CLK_GEN2_3V3AUX_SDASMB_HOST_CLK_GEN2_3V3AUX_SCL33SMB_HOST_CLK_3V3AUX_SCL_R11/16W1%CHIP33.2SMB_9ZXL045_P1_SCL33CHIPSMB_9ZXL045_P1_SDASMB_VR_3V3AUX_SCLSMB_VR_3V3STBY_SCLSMB_VR_3V3AUX_SDA33SMB_VR_3V3STBY_SDAEMPTYJTAG_SCM_TDO_R3333SMB_SCM_2_R3_SDA3333SMB_SCM_2_R3_SCL
33.21%CHIPCHIPCHIP33.20402LFSMB_HOST_CLK_3V3AUX_SCLCHIP1/16WSMB_HOST_CLK_3V3AUX_SDASMB_9ZXL045_P0_SCLSMB_9ZXL045_P0_SDA33CHIP33CHIP33CHIP1%CHIP1%33.20402LFCHIP1/16WSMB_SML1_PMBUS_HSC_SDASMB_SML1_PMBUS_HSC_SCLSMB_CPU_5_SCLJTAG_SCM_TDOCO-LAY R6068 & R6069CHIPSMB_CPU0_CPU1_SEC_SCLSMB_CPU0_CPU1_APML_SDAI3C_BMC_SWB_SDASMB_CPU0_CPU1_APML_SCL
SMB_SCM_2_R1_SCLSMB_SCM_2_R2_SDA33SMB_SCM_2_R1_SDASMB_SCM_2_R2_SCLSMB_SCM_2_R5_SDA33333333
SMB_MUX_RT_R1_SDASMB_MUX_RT_R1_SCLSMB_1_PLD_3V3AUX_SDA_R1SMB_SML1_PMBUS_HSC_R1_SCLSMB_SML1_PMBUS_HSC_R1_SDASMB_1_PLD_3V3AUX_SCL_R10CHIPCHIP0CHIPCHIP0402LF1%33.20402LFCHIP1%CHIPCHIP33.21%33.2
SMB_OCP_SFF_3V3AUX_SCLSMB_1_BMC_GPU_SDASMB_2_BMC_GPU_SDA
1/16W00SMB_1_PLD_3V3AUX_SDASMB_1_PLD_3V3AUX_SCLEMPTY1%1/16W0402LF0402LFEMPTY2.2K5%EMPTY1/16W2.2K5%EMPTY0402LF1/16W2KEMPTY1%0402LF0402LFEMPTY1%2K1/16W2K1/16WEMPTY1%1%2KEMPTY2K 1%2KEMPTY1%EMPTY1%1/16W0402LF2K2K0402LFSMB_SCM_2_R4_SDAJTAG_SCM_TDI33.2
33SMB_SCM_2_R5_SCL
33.2SMB_PMBUS_3V3AUX_SCLSMB_PMBUS_3V3AUX_SDA
1/16WCHIP5%10K0402LF
1/16WEMPTY5%10K0402LF5%EMPTY1/16W0402LF10K
5%10K1/16W0402LFEMPTY
10K5%1/16WEMPTY0402LF10K5%1/16WEMPTY0402LF
0JTAG_SCM_TDI_R0EMPTY0CHIP0SMB_CPU_5_R1_SDASMB_CPU_5_R1_SCLSGPIO_SCM_INTR_NEMPTY4.7KSGPIO_SCM_RESET_NEMPTY4.7KJTAG_SCM_DBREQ_N4.7KEMPTY2KEMPTYSGPIO_SCM_LD_<1>SGPIO_SCM_DI_<1>SGPIO_SCM_CLK_<1>SCM_SPARE_0SCM_SPARE_1
50V220PF 220PF5%50V
EMPTY2K2K2K2K2K2K
SMB_OCP_V3_2_3V3AUX_SDA0402LF 1/16W2.2KUART_CPU0_SCM_LVC3_UART1_TX
SGPIO_SCM_DO_<1>SGPIO_SCM_DI_<0>SGPIO_SCM_LD_<0>SGPIO_SCM_CLK_<0>SMB_2_BMC_GPU_SCLSMB_OCP_V3_2_3V3AUX_SCLUART_CPU0_SCM_LVC3_UART1_R_RXSMB_OCP_SFF_3V3AUX_SDASMB_HOST_CLK_3V3AUX_SDASMB_HOST_CLK_3V3AUX_SCLUART_VCC_J8SMB_1_BMC_GPU_SCLEMPTYEMPTY2KEMPTY
C0402
1%1%
C04025%2.2K EMPTY5%5%EMPTY0402LF 1/16W5%2.2K EMPTY5%2.2K EMPTY0402LF 1/16W5%2.2K EMPTY2.2K5%EMPTY0402LF 1/16W2.2K5%EMPTY2.2K5%EMPTY5%2.2K EMPTY0402LF 1/16W2.2K5%EMPTY2.2K5%EMPTY1/16WCONN4_HFK1040-L0P1L-7HIOTHLFEMPTY5%2.2K
1%0402LF 1/16W
3333SMB_SCM_2_R4_SCL
33.233.233.21%1/16W
00CO-LAY R6066 & R6067P0V9_RETIMER_CPU1_PMSCLP0V9_RETIMER_CPU1_PMSDASMB_CPU_5_SDA1%SMB_2_PLD_3V3AUX_SCL_R1SMB_2_PLD_3V3AUX_SDA_R1SMB_PMBUS_3V3AUX_SDASMB_PMBUS_3V3AUX_SCLSMB_1_PLD_3V3AUX_SDASMB_1_PLD_3V3AUX_SCLSMB_FAN_3V3AUX_SCLSMB_FAN_3V3AUX_SDASMB_CPU0_CPU1_SEC_SDA3333SMB_SCM_2_R6_SCLP0V9_RETIMER_CPU0_PMSCLP0V9_RETIMER_CPU0_PMSDA33SMB_SCM_2_R6_SDA
SMB_CPU_5_SDA
R6858
R6859
R351
R352
R349
R350
R6070
2 1R6067
2 1R6069
2 1R6068
2 1R6066
2
1
R891
2
1
R889
R130
2
1 C62
2 1R1453
21R1495
21R1496
21R6018
21R6019
21R6020
21R6022
21R6021
21R6023
21R6024
21R632
21R633
21R1321
21R1494
4
3
2
1
J8
2
1
R890
2
1
R888
2
1
R131
2
1 C63
2 1R1447
21R6027
R1546
21R6016
21R6017
21
R6783
R6782
R6857
R6856
R309
R308
R6865
R6864
R6863
R6862
R6785
R6784
21R1498
21R6077
21R6076
21R1497
R1517
R1516
R347
R348
R4150
R4149
R4151
R1319
R3062
R1384
R1385
R1386
R329
R6037
R6036
R330
R331
R332
R1460
R4152
1
2
3
4
21R364
2 12 1
21
21
21
21
21 21
21
21
21
21
21
21
2 12 1
21
21
21
21
21 21
21
21
21
21 21
21 21
21
21 21
21 21
21 21
21 21
21 21
21 21
21 21
21R2212 21R2213
21R2999 21R3004
21R3226 21R3227
21
21
2121
CAD NOTE:
CAD NOTE:
R3241
R3242
R2996R2995
R3341R3340
R3240
R3243
SHEETDATE
DEPARTMENT
SIZE
PROJECT DOCUMENT NUMBER REV
REVIEWER
DESIGNER
123
7 3 2 1 6 5 4
E
A
B
C
E
D
C
B
A
7 6 5 4
D OUT
OUTOUT
INBI
OUTOUT
INBI
BIIN
IN
OUTOUT
OUTOUT
OUTOUT
OUTOUT
BIBI
INOUT
BIBI
IN
BI
OUTOUT
OUT
BI
OUT
BI
BI
OUT
OUTOUT
IN
OUTOUTOUTOUTOUTOUTOUT
BI
BI
OUT
BI
OUT
BI
OUT
OUT
BI
BIOUT
BIOUT
OUT
BI
OUT
BI
OUT
BI
OUT
BI
OUT
OUTBI
OUT
OUT
IN
OUT
IN
OUT
BI
BIBI
OUT
BI
BIOUT
BIOUT
BIOUT
BIOUT
OUTOUT
OUT
C



2ND SOURCE OF PU300PC2239PR4014PR4010PU299 OPTIONAL BOMPOPPOPVTH>1.391V(HIGH)DE-POPDE-POPVIMON(MAX)= 1.563V @ IOUT=5.34ADE-POPDE-POPPR4009 POPDE-POPSTART UP TIME:8.62MSVIMON(MAX)= 1.610V @ IOUT=5.35A
UVP: 10.17VOVP: 14.91VENABLE:START UP TIME:8.21MSPR4006POPMP5022CMP5025C/MP5022APOPMP5025A/IMAX=4ADESIGN SPECIFICATIONOCP=MAX*1.3=5.2AP12V_SCM_R
TFAULT: 1.27MSTDELAY: 6.29MSThu Sep 14 16:12:28 2023<NAME_2><NAME_1>MB FABCGT AMDV02152 OF 365
SCM_P12V_MAM_BOM1P12V_AUXP3V3_AUXP12V_AUX
P12V_AUXP12V_SCM_R
P12V_SCM_RP12V_AUXP3V3_AUXP3V3_AUXP3V3_AUXP3V3_AUXSCM_P12V_MPS_BOM2P12V_SCM_IMONICRS31312RSMLFP12V_SCM_AVIN_PDP12V_SCM_OV_FBHP_LVC3_SCM_HSC_PWRGD_RP12V_SCM_FLTB_NP12V_SCM_EN_R2P12V_SCM_TIMERP12V_SCM_ISETP12V_SCM_SS1/16WP12V_SCM_CBSCM_P12V_MAM_BOM1C0402X6S1UFSCM_P12V_MPS_BOM2CHIPSCM_P12V_MPS_BOM21521528115082 15225715280 15281152257
0.22UFSCM_P12V_MPS_BOM2SCM_P12V_MPS_BOM2C0603SCM_P12V_MPS_BOM20100NFSCM_P12V_MPS_BOM2CHIPSCM_P12V_MPS_BOM2P12V_SCM_AVIN_PD5%30.1KSCM_P12V_MPS_BOM21/16W10K2.2UF16V1/16W0402LFSCM_P12V_MPS_BOM21%CHIP120KX7R20%SCM_P12V_MPS_BOM204021%0.1UF71.5K1%1/16WCHIPEMPTY0402LFSCM_P12V_MPS_BOM25%1/16WHP_LVC3_SCM_HSC_PWRGD0.047UF1/16WC04020402LFSCM_P12V_MPS_BOM2P12V_SCM_ISET_R0402LF1%X7R50V560PF0402LFP12V_SCM_ENSCM_P12V_MAM_BOM1FM_SCM_PRSNT1_R_N1/16W0402LFSMLF2N7002KSCM_P12V_MAM_BOM10402LF1/16WPJT138KSMLFSCM_P12V_MAM_BOM10402LF0P12V_SCM_UV_R1/16WSCM_P12V_MAM_BOM1CHIP1/16WSCM_P12V_MAM_BOM10ICEMPTY1%10MSCM_P12V_MAM_BOM11/16WCHIPP12V_SCM_GATE1/16W1/16WSCM_P12V_MAM_BOM1CHIPSCM_P12V_MAM_BOM1SCM_P12V_MAM_BOM11%C0402MAX15090BEWI+TSMLFSCM_P12V_MAM_BOM10402LF17.8KP12V_SCM_OVP12V_SCM_SENSESCM_P12V_MAM_BOM1C0402 0402LF1/16W1%100KC0805C04020.01UFCHIP0402LF3900PFSCM_P12V_MAM_BOM15%0402LFB340A-13-FX7R10UF0402 C0805X6S0.1UFICFM_SCM_PRSNT1_NP12V_SCM_FAULT_R_N
VIRTUAL_RESEAT_FPGA_N
P12V_SCM0402LF1/16WIC0CHIP
22UF16V16VX6S25VCHIP1/16WCHIP1%1.33K6.8K1%CHIP1%0402LFCHIP
C0402X7R10%25VCHIP50VC04021%0402LFEMPTY1%25VCHIPX7R25V
25VCHIP0402LF1001%1%CHIPICICCHIP0402LFCHIP1%1/16W1K1%CHIP1/16WCHIP 1/16W5%CHIP1/16W
50V0CHIP0402LFHP_LVC3_SCM_HSC_PWRGDP12V_SCM_FAULT_R_N01/16W1%100KSCM_P12V_MAM_BOM150V15K1%101UFC0402P12V_SCM_VCCSCM_P12V_MAM_BOM1SCM_P12V_MAM_BOM11UFC040225VSMLFX6S160K1%CHIP0402LF1UFX6SSCM_P12V_MAM_BOM1CHIPSCM_P12V_MAM_BOM10402LF0402LF5%1/16W10KICSMF14ACHIP1/16WP12V_SCM_UVP12V_SCM_PWRGDP12V_SCM_FAULT_NP12V_SCM_REG25VSMLFP12V_SCM_EN_GPJT138KSCM_P12V_MAM_BOM15%010K1/16W0402LFP12V_SCM_EN_R1/16W0X7R16V04025%SCM_P12V_MPS_BOM220KSCM_P12V_MPS_BOM2CHIP1/16W1%24.3K0402LF0402LF5%0402LFSCM_P12V_MAM_BOM1SCM_P12V_MPS_BOM210K1/16WCHIP1%0402LFSCM_P12V_MPS_BOM20402LFSCM_P12V_MPS_BOM20402LF49.9SCM_P12V_MPS_BOM21/10W0603LFCHIP0402LF1%10KSCM_P12V_MPS_BOM2SCM_P12V_MPS_BOM20402LF1%1/16WX7R100
G
G2
G1
S DCAS2 D2D1S1
PR4014
21PR4012
PC2237
PR4010
PD115
PR4009
R8031
R8030
R8012
PC2240
R4013PR4526
PR4003
PR4001
PR4002
PC2241
PR4011
R3836
PR4006
PR4005PC2340
PC2238
R4015
PR4008
PC2234
PC2233
PR4000
PR4004
PC2239
PC2235
PR4007
PC2231
PC2232
PC2230
R4071
R4062
PR4540PR3999
PC2229
R1856
20
19
18
17
16
15
14
13
26
25
24
23
21_22
4
6
10
11
2
5
87
9
3
1
12
PC2242
A2
D2
D1 D7
D3
D6
D4
C6
C4
B6
B4
A4
A1
D5
C5
C3
B5
B3
A5
A3
C2
C1
B2
A6
C7
B7
A7B15
2
G
4 31 6S D
PU299
PU300
Q125
Q125
Q39
PD116
GND
SS
ISET
TIMER
ENTM
LOADEN
EN
VIN_26
VIN_25
VIN_24
VIN_23
IMON
FLTB
PG
OV
VOUT_13
AVIN
VOUT_14
VOUT_15
VOUT_16
VOUT_17
VOUT_18
VOUT_19
VIN_21_22
VOUT_20
S
G
D
PG
FAULT#
GND_C2
GND_C1
GND_B2
CDLY
GATE
OUT_D6
OUT_D4
OUT_C6
OUT_C4
OUT_B6
OUT_B4
OUT_A4
ISENSEOV
UV
REG
EN#
CB
IN_D5
IN_C5
IN_C3
IN_B5
IN_B3
IN_A5
IN_A3
VCC
CA
21
21
21
2
12
1
2
1
2
1
2
1
2
1
2
1
2
1
2
1
2
1
2
1
2
1
2
1
2
1
2
1
2
12
1
2
1
2
1
21
2
1
2
1
R1857
21
21R3998
2
1
2
1
21
2
1
2121
PC2236
CA
CA
SHEETDATE
DEPARTMENT
SIZE
PROJECT DOCUMENT NUMBER REV
REVIEWER
DESIGNER
123
7 3 2 1 6 5 4
E
A
B
C
E
D
C
B
A
7 6 5 4
D
OUT
OUT
OUT
OUT
OUT
IN
IN
IN
R3997
R3996
R1854
C



Thu Sep 14 16:12:48 2023<NAME_2><NAME_1>MB FABCGT AMDV02153 OF 365
P1V8_AUXPVDD18_S5_P0P1V8_AUX81838115329150 153153811531500402LF05%EMPTY1/16W5%FM_ESPI_CPU0_ALERT_R_SELESPI_CPU0_ALERT_PLD_N0402LF0ESPI_CPU0_ALERT_P0_N0402LFESPI_CPU0_ALERT_NCHIPESPI_CPU0_ALERT_R1_N1/16WICESPI_CPU0_ALERT_PLD_NEMPTY1/16W4.7K5%0402LFEMPTY5%1/16W4.7KESPI_CPU0_ALERT_NSMLF25V0.1UF
SCM_SW
10%0402X7RNC7SB3157P6X
R80345
6
2
1
34
U8000
A
VCC
S
B0
GND
B1
21
21
2
1
2
1
2
1
R1197
SHEETDATE
DEPARTMENT
SIZE
PROJECT DOCUMENT NUMBER REV
REVIEWER
DESIGNER
123
7 3 2 1 6 5 4
E
A
B
C
E
D
C
B
A
7 6 5 4
D
IN
IN
OUT
IN
IN
OUT
R8036R8035
C8007
C



Thu Aug 24 10:14:42 2023<NAME_2><NAME_1>MB FABCGT AMDV02154 OF 365Blank
SHEETDATE
DEPARTMENT
SIZE
PROJECT DOCUMENT NUMBER REV
REVIEWER
DESIGNER
123
7 3 2 1 6 5 4
E
A
B
C
E
D
C
B
A
7 6 5 4
D
C



M.2OCP
Thu Sep 14 16:12:14 2023<NAME_2><NAME_1>MB FABCGT AMDV02155 OF 365
P3V3_AUXP3V3_AUXPVDD18_S5_P013313914428 55155155IRQ_OCP_SFF_WAKE_BUF_NIRQ_OCP_V3_2_WAKE_BUF_N5%5%1/16W 0402LF33CHIPCHIP1/16W 0402LF33M2_0_PEWAKE_R_N5%33IRQ_WAKE_NIRQ_WAKE_R_N5%33CHIP10K0402LFIRQ_LVC3_WAKE1/16W10KCHIP0402LF1%SMLFIRQ_LVC3_WAKE_NIRQ_LVC3_WAKEIC2N7002KDW2.2K0402LF
WAKE
2
1 R437
21R1311
2 1R1009
2
1
R994
21R6063
21R116
21R1005
41
52
36
Q4
D2D1
S2S1
G2G1
SHEETDATE
DEPARTMENT
SIZE
PROJECT DOCUMENT NUMBER REV
REVIEWER
DESIGNER
123
7 3 2 1 6 5 4
E
A
B
C
E
D
C
B
A
7 6 5 4
D
OUT
IN
IN
OUTIN
IN
C



Thu Aug 24 10:14:43 2023<NAME_2><NAME_1>MB FABCGT AMDV02156 OF 365Blank
SHEETDATE
DEPARTMENT
SIZE
PROJECT DOCUMENT NUMBER REV
REVIEWER
DESIGNER
123
7 3 2 1 6 5 4
E
A
B
C
E
D
C
B
A
7 6 5 4
D
C



Thu Aug 24 10:14:43 2023<NAME_2><NAME_1>MB FABCGT AMDV02157 OF 365Blank
SHEETDATE
DEPARTMENT
SIZE
PROJECT DOCUMENT NUMBER REV
REVIEWER
DESIGNER
123
7 3 2 1 6 5 4
E
A
B
C
E
D
C
B
A
7 6 5 4
D
C



Thu Aug 24 10:14:44 2023<NAME_2><NAME_1>MB FABCGT AMDV02158 OF 365Blank
SHEETDATE
DEPARTMENT
SIZE
PROJECT DOCUMENT NUMBER REV
REVIEWER
DESIGNER
123
7 3 2 1 6 5 4
E
A
B
C
E
D
C
B
A
7 6 5 4
D
C



Thu Sep 14 16:12:14 2023<NAME_2><NAME_1>MB FABCGT AMDV02159 OF 365P3V3_AUXP3V3_AUX
PVDD11_S3_P1
PVDD11_S3_P0 P3V3_AUX
PVDD11_S3_P1P3V3_AUXPVDD11_S3_P1
PVDD11_S3_P0PVDD11_S3_P0PVDD11_S3_P0PVDD11_S3_P1808315055
8083
55801502828 92 93 94 95 96 9792 93 94 95 96 9786 87 88 89 909198 99 100101102 103150150150150104 105 106 107 108 1098080808380
55
150808386 87 88 89 909115055 98 99 100101102 103104 105 106 107 108 1092828
RES R1295.1 & R1336.2 / R1296.1& R1337.2 CO-LAYOUTCPU I3C BYPASS, RES R566.2 & R990.1 / R567.2 & R991.1 CO-LAYOUT0EMPTYCPU I3C BYPASS, RES R564.2 & R988.1 / R565.2 & R989.1 CO-LAYOUTFM_I3C_CPU1_MUX1_OE_N0402LF1/16WSMLF0402LFI3C_SCM_3_R_SDAI3C_1_SPD_DDRGL_CPU1_R_SCLEMPTYPI3CSW12ZUAEX25V10%
FM_I3C_CPU0_MUX0_OE_N1%
00I3C_0_SPD_DDRAF_CPU1_R_SCL I3C_0_SPD_DDRAF_CPU1_SCLFM_I3C_CPU1_MUX0_SELEMPTYPI3CSW12ZUAEXI3C_SPD_DDRGL_CPU0_LVC1_SDA0.1UFI3C_SPD_DDRAF_CPU0_BYPASS_SDAI3C_SCM_0_R_SCLEMPTY EMPTY00I3C_0_SPD_DDRAF_CPU0_R_SCLI3C_0_SPD_DDRAF_CPU0_R_SDAI3C_SPD_DDRGL_CPU0_SDAI3C_SPD_DDRGL_CPU0_SCLX7R0.1UF10%25V
I3C MUX - DDR5 SPD
I3C_SPD_DDRAF_CPU0_SDAI3C_SPD_DDRAF_CPU1_SDA
ICIC25VIC0402I3C_SPD_DDRGL_CPU1_LVC1_SCL0402I3C_SCM_1_R_SDAI3C_SCM_2_R_SCLI3C_SCM_2_R_SDAI3C_SCM_3_R_SCLI3C_SPD_DDRGL_CPU1_SDAFM_I3C_CPU1_MUX1_SEL
0402FM_I3C_CPU0_MUX1_SELSMLF0402X7R10%SMLF0.1UF
I3C_SPD_DDRAF_CPU0_LVC1_SCLPI3CSW12ZUAEX0.1UF25V
X7RICFM_I3C_CPU1_MUX0_OE_N10%FM_I3C_CPU0_MUX0_SELI3C_SPD_DDRGL_CPU0_LVC1_SCLX7R0I3C_0_SPD_DDRAF_CPU1_SDA0I3C_1_SPD_DDRGL_CPU1_R_SDA
0I3C_SPD_DDRAF_CPU0_LVC1_SDA000I3C_0_SPD_DDRAF_CPU0_SCL0I3C_1_SPD_DDRGL_CPU0_SCL0 00I3C_SPD_DDRGL_CPU1_LVC1_SDA0EMPTYEMPTY0EMPTY0 0EMPTY0EMPTYI3C_SPD_DDRAF_CPU1_BYPASS_SDA00 000EMPTYI3C_SPD_DDRGL_CPU0_BYPASS_SCL0EMPTY0EMPTYI3C_SPD_DDRGL_CPU1_BYPASS_SCL0EMPTYI3C_SPD_DDRGL_CPU1_BYPASS_SDA1%1/16W1K1/16WEMPTY1K1%1/16W1%EMPTY1K0402LF
0402LF1/16WEMPTY1%1K0402LF1/16WEMPTY1K
0402LF1K1%
EMPTY1%1K0402LF1/16W1KEMPTY1%0402LF1/16W1/16WEMPTY0402LF1K1%1KEMPTY0402LF1/16WEMPTY1K0402LF1%EMPTY0402LF1%1K1/16W 1/16WEMPTY0402LF1K1%1/16W1%1K0402LF0402LFEMPTY1/16W1%1K1/16WEMPTY1K1%
EMPTYPI3CSW12ZUAEX0I3C_0_SPD_DDRAF_CPU0_SDAI3C_SCM_0_R_SDAI3C_SPD_DDRAF_CPU0_BYPASS_SCLFM_I3C_CPU0_MUX1_OE_NI3C_SPD_DDRAF_CPU0_SCLI3C_SCM_1_R_SCLI3C_1_SPD_DDRGL_CPU0_SDA1%I3C_0_SPD_DDRAF_CPU1_R_SDAI3C_SPD_DDRAF_CPU1_SCL0I3C_1_SPD_DDRGL_CPU1_SCLI3C_1_SPD_DDRGL_CPU1_SDA0 I3C_SPD_DDRGL_CPU1_SCL
CPU I3C BYPASS, RES R426.2 & R2310.1 / R427.2 & R2311.1 CO-LAYOUTSMLF0RES R1297.1 & R1330.2 / R1298.1 & R1331.2 CO-LAYOUTEMPTYI3C_1_SPD_DDRGL_CPU0_R_SDAI3C_1_SPD_DDRGL_CPU0_R_SCLCPU I3C BYPASS, RES R428.2 & R986.1 / R429.2 & R987.1 CO-LAYOUTI3C_SPD_DDRGL_CPU0_BYPASS_SDAEMPTYEMPTYRES R1299.1 & R1332.2 / R1300.1 & R1333.2 CO-LAYOUT1/16WEMPTYI3C_SPD_DDRAF_CPU1_LVC1_SCLI3C_SPD_DDRAF_CPU1_LVC1_SDAI3C_SPD_DDRAF_CPU1_BYPASS_SCLRES R1293.1 & R1334.2 / R1294.1 & R1335.2 CO-LAYOUT0402LF
R5020R5021
R5019 R5018
R5016R5017
R5014R5015
R5012R5013
R5011 R5010
R5009 R5008
R5007 R5006
21R1337
21R133621R990
21R991
21R1335
21R133421R988
21R989
21R987
21R986 21R1332
21R1333
21R1331
21R1330
21R2311
21R2310
2 1R567
2 1R566
2 1R564
2 1R565
2 1R429
2 1R428
2 1R427
2 1R426
10
9
6
5
7
8
4
3
2
1
U108
2
1
C1339
10
9
6
5
7
8
4
3
2
1
U107
2
1
C1338
2
1
C1337
10
9
6
5
7
8
4
3
2
1
U106
2
1
C1336
10
9
6
5
7
8
4
3
2
1
U105
2 1R1296
2 1R1295
2 1R1294
2 1R1293
2 1R1300
2 1R1299
2 1R1298
2 1R1297
D+
GND
1D-
VDD
S
OE#
D-
2D-
2D+
1D+
D+
GND
1D-
VDD
S
OE#
D-
2D-
2D+
1D+
D+
GND
1D-
VDD
S
OE#
D-
2D-
2D+
1D+
D+
GND
1D-
VDD
S
OE#
D-
2D-
2D+
1D+
2
1
2
1
2
1
2
1
2
1
2
1
2
1
2
1
2
1
2
1
2
1
2
1
2
1
2
1
2
1
2
1
CAD NOTE:
CAD NOTE:
CAD NOTE:
CAD NOTE:
CAD NOTE:
CAD NOTE:
CAD NOTE:
CAD NOTE:
SHEETDATE
DEPARTMENT
SIZE
PROJECT DOCUMENT NUMBER REV
REVIEWER
DESIGNER
123
7 3 2 1 6 5 4
E
A
B
C
E
D
C
B
A
7 6 5 4
D
BIOUT
BIOUT
BIOUT
OUTBI
ININ
ININ
ININ
ININ
IN
IN
BI
BI
INBI
INBI
BIIN
BIIN
INBI
BIIN
C



INTERNAL PUFROM 2ND SOURCE MUXFROM MAIN SOURCE MUX
TBCINTERNAL PUThu Sep 14 16:12:35 2023<NAME_2><NAME_1>MB FABCGT AMDV02160 OF 365
P3V3P3V3P3V3_AUX
P3V3_AUXPVDD18_S5_P0P3V3_AUXPVDD18_S5_P0PVDD18_S5_P0P3V3_AUXPVDD11_S3_P0P3V3_AUXP3V3P3V3PVDD11_S3_P0PVDD11_S3_P0160161160161150151160160160 161160 161
160 161160 161150151150151160160161160160161
160150151160150151160150151160160160160160SMB_CPU0_CPU1_APML_BUF2_SCL_R125V10%CHIPSMB_CPU0_CPU1_APML_SDA_R20SMB_CPU0_CPU1_APML_SCL_R2SMB_CPU0_CPU1_APML_BUF2_SDA_R100402LF0402LF0PU_U2_EN0.1UF25V10%PCA9617ADP0.1UFSMB_CPU0_CPU1_APML_BUF1_SCLEMPTYSMB_CPU0_CPU1_APML_BUF1_SDAEMPTYSMB_CPU0_CPU1_APML_SDAEMPTY0SMB_CPU0_CPU1_APML_BUF1_SDA_R2EMPTYEMPTYEMPTYEMPTYSMB_CPU0_CPU1_APML_SCL_R2SMB_CPU0_CPU1_APML_SDA_R20402LFEMPTY1/16W040225V0.1UF10%X7R5%1/16WEMPTY0402LF0402LF1K0402LF1/16W4.7KX7R0402X7R25V10%SMLFEMPTY
SMB_CPU0_CPU1_SEC_SDA_R2SMB_CPU0_CPU1_SEC_SCL_R2SMB_CPU0_CPU1_SEC_SCLSMB_CPU0_CPU1_SEC_SDA SMB_CPU0_CPU1_SEC_SDA_R1SMB_CPU0_CPU1_SEC_SCL_R1X7R040210%0.1UF00IC25V25V040210%X7R0.1UF
0402
I2C MUX - APML(1/2)PU_U96_EN4.7K1/16W0402LFEMPTY5%
5%SMLFPCA9617ADP
PU_U5_EN0402LF5%4.7KEMPTY1/16W5%4.7KEMPTY0402LF1/16W5%4.7K0402LFEMPTY1/16W1/16WEMPTY0402LF5%SMB_CPU0_CPU1_APML_BUF1_SDA_R2SMB_CPU0_CPU1_SEC_SCL_R2SMB_CPU0_CPU1_APML_BUF1_SCL_R2SMB_CPU0_CPU1_SEC_SDA_R2R256/R274 R257/R281 CO-LAYR140/R151 R150/R162 CO-LAY000SMB_CPU0_CPU1_APML_BUF1_SCL_R20EMPTY000SMB_CPU0_CPU1_APML_SCL4.7KSMLF0.1UFX7RICPCA9617ADPSMB_CPU0_CPU1_APML_BUF2_SCLSMB_CPU0_CPU1_APML_SDACHIPSMB_CPU0_CPU1_APML_BUF1_SCL_R1SMB_CPU0_CPU1_APML_BUF1_SDA_R104020402LFCHIPCHIP0SMB_CPU0_CPU1_APML_SCL0402LF0CHIP0SMB_CPU0_CPU1_APML_BUF2_SDASMB_CPU0_CPU1_APML_BUF2_SDA_R2SMB_CPU0_CPU1_APML_BUF2_SCL_R21%1/16WEMPTY4.7K1K1%EMPTYCHIP 0402LF0402LFSMB_CPU0_CPU1_APML_BUF2_SDA_R2SMB_CPU0_CPU1_APML_BUF2_SCL_R2
C2
2
1
R406
2
1
R368
2
1
R365
2
1
R361
R78
2
1
C26
2
1
C23
21R1153
21R1154
2
1
C612
2
1 C611
R322
U5
C3
R290
R201
R200
8 1
6 3
7 2
45
8 1
6 3
7 2
45
81
63
72
4 5
U2
U96
GND
SCLB
SDAB SDAA
SCLA
VCCB VCCA
EN
GND
SCLB
SDAB SDAA
SCLA
VCCB VCCA
EN
GND
SCLB
SDABSDAA
SCLA
VCCBVCCA
EN
21
21
21 21
21
21 2 1
21
21R162
21R151
2
1
2
1
21
21
21
21
2
1
2
1
2
1
2
1
2
1
CAD NOTE:CAD NOTE:
SHEETDATE
DEPARTMENT
SIZE
PROJECT DOCUMENT NUMBER REV
REVIEWER
DESIGNER
123
7 3 2 1 6 5 4
E
A
B
C
E
D
C
B
A
7 6 5 4
D
IN
IN
IN
IN
BI
IN
IN
BI
OUTOUT
BI
OUT
BI
OUT
OUTOUTOUT
BI
OUT
OUT
BI
IN
R140
R150
R789
R790
R1152
R1151 R256
R257
R281
R274
R206
R202
C



TBC
TBCADDR:0XE0(8-BIT)/0X70(7-BIT)U213 IS APML MUX MAIN SOURCEU4 IS APML MUX 2ND SOURCE
Thu Sep 14 16:12:15 2023<NAME_2><NAME_1>MB FABCGT AMDV02161 OF 365
PVDD18_S5_P0P3V3_AUXPVDD11_S3_P0 PVDD18_S5_P0PVDD11_S3_P1 PVDD18_S5_P1
P3V3_AUX82 8382 83161 54161 5428 16182 8328 16182 831612755 1611612716155551611615516154161542816116016028161161 27161 2716016116016116016116016116127161271615416154FM_APML_MUX2_OE_NSMB_APML_CPU0_MUX2_SCLFM_APML_MUX2_SELSMB_CPU0_CPU1_APML_MUX2_SDACHIP00402LFCHIPI3C_MUX_CPU0_VIO1UF10%EMPTYC0402EMPTY25VEMPTYEMPTY6.3V20%00 3333SMB_APML_CPU1_SDASMB_APML_CPU1_SCL3333R323/R326 R324/R325 CO-LAY10%X7R040225V0 0SMB_CPU0_SEC_SCL0X7R0.1UF040225V10%PI3CSW12ZUAEXFM_SEC_MUX_SELSMB_CPU0_SEC_R_SCLSMB_CPU0_SEC_R_SDA SMB_CPU0_SEC_SDAFM_SEC_MUX_OE_NSMB_APML_CPU0_SDA0402LF0SMB_CPU1_SEC_R_SCL1KCHIP0402LF1KCHIPSMB_CPU1_SEC_SDASMB_APML_CPU0_SCLSMB_CPU1_SEC_SCL0EMPTYEMPTY0 SMB_CPU1_SEC_SDASMB_CPU1_SEC_SCLSMB_APML_CPU1_SCLI2C MUX - APML(2/2)0000 1%1K1%1%CHIP1/16W1K1%1/16W0402LFCHIP1%1/16W1%1K1/16WCHIP0402LF1K1%1/16W0402LFSMB_APML_CPU1_SDAEMPTY0SMB_CPU1_SEC_R_SDA1K0402LFCHIP1/16W1%1K0402LFCHIP1/16W0402LFSMB_CPU0_SEC_SDAEMPTYSMB_CPU0_CPU1_SEC_SDA_R2SMB_CPU0_CPU1_SEC_SCL_R2SMLFICSMB_CPU0_SEC_SCLCHIP1/16WEMPTYEMPTY0 R337/R1157 R338/R1158 CO-LAYR327/R1156 R328/R1155 CO-LAY0SMLFSMB_APML_CPU0_R_SCLSMB_APML_CPU1_R_SCLIML3112-Y2B000NCG81/16W10K1%0402LFCHIPEMPTYEMPTYEMPTYSMB_APML_CPU0_SCLSMB_APML_CPU0_SDA10UFEMPTYEMPTYEMPTYC0402SMB_APML_CPU1_R_SDAEMPTYEMPTYSMB_APML_CPU0_R_SDASMB_CPU0_CPU1_APML_MUX1_SDASMB_CPU0_CPU1_APML_MUX1_SCLSMB_CPU0_CPU1_APML_SDA_R2SMB_CPU0_CPU1_APML_SCL_R2IC0.1UFSMLFPI3CSW12ZUAEXSMB_CPU0_CPU1_APML_SCL_R2SMB_CPU0_CPU1_APML_MUX2_SCL0402LF0SMB_CPU0_CPU1_APML_SDA_R20402LF0SMB_APML_CPU0_SCLCHIP00402LFSMB_APML_CPU0_MUX2_SDASMB_APML_CPU0_SDACHIP00402LFSMB_APML_CPU1_MUX2_SCLSMB_APML_CPU1_SCLCHIP0402LF0SMB_APML_CPU1_MUX2_SDASMB_APML_CPU1_SDACHIP
R1159
R1160
R1157
R1158
2
1
R367
2
1
R360
2
1
R362
21R1155
21R143
21R1161
21R1162
21R147
2
1
R370
2
1
R369
2
1
R363
2
1
R366
2
1
R359
21R1156
21R142
21R139
R5004
21R146
21R144
21R145
21R148
21R358
C9 C24
R338
R337
R328
R327
C11
C25
10
9
6
5
7
8
4
3
2
1
7
5
9
8
1
6
4
2
3
10
9
6
5
7
8
4
3
2
1
U4
U213
U6
D+
GND
1D-
VDD
S
OE#
D-
2D-
2D+
1D+
D+
GND
1D-
VDD
S
OE#
D-
2D-
2D+
1D+
TH_GND
LSDA_1||HSAHSCL
LSCL_0
LSDA_0
VIO
LSCL_1
VDD
HSDA
2
1
2
1
21 21
21R326
21
21 21 21 21
2
1
21 21
21 21
2
1
2
1
CAD NOTE:
CAD NOTE:
CAD NOTE:
R325
SHEETDATE
DEPARTMENT
SIZE
PROJECT DOCUMENT NUMBER REV
REVIEWER
DESIGNER
123
7 3 2 1 6 5 4
E
A
B
C
E
D
C
B
A
7 6 5 4
D
BI
BIOUT
OUT
ININ
ININ
BI
BI
BI
BIOUT
BIOUT
OUTOUT
OUTOUT
OUTOUT
OUTOUT
BI
BI
BI
INBI
BIIN
R324
R323
C



Thu Aug 24 10:14:46 2023<NAME_2><NAME_1>MB FABCGT AMDV02162 OF 365Blank
SHEETDATE
DEPARTMENT
SIZE
PROJECT DOCUMENT NUMBER REV
REVIEWER
DESIGNER
123
7 3 2 1 6 5 4
E
A
B
C
E
D
C
B
A
7 6 5 4
D
C



Thu Aug 24 10:14:47 2023<NAME_2><NAME_1>MB FABCGT AMDV02163 OF 365Blank
SHEETDATE
DEPARTMENT
SIZE
PROJECT DOCUMENT NUMBER REV
REVIEWER
DESIGNER
123
7 3 2 1 6 5 4
E
A
B
C
E
D
C
B
A
7 6 5 4
D
C



CPU0 UART1TO SCM UART1
Thu Sep 14 16:12:15 2023<NAME_2><NAME_1>MB FABCGT AMDV02164 OF 365
PVDD18_S5_P0P5V_AUX P3V3_AUXP3V3_AUXP3V3_AUXPVDD18_S5_P0PVDD18_S5_P0PVDD18_S5_P01641642716427 164 150 15116416481164164150151150151164164164164150 151 164164 27164 272716427 7616427164277616416433UART_LS_EN_R_N UART_LS_EN_N1/16W5%10K0402LFCHIP5%10K1/16W0402LFCHIP0402LF1/16W5%10KCHIP5%0402LF1/16W10KCHIP
1/16WCHIP5%10K0402LF
10K0402LFEMPTY5%1/16W5%1/16WEMPTY0402LF10K5%1/16WEMPTY0402LF10K1/16W5%0402LFEMPTY10K10K1/16WEMPTY5%0402LFUART_CPU0_SCM_UART1_R_RXUART_CPU0_SCM_UART1_RX0UART_CPU0_UART0_R_RXUART_CPU0_UART0_RX0 UART_CPU0_SCM_LVC3_UART1_TXUART_CPU0_SCM_LVC3_UART1_R_TX0UART_CPU0_LVC3_UART0_TXUART_CPU0_LVC3_UART0_R_TX0UART_CPU0_LVC3_UART0_RXUART_CPU0_LVC3_UART0_R_RX04.7K1/16WCHIP0402LF5%SMLFIC10%NX138BKSMLFUART_LS_ENIC50V25V 25VCONN4_HFK1040-L0P1L-7HIOX7R
UART LEVEL SHIFTTHLF220PFUART_CPU0_LVC3_UART0_TX220PFC040250V5%UART_VCC_J135%C04020402SN74AVC4T774PWR0.1UF10%X7R0402UART_CPU0_SCM_LVC3_UART1_TXUART_CPU0_SCM_LVC3_UART1_R_RXUART_CPU0_LVC3_UART0_TXUART_CPU0_LVC3_UART0_RXUART_CPU0_LVC3_UART0_R_RXUART_CPU0_SCM_LVC3_UART1_R_RX0.1UFUART_CPU0_UART0_RXUART_CPU0_SCM_UART1_RXUART_CPU0_UART0_TXUART_CPU0_SCM_UART1_TXUART_CPU0_UART0_TXUART_CPU0_SCM_UART1_TXUART_LS_EN_N164
21R1423
21R817
21R1425
21R818
21R819
2 1R1253
2
1
R822
2
1
R823
2
1
R824
2
1
R825
2
1
R813
2
1
R814
2
1
R815
2
1
R816
4
3
2
1
J13
2
1 C363
2
1 C364
2
1
R821
2
1C1352
2
1 C1354
2
1
R1419
G
Q61
21R820
S D
1516
9
10
8
7
2
1
11
12
13
14
6
5
4
3
U116
GATE
1
2
3
4
VCCA VCCB
B1
B2
B3
B4
GND
OE
DIR4
DIR3
A4
A3
A2
A1
DIR2
DIR1
DRAINSOURCE
SHEETDATE
DEPARTMENT
SIZE
PROJECT DOCUMENT NUMBER REV
REVIEWER
DESIGNER
123
7 3 2 1 6 5 4
E
A
B
C
E
D
C
B
A
7 6 5 4
D
IN
IN
INOUTINOUT IN
OUTINOUT
OUT
OUT
OUTOUTOUT
OUTOUT
OUT
IN
OUT
OUT
C



BIOS DBG MODE LEDThu Sep 14 16:12:16 2023<NAME_2><NAME_1>MB FABCGT AMDV02165 OF 365GNDP3V3_AUXP3V3_AUXLED (1/2)BIOS_DEBUG_MODELED_BIOS_DBG_MODE_NSMLFICNX138BKSMLFICNX138BK1KCHIP1/16W1%0402LFLED_BIOS_DBG_MODESMLFICLED_BLUELTST-C281TBKT-5ACHIP1%1/16W130LED_BIOS_DBG_MODE_R0402LF2816781
2
1
R1507
21R1444
G
Q30
G
Q29
CA
D9
S DS D
GATE
GATE
A C
DRAINSOURCEDRAINSOURCE
SHEETDATE
DEPARTMENT
SIZE
PROJECT DOCUMENT NUMBER REV
REVIEWER
DESIGNER
123
7 3 2 1 6 5 4
E
A
B
C
E
D
C
B
A
7 6 5 4
D
IN
C



BOOT-UP READY LEDSMERR LEDP12V POWER LEDP5V_AUX POWER LEDThu Sep 14 16:12:15 2023<NAME_2><NAME_1>MB FABCGT AMDV02166 OF 365
P1V8_AUX
P5V_AUX
P3V3_AUXP3V3_AUX
P5V_AUX
P3V3_AUXP3V3_AUXP3V3_AUXP3V3_AUXP1V8_AUX
8181283428FM_SMERR_BUF_R_LED_N00025V0.1UF1/16W4701%LTST-C281TBKT-5A0402LFCHIP1/16W470SMLFLTST-C281TBKT-5ASMLFP12V_ALL_PWROK_NICLED_BLUEPU_P12V_ALL_PWROK_LEDSMLFICPU_SMERR_LEDLTST-C190KSKT-PSMERR_LED2490402LF1%CHIP1/16WLED_YELLOW1/16W2N7002KDWSMERR_LED_NSMLFICIC5%SMLF
0402LF1%CHIPICP5V_STBY_PWR_LEDLED_BLUE
1300402LF1%CHIP1/16W1/16WLTST-C281TBKT-5ALED_BLUESMLFIC2N7002KDWBOOT_RDY_LED_NSMLFCHIPPU_BOOT_RDY_LED4.7K 4.7K
P12V_ALL_PWROKFM_SMERR_LED_N10%0402SMLFSMLF25VSN74LVC1G07DBVRSN74LVC1G07DBVR10%ICX7RICX7RBOOT_RDY_LED
LED (2/2)NX138BK
0402IC0.1UFBOOT_RDY_R1_N5%CHIP4.7K1/16WCHIP5%4.7K1/16W5%CHIPFM_BIOS_POST_CMPLT_NBOOT_RDY_BUF_R_LEDBOOT_RDY_BUF_LEDFM_SMERR_BUF_LED_NEMPTY0BOOT_RDY_H
G
Q12
C A
D46
21
R1208
21
R1207
C A
D49
21R941
21
R934
4
5
13
2
U86
2
1 C219
4
5
13
2
U82
2
1 C218
21
R936
21 R935
41
52
36
Q112
1
R945
41
52
36
Q22
1
R944
2
1
R947
C A
D6
C A
D5
21R948
2
1
R946
21
R950
S D
AC
AC
GATE
AC
AC
NC
Y
GND
A
VCC
NC
Y
GND
A
VCC
D2D1
S2S1
G2G1
D2D1
S2S1
G2G1
DRAINSOURCE
SHEETDATE
DEPARTMENT
SIZE
PROJECT DOCUMENT NUMBER REV
REVIEWER
DESIGNER
123
7 3 2 1 6 5 4
E
A
B
C
E
D
C
B
A
7 6 5 4
D
IN
IN
IN
IN
C



ON: ENABLE JTAG MUX TO HDTON: DISABLE REMOTE DEBUG (DEFAULT)OFF: ENABLE REMOTE DEBUGOFF: DISABLE ALL POWER ON (DEFAULT)FPGA_DEBUG_SW_SPARESWITCH DEFAULT IS OFFOFF:NORMAL(DEFAULT)ON:FRUON: NORMAL OPERATION (DEFAULT)OFF: BIOS USB FLASH RECOVERY MODEBIOS RECOVERYON:FPGA_DEBUG_LEDPASSWORD CLEAR
OFF: BIOS USB FLASH RECOVERY MODEON: NORMAL OPERATION (DEFAULT)HW ASD ENON: DISABLE CPU0 DEBUGOFF: CPU0 PRESENT FOR DEBUG (DEFAULT)CPU0 BYPASS CHAIN CONTROLBIOS USB RECOVERYBMC SPD REMOTE DEBUGOFF: BMC SPD REMOTE DEBUG DISABLED (DEFAULT)FORCE POWER ONON: ENABLE ALL POWER ONBMC JTAG SELON: BMC SPD REMOTE DEBUG ENABLEDCPU1 BYPASS CHAIN CONTROLOFF: CPU1 PRESENT FOR DEBUG (DEFAULT)ON: DISABLE CPU1 DEBUGOFF:POST LED(DEFAULT)FPGA_DEBUG_LED_CTRLSWITCH DEFAULT IS OFFOFF: ENABLE JTAG MUX TO PLD (DEFAULT)OFF: NORMAL (DEFAULT)ON: PASSWORD CLEARThu Sep 14 16:12:15 2023<NAME_2><NAME_1>MB FABCGT AMDV02167 OF 365
167 PVDD18_S5_P0P1V8_AUXP1V8_AUXP1V8_AUXP1V8_AUXP3V3_AUXP3V3_AUXP1V8_AUXP1V8_AUX
P3V3_AUXP1V8_AUXPVDD18_S5_P0P3V3_AUX P1V8_AUXP1V8_AUXP3V3_AUX167811678116781167 27811678181167 28 165167 82167 82167167167 16781167 2816716781811672816516728
1671678227
1678216727811678154
16781
1678116716781167167 172
16717281167
81167
FM_FORCE_ALL_PWRON_ONFM_FORCE_ALL_PWRON
00 1/16WEMPTYU124_VCCSN74LVC1G07DBVRSMLFSW20S_DHNF-10F-Q-T/RFM_SPD_CPU0_SWITCH_CTRL_NFM_FORCE_ALL_PWRONFM_BIOS_USB_RECOVERYFPGA_DEBUG_SW_SPAREBIOS_DEBUG_MODEFM_PRSNT_CPU0_NFM_PRSNT_CPU1_NFM_FORCE_ALL_PWRON_ONPU_BIOS_USB_RECOVERYDEBUG JUMPERPU_FPGA_DEBUG_LED_CTRL FPGA_DEBUG_LED_CTRLFM_PASSWORD_CLEAR_NPD_BIOS_DEBUG_MODEPU_FPGA_DEBUG_SW_SPAREBMC_JTAG_SELMECH0402LFSMLF1/16W5%CHIP0402LF5%
1/16WCHIP5%4.7K0402LF
BIOS_DEBUG_MODEFM_PASSWORD_CLEAR_N2.2K1/16WPU_BIOS_USB_RECOVERY0402LF5%CHIPFM_PRSNT_CPU1_NPRSNT_CPU0_N
FM_PRSNT_CPU0_NFM_BIOS_USB_RECOVERYBMC_JTAG_SELPRSNT_CPU1_N
FM_SPD_CPU0_SWITCH_CTRL_N
1001000402LF1001%CHIP1/16W100K CHIP
CHIP100KFPGA_DEBUG_LED_CTRLCHIP10K
10K10K
10K10K10K10K1K100KPU_FPGA_DEBUG_LED_CTRLFPGA_DEBUG_SW_SPAREPU_FPGA_DEBUG_SW_SPAREJTAG_BMC_OE10K00IC
1%1000402LFEMPTY1/16W
1/16WEMPTY0402LF1%0.1UF25VX7R0402
JTAG_BMC_OEFM_JTAG_BMC_R_OE100FM_JTAG_BMC_R_OE10K
2121 21
2
1
R6107
2
1
R6106
2
1
R1356
2
1
R1357
2
1
R1358
2
1
R6040
2
1
R6042
2
1
R22
2
1R1265
2
1
R733
2
1
R1264
2
1
R5071
2
1R6044
2
1
R1262
R734
2
1
R1261
21R1508
R744
R6041R6043R8
U124
R8019
R8017 R8018
C693
20
19
18
17
16
15
14
13
12
11
10
9
8
7
6
5
4
3
2
1
4
5
13
2
SW1
ON
10
9
20
19
18
17
16
15
8
7
6
5
14
13
12
11
4
3
2
1
NC
Y
GND
A
VCC
2
1
2
1
2
1
21
21
2
1
SHEETDATE
DEPARTMENT
SIZE
PROJECT DOCUMENT NUMBER REV
REVIEWER
DESIGNER
123
7 3 2 1 6 5 4
E
A
B
C
E
D
C
B
A
7 6 5 4
D
IN
IN
OUT
IN
OUT
OUT
OUT
OUT
OUT
OUT
OUT
OUT
OUT
INOUT
OUT
IN
IN
OUTOUT
OUTOUT
OUTOUTOUTOUTOUTOUT
IN
OUT
OUT
OUT
OUT
IN
C



Thu Aug 24 10:14:50 2023<NAME_2><NAME_1>MB FABCGT AMDV02168 OF 365Blank
SHEETDATE
DEPARTMENT
SIZE
PROJECT DOCUMENT NUMBER REV
REVIEWER
DESIGNER
123
7 3 2 1 6 5 4
E
A
B
C
E
D
C
B
A
7 6 5 4
D
C



P3V3_AUX DISCHARGE
VTH(MAX)=2.2VVTH(MAX)=1VP12V_AUX DISCHARGEVTH(MAX)=1VVTH(MAX)=2.2VThu Sep 14 16:13:12 2023<NAME_2><NAME_1>MB FABCGT AMDV02169 OF 365
P12V_AUXP12V_AUXP12V_AUXP12V_AUXP3V3_AUXP3V3_AUXP3V3_AUX_DSCEMPTYPSMNR58-30YLHSMLFP3V3_AUX_DSC_G2DMP2035U-7EMPTYEMPTY0402LFEMPTY1/16W11.5K0402LFP3V3_AUX_DSC_VOL
2512LFP12V_AUX_DSCEMPTYPSMNR58-30YLHSMLFEMPTY0402LF1/16W1%EMPTY0402LFEMPTY1/16W0402LFEMPTYP12V_AUX_DSC_G2EMPTY2W1%1010K
EMPTY1/16W1%10K0402LFP3V3_AUX_DSC_S1P12V_AUX_DSC_S1DMP2035U-7SMLFSMLF
EMPTYC080520%
P12V_AUX_DSC_VOL
0402LF
1KEMPTY1K1%0402LFEMPTYEMPTYDISCHARGE CIRCUIT0402LF
P12V_AUX_DSC_G130K1%10M1/16WEMPTY1/16W1%1%
2K0402LF11.5K1%EMPTY1/16W30K1%1/16W1/16W1%BAT54CWSMLFEMPTY
16V22UFP3V3_AUX_DSC_G1C0805EMPTY20%16V1%1/16WBAT54CWSMLFEMPTY2512LF101%2W22UF
3
1
2
S D 4
4S D3
1
2
G5321 5321G
Q7003
Q7001
C
B
A
C
B
A S D
D1
G1
S3 S2 S1
4
D1
G1
S3 S2 S1
4S D
G1253 1253GU60Q7002Q7000SGDSGD
2
1
2
1
2
1
2
1
2
1 2
1
2
1
2
1
2
1
2
1
2
1
2
1
U57
2
1
2
1
SHEETDATE
DEPARTMENT
SIZE
PROJECT DOCUMENT NUMBER REV
REVIEWER
DESIGNER
123
7 3 2 1 6 5 4
E
A
B
C
E
D
C
B
A
7 6 5 4
D
R1092
R1052
R954
R896
C1114
R1475
R1481
R1480
R1474R1049
R1007
C1113
R855
R700
C



Thu Aug 24 10:14:51 2023<NAME_2><NAME_1>MB FABCGT AMDV02170 OF 365Blank
SHEETDATE
DEPARTMENT
SIZE
PROJECT DOCUMENT NUMBER REV
REVIEWER
DESIGNER
123
7 3 2 1 6 5 4
E
A
B
C
E
D
C
B
A
7 6 5 4
D
C



JTAG ENABLE JUMPER1-2 DISABLE(DEFAULT)2-3 ENABLETBCJTAG ENABLE JUMPER1-2 DISABLE(DEFAULT)2-3 ENABLETBCRSVDCPLDCPLDCPUThu Sep 14 16:12:15 2023<NAME_2><NAME_1>MB FABCGT AMDV02171 OF 365
P3V3_AUXP3V3_AUXP3V3_AUXP3V3_AUXP3V3_AUX
P3V3_AUXP3V3_AUXP3V3_AUXP3V3_AUXP3V3_AUXTP_JTAG_SCM_SLOT3_R_TDIJTAG_SCM_PLD_R_TDOJTAG_SCM_MUX_R_TDOTP_JTAG_SCM_SLOT3_R_TDOR6102 PLACE CLOSE TO U212JTAG_SCM_PLD_TMSJTAG_SCM_PLD_TCKCHIP221%221%22CHIPCHIP5%4.7K0402LF4.7KCHIP5%1/16W0402LF1/16W5%4.7KEMPTY0402LFEMPTY5%4.7K0402LF1/16WJTAG_SCM_MUX_TDO1/16WX7RSMLFSN74LVC1G07DBVR0402LF04020402LF0402LF25V16V10K0.1UF0.1UF10K10K10K 10K 10K10K1%10%10%1%1%1% 1%1%1%1%EMPTYEMPTYCHIPX7RCHIP CHIPCHIP1/16W1/16W 1/16WJTAG_SCM_TDOJTAG_SCM_TDIJTAG_SCM_TMSJTAG_SCM_TCKJTAG_SCM_MUX_TDI
JTAG - BMC MUX
10KEMPTY EMPTY1%0402LFEMPTY1%1%10K10K1/16W0402LF10K
X7R1/16WSCM_JTAG_MUX_S00402LF1/16WEMPTY5%4.7KC0402CHIPCHIP4.7K4.7K5%225%0402LF0402LF4.7KCHIP4.7K5%PU_U212_EN_NPD_U212_EN_N1/16WIO
74LV4052PWSMLFICJTAG_SCM_TCKCHIPJTAG_SCM_TDISCM_JTAG_MUX_S0_R2JTAG_SCM_TDOSCM_JTAG_MUX_S11%1%JTAG_SCM_PLD_TDOJTAG_SCM_PLD_TDIJTAG_SCM_TMSC0402FW_RECOVERY_R10%16VCHIPTP_JTAG_SCM_SLOT3_R_TMS5%1/16W0.1UFJTAG_SCM_PLD_R_TCKTP_JTAG_SCM_SLOT3_R_TCKJTAG_SCM_PLD_R_TMSR6101 PLACE CLOSE TO U160U160_EN_NSCM_JTAG_MUX_S0_R1CHIPJTAG_SCM_MUX_TDICHIPJTAG_SCM_MUX_R_TMS JTAG_SCM_MUX_TMS0CHIPJTAG_SCM_MUX_R_TCK JTAG_SCM_MUX_TCK05%5%0CHIP0402LF5%0CHIPJTAG_SCM_MUX_TDOSMLFJTAG_SCM_PLD_R_TDIJTAG_SCM_MUX_R_TDI00 80858085172 171171151151171171150171150171 172171172
8017115015117117115180 80858580171150150 172171172171172171172171CONN3_210-HP1-030BR1U212_EN_NIC74LV4052PW0402LF1/16WTHLFIOCONN3_210-HP1-030BR15%EMPTY172171JTAG_SCM_MUX_TCKJTAG_SCM_MUX_TMSPU_U160_EN_NPD_U160_EN_NTHLF1/16W
R1739
R6182
R1313
R6181
2
1
R1318
21 R6102
21 R6101
2
1
R1342
21R1740
21R1741
21R1736
21R1737
21R1742
21R1738
2
1 C553
4
5
13
2
U99
2
1
R1343
21R1743
2
1
R1658
2
1
R1659
2
1
R1729
2
1
R1730
2
1C194
2
1C1554
2
1
R1744
2
1
R1748
2
1
R1745
2
1
R1746
2
1
R1747
2
1
R1727
2
1
R1728
2
1
R1735
2
1
R1731
2
1
R1734
3
2
1
3
2
1
7
16
9
10
8
6
3 4
2
5
1
13
11
15
14
12
7
16
9
10
8
6
3 4
2
5
1
13
11
15
14
12
JP6001
JP6000
U212
U160
1
2
3
1
2
3
NC
Y
GND
A
VCC
VCC
1Y2
1Y1
1Z
1Y0
1Y3
S0
S1
GND
VEEE_N
2Y1
2Y32Z
2Y2
2Y0
VCC
1Y2
1Y1
1Z
1Y0
1Y3
S0
S1
GND
VEEE_N
2Y1
2Y32Z
2Y2
2Y0
21
2
1
2
1
2
1
CAD NOTE:
CAD NOTE:
SHEETDATE
DEPARTMENT
SIZE
PROJECT DOCUMENT NUMBER REV
REVIEWER
DESIGNER
123
7 3 2 1 6 5 4
E
A
B
C
E
D
C
B
A
7 6 5 4
D
OUT
OUT
OUT
OUT
ININ
IN
OUTOUT
IN
OUT
IN
IN
IN
IN
OUTOUTOUTOUT
OUTOUTOUTOUT
C



BMCH:BMCL:HDT
HDTTO JTAG BUF
Thu Sep 14 16:12:16 2023<NAME_2><NAME_1>MB FABCGT AMDV02172 OF 365
PVDD18_S5_P0P3V3_AUXPVDD18_S5_P0PVDD18_S5_P0PVDD18_S5_P0PVDD18_S5_P0PVDD18_S5_P0PVDD18_S5_P0PVDD18_S5_P0P3V3_AUXPVDD18_S5_P0P3V3_AUX1731738381278217227822782 81173172 173172172172172172
1501518017217217217217116717117217117117317381810.01UF50V10%EMPTYC04020.1UFR6108 PLACE CLOSE TO U146X7R10%16VC0402R6111 PLACE CLOSE TO U146X7RBSS138KJTAG_BMC_OE_N0402LF1/16WSN74AVC2T245RSWRJTAG_BMC_R_D_OE0402LFJTAG_DBREQ_N221%JTAG_TRST_N221%PRSNT_HDT_R_NPRSNT_HDT_N33HDT_CPU0_XTRIG_L5CPU0_XTRIG_L533HDT_HDR_TRST_N33HDT_CPU0_XTRIG_L6CPU0_XTRIG_L633HDT_CPU0_XTRIG_L7CPU0_XTRIG_L733CPU0_HDT_CONN_TESTEN33331%0402LF1KCHIP1/16W1%1K1%0402LF1KCHIP1/16W1%1K1%1K1%1K1%1KJTAG_TDO0HDT_HDR_TDO_RHDT_HDR_TDOCHIP0 HDT_HDR_R_TCK0HDT_HDR_R_TMS0HDT_HDR_R_TDI005%CHIP4.7K4.7K5%1/16WCHIPSMLFPLACE U146 AND U147 CLOSER
JTAG_TDI_RJTAG_TDO_R1SMLF
SMLFSMLFPLACE CAP AND RES NEAR J54
JTAG - HDT & BMC MUXPLACE U149 AND U148 CLOSER
JTAG_TCKHDT_HDR_TMSHDT_HDR_TCKHDT_HDR_TDOHDT_HDR_TDIHDT_HDR_DBREQ_NJTAG_TMS_RJTAG_TRST_R_NJTAG_TCK_RJTAG_DBREQ_R_NJTAG_SCM_DBREQ_NJTAG_SCM_TRST_NHDT_HDR_DBREQ_NHDT_HDR_TMSHDT_HDR_TRST_NHDT_HDR_TCKHDT_HDR_DBREQ_R_NHDT_CPU0_HDT_CONN_TESTENHDT_HDR_TRST_N_R
JTAG_SCM_MUX_TDIJTAG_BMC_OEICX7R
IC
X7RX7RX7RX7RIOX7RNPONPONPOX7RICICX7RX7RIC10%10%10%10%5%5%5%10%10%10%10%0.1UFSCONN20_HSU2101-L0000-7H0.001UF33PF33PF33PF0.1UFSN74AVC4T774PWR0.1UFSN74AVC2T245RSWR16V50V50V50V50V50V50V50V16V16V16V16VC0402C0402C0402C0402040204020402C0402C0402C0402C0402SMLFSN74AVC4T774PWRSMLF0.1UF16VJTAG_SCM_MUX_TDO0.1UFHDT_HDR_TDI0.1UF10%X7RJTAG_SCM_MUX_TMSJTAG_SCM_MUX_TCKC0402JTAG_TDICHIP025VX7R10%04020.1UFJTAG_TMS05%05%HDT_HDR_RESET_NHDT_HDR_PWROK10%10%C0402C04020.001UF 0.001UF 0.001UF50V0.01UF
2
1 C86
21R6111
21
R6108
21R1528
2
1 C85
21R478
21R1620
21R476
21R477
2
1
R1621
2019
1817
1615
1413
1211
109
87
65
43
21
J54
2
1 C604
2
1 C605
2
1 C87
21R1353
21R1352
2
1 C551
2
1
R1630
2
1
R1628
2
1
R1627
2
1
R1626
21R1632
21R1631
2
1 R1629
2
1
R1624
21R1354
G
Q62
2
1
R617
21R1634
21
R1619
2
1
R1622
2
1
C1503
6
7
2
3
1
10
4
5
9
8
U146
2
1
C1505
2
1
C1506
2
1
C1504
21R1625
2
1
C1507
1516
9
10
8
7
2
1
11
12
13
14
6
5
4
3
U148
1516
9
10
8
7
2
1
11
12
13
14
6
5
4
3
U149
2
1
C1508
2
1 C1510
2
1 C1511
2
1 C1512
2
1
C1509
21R1636
21R1635
21R1633
6
7
2
3
1
10
4
5
9
8
U147
S D
C8006
DIR1
A2
A1
VCCA
VCCB
B1
B2
GND
OE_#
DIR2
VCCA VCCB
B1
B2
B3
B4
GND
OE
DIR4
DIR3
A4
A3
A2
A1
DIR2
DIR1
VCCA VCCB
B1
B2
B3
B4
GND
OE
DIR4
DIR3
A4
A3
A2
A1
DIR2
DIR1
2019
1817
1615
1413
1211
109
87
65
43
21
DIR1
A2
A1
VCCA
VCCB
B1
B2
GND
OE_#
DIR2
2
1
CAD NOTE:
CAD NOTE:CAD NOTE:
CAD NOTE:
CAD NOTE:
SHEETDATE
DEPARTMENT
SIZE
PROJECT DOCUMENT NUMBER REV
REVIEWER
DESIGNER
123
7 3 2 1 6 5 4
E
A
B
C
E
D
C
B
A
7 6 5 4
D
IN
OUT
IN
OUT
IN
ININ
IN
ININ
OUTOUT OUT IN
ININ
IN OUTOUT
OUT
BIBI
OUTBI
OUTOUT
INOUT
IN
OUT
IN
OUT
C



CPU0/1 TDI/TDO DAISY CHAIN
CPU0CPU1
Thu Sep 14 16:12:16 2023<NAME_2><NAME_1>MB FABCGT AMDV02173 OF 365PVDD18_S5_P0 PVDD18_S5_P0PVDD18_S5_P0PVDD18_S5_P0 PVDD18_S5_P0PVDD18_S5_P1174172
17217217217281174172
2727275454545427810R6103 PLACE CLOSE TO U152SMLFJTAG_CPUX_TDOJTAG_TDIC0402X7RC0402C0402C0402C0402C0402
16V16V
16V16VSN74AVC4T774PWR
0.1UF0.1UFSN74AVC2T245RSWR0.1UF0.1UF0.1UF
10%10%
10%10%IC
X7RICX7RX7RX7RJTAG_TMSJTAG_DBREQ_NJTAG_TRST_NJTAG_TCKCPU0_JTAG_BUF_OE
JTAG - BUFFER
SMLF
U152_OE_NR6109 PLACE CLOSE TO U1524.7K5%0402LFCHIP1/16WJTAG_CPUX_TDI_R1 JTAG_CPUX_TDICHIP0JTAG_TDO JTAG_TDO_R
CHIP1%22JTAG_P0_R_TMS JTAG_CPU0_TMSCHIP1%22JTAG_P0_R_TRST_N JTAG_CPU0_TRST_NCHIP1%22JTAG_P0_R_TCK JTAG_CPU0_TCKCHIP1%22JTAG_P1_R_TCK JTAG_CPU1_TCKCHIP1%22JTAG_P1_R_TMS JTAG_CPU1_TMSCHIP1%22JTAG_P1_R_TRST_N JTAG_CPU1_TRST_NCHIP1%22JTAG_CPU1_DBREQ_NCHIP1%22JTAG_P0_R_DBREQ_N JTAG_CPU0_DBREQ_NCPU1_JTAG_BUF_OE0.1UFJTAG_P1_R_DBREQ_N16V10%X7RSMLF16V10%ICSN74AVC4T774PWR
R6109
21 R6103
2
1
R1637
2
1
C1513
2
1
C1518
6
7
2
3
1
10
4
5
9
8
U152
2
1
C1515
2
1
C1517
21R1645
21R1644
21R1643
21R1642
1516
9
10
8
7
2
1
11
12
13
14
6
5
4
3
U151
21R1638
21R1640
21R1639
21R1641
2
1
C1514
2
1
C1516
1516
9
10
8
7
2
1
11
12
13
14
6
5
4
3
U150
VCCA VCCB
B1
B2
B3
B4
GND
OE
DIR4
DIR3
A4
A3
A2
A1
DIR2
DIR1
DIR1
A2
A1
VCCA
VCCB
B1
B2
GND
OE_#
DIR2
VCCA VCCB
B1
B2
B3
B4
GND
OE
DIR4
DIR3
A4
A3
A2
A1
DIR2
DIR1
21
CAD NOTE:
CAD NOTE:
SHEETDATE
DEPARTMENT
SIZE
PROJECT DOCUMENT NUMBER REV
REVIEWER
DESIGNER
123
7 3 2 1 6 5 4
E
A
B
C
E
D
C
B
A
7 6 5 4
D
IN
IN
IN
IN
OUT
OUT
IN
OUT
OUTOUTOUT
OUTOUTOUT
OUT
ININ
IN
C



CPU1 TDICPU0 TDI
H:CPU1CPU1 TDOH:CPU0L:BYPASSL:BYPASSCPU0 TDO
Thu Sep 14 16:12:16 2023<NAME_2><NAME_1>MB FABCGT AMDV02174 OF 365
PVDD18_S5_P0PVDD18_S5_P0PVDD18_S5_P0PVDD18_S5_P0PVDD18_S5_P0PVDD18_S5_P0PVDD18_S5_P0PVDD18_S5_P05417327548181271730010%5%0CHIPJTAG_CPU1_R_TDI JTAG_CPU1_TDIC0402CHIP5%0JTAG_CPU0_R_TDI0402LF1K1%CHIP1/16W0402LF1K1%CHIP1/16W0402LFCHIP1%1K1/16W0402LF1K1%CHIP1/16WJTAG_CPUX_TDO0CHIPJTAG_CPU0_TDO_CPU1_TDI_R1JTAG_CPU0_BYPASS_R1R6110 PLACE CLOSE TO U154JTAG_CPUX_TDO_RJTAG_CPU0_BYPASSR6105 PLACE CLOSE TO U13R6104 PLACE CLOSE TO U13EMPTYC0402JTAG_CPU0_TDIJTAG_CPU0_TDO_CPU1_TDIC04020.1UF16VSMLFSN74AUC2G66DCTRSMLFSMLFSMLFSMLF
JTAG - TDI/TDO
JTAG_CPU1_BYPASSJTAG_CPU1_TDOFM_PLD_CPU1_PRSNT_HDT_NFM_PLD_CPU0_PRSNT_HDT_NCPU1_HDT_BYPASS_SELCPU0_HDT_BYPASS_SELICICX7RICICX7RX7RIC10%10%0.1UFSN74AUC2G66DCTRSN74AUC2G66DCTR0.1UF0.1UFBSS138KBSS138K
16V16V50V16VC0402C040210%0.01UF10%X7RJTAG_CPU0_TDOICJTAG_CPUX_TDISN74AUC2G66DCTRSMLF
R6110
21R6105
21 R6104
G Q64
G Q63
2
1
C1523
2
1
C1522
21 R1651
8
43
65
7 2
1
U154
2
1
R1650
2
1
R1649
8
43
65
7 2
1
U142
1
C1521
8
43
65
7 2
1
U13
2
1
C1519
2
1
R1647
2
1
R1646 2
1 C1520
21 R1648
8
43
65
7 2
1
U153
S D
S D
2B
1B
GND
VCC
2C
2A
1C
1A
2B
1B
GND
VCC
2C
2A
1C
1A
2B
1B
GND
VCC
2C
2A
1C
1A
2B
1B
GND
VCC
2C
2A
1C
1A
21
CAD NOTE:
CAD NOTE:
CAD NOTE:
SHEETDATE
DEPARTMENT
SIZE
PROJECT DOCUMENT NUMBER REV
REVIEWER
DESIGNER
123
7 3 2 1 6 5 4
E
A
B
C
E
D
C
B
A
7 6 5 4
D
IN OUT
IN
OUT
OUT
IN
IN
IN
C



Thu Aug 24 10:14:54 2023<NAME_2><NAME_1>MB FABCGT AMDV02175 OF 365Blank
SHEETDATE
DEPARTMENT
SIZE
PROJECT DOCUMENT NUMBER REV
REVIEWER
DESIGNER
123
7 3 2 1 6 5 4
E
A
B
C
E
D
C
B
A
7 6 5 4
D
C



TBCADDRESS : 0XA2 (8-BIT) / 0X51 (7-BIT)
Thu Sep 14 16:12:46 2023<NAME_2><NAME_1>MB FABCGT AMDV02176 OF 365
1/16WP3V3_AUXP5V_AUXP5V_AUXP3V3_AUXP5V_AUX
P3V3_AUXP3V3_AUXP3V3_AUX176178179251180180180180
246178235
176178179251179251176178180180180180180180179251176178180180SMB_USB_CPU0_HUB1_SDACHIP1/16WUSB3_HUB1_CYP1/16WEMPTYUSB_CPU0_HUB1_MODE_SEL0USB_CPU0_HUB1_MODE_SEL1USB3_HUB1_CYP1/16W1%USB3_HUB1_CYPUSB_CPU0_ADD_A21/16WEMPTY0402LF10K1%USB3_HUB1_CYP10K1/16WCHIP1%0402LFUSB3_HUB1_CYP10K1%1/16WCHIP0402LF0402LFEMPTY1%0402LF0402LFUSB3_CPU0_BMC_HUB1_TX_DNUSB2_CPU0_P0_HUB1_R_DPUSB2_CPU0_P0_HUB1_R_DNC0805X6S20%16V22UFUSB3_HUB1_CYP01/16WUSB_CPU0_HUB1_VBUS_DSCYUSB3304-68LTXIUSB3_HUB1_CYP
USB3_HUB1_CYP25VX6SC04021UFUSB3.0 EXT HUB MAIN(1/2)0402LFMISC26MHZUSB3_HUB1_CYPUSB3_HUB1_CYP0402LF1/16W0402LF0402LF1/16WUSB3_HUB1_CYPUSB3_CPU0_BMC_TX_C1_DP
USB3_HUB1_CYPRST_USB_CPU0_HUB1_R_N10%USB3_HUB1_CYPC04021%CHIP1/16W33.2RST_USB_HUB_NUSB3_HUB1_CYPXTAL_USB_CPU0_HUB1_XOUTSMLFUSB3_HUB1_CYP10K1%10KUSB3_HUB1_CYP USB3_HUB1_CYP10K1%CHIP0402LF 0402LFCHIP1/16W1%0402LFCHIP1%SMB_USB_CPU0_HUB1_SDASMB_USB_CPU0_HUB1_SCLUSB3_HUB1_CYP6.04K10K1%1/16WCHIPTP_CPU0_USB_HUB1_SUSPENDCHIPUSB3_CPU0_BMC_TX_C1_DNUSB3_CPU0_BMC_RX_HUB1_DPUSB3_CPU0_BMC_RX_HUB1_DNUSB2_CPU0_P0_R1_DPCHIPUSB3_HUB1_CYPUSB_CPU0_HUB1_VBUS_USUSB3_HUB1_CYP10K1%10K0402LF0402LF1/16WCHIP1%ICUSB3_CPU0_BMC_HUB1_TX_DP
15PF0402
USB2_CPU0_P0_R1_DNIC1/16WSMLFUSB_CPU0_HUB1_RREF_SS2001%CHIP1/16WUSB_CPU0_HUB1_RREF_USB2USB3_HUB1_CYP5%C0G50VPU_CPU0_USB_HUB_RESERVED1PU_CPU0_USB_HUB_RESERVED212PF50VC0G5%XTAL_USB_CPU0_HUB1_XIN10K1%0402LF0402LFEMPTY1/16W0.1%47K
CHIP0402LF5%040210%X7R50V470PFUSB3_HUB1_CYPUSB3_HUB1_CYP10K1%EMPTY0402X7R10%25VSMLF0.1UFPU_CPU0_USB_HUB_OVRCURRPU_CPU0_USB_HUB_PWR_EN0402LFSMB_USB_CPU0_HUB1_SCL33.2 EMPTYUSB3_HUB1_CYP1%1%33.21%1/16WEMPTYUSB3_HUB1_CYP10KUSB3_HUB1_CYP1/16W10KUSB3_HUB1_CYP10KEMPTY1/16W1%USB3_HUB1_CYP1%1/16WCHIPUSB_CPU0_ADD_A0USB_CPU0_ADD_A1USB3_HUB1_CYPUSB3_HUB1_CYP0402LF1KPD_USB_CPU0_WPSMB_USB_CPU0_HUB1_SDA_R2SMB_USB_CPU0_HUB1_SCL_R2USB3_HUB1_CYPEMPTY1/16W1%10KUSB3_CPU0_BMC_RX_C1_DPUSB3_CPU0_BMC_RX_C1_DNUSB3_HUB1_CYPM24128-BWMN6TPUSB3_HUB1_CYP0402LF10KCHIP0402LF1%0402LF10KEMPTY1/16WUSB3_HUB1_CYPUSB3_HUB1_CYP10KCHIP0402LF1%1/16W0402LFEMPTY10KUSB3_HUB1_CYP1/16W1%
R6227 R6226
R6224
R6225
R4452
R6216R6214
C6083
R6220R6218
R6217
C6028C6027R4450
C2317
7
4
8
5
6 3
2
1
3 1
4 2
54
55
17 18
6
5
9
8
57
58
20
2
26
31
22
21
29
30
25
24
23
33
32
40
TH
11
12
15
14
67
68
38
39
35
36
65
64
41
42
45
44
62
63
47
48
51
50
60
59
U6003
Y9
U6001
E0
E1
E2
VSSSDA
SCL
WC#
VCC
X2
G2 G1
X1
1/2
EPAD
RESERVED1
RESERVED2
RESET#
OVRCURR
PWR_EN
NC_25
RREF_USB2
RREF_SS
US_TXM
US_TXP
US_RXM
US_RXP
US_DM
US_DP
VBUS_US
GND
MODE_SEL1
MODE_SEL0
XTL_OUT
XTL_IN
SUSPEND
I2C_DATA
I2C_CLK
VBUS_DS
DS4_TXM
DS4_TXP
DS4_RXM
DS4_RXP
DS4_DM
DS4_DP
DS3_TXM
DS3_TXP
DS3_RXM
DS3_RXP
DS3_DM
DS3_DP
DS2_TXM
DS2_TXP
DS2_RXM
DS2_RXP
DS2_DM
DS2_DP
DS1_TXM
DS1_TXP
DS1_RXM
DS1_RXP
DS1_DM
DS1_DP
MODE SEL GPIO.RREF.PWR & OVRCUR UP STREAMDOWN STREAMI2CCLOCK & RESET
2
1
2
1
2
1
2
1
2
1
2
1
2
1
2
1
2
1
21 21
2
1
R6223
2
1
2
1
2
1
2
1
2
1
2
1
2
1
2
1
2
1
2
1
2
1
2
1
2
1
21R6203
21R6202
2
1
2
121
2
1
2
1
21R4451
C93 C91
R6215R6213
R6221R6219
R6222
R6209
R6208
R6207 R6206 R6205 R6204
SHEETDATE
DEPARTMENT
SIZE
PROJECT DOCUMENT NUMBER REV
REVIEWER
DESIGNER
123
7 3 2 1 6 5 4
E
A
B
C
E
D
C
B
A
7 6 5 4
D
BI
BIIN
BI
OUTOUT
BI
IN
ININ
BIBI
IN
ININ
OUTOUT
R4453
C



Thu Sep 14 16:12:46 2023<NAME_2><NAME_1>MB FABCGT AMDV02177 OF 365
P3V3_AUX_CPU0_USB_AVDD33P1V2_AUXP1V2_AUXP1V2_AUXP3V3_AUXP1V2_CPU0_USB_DVDD12
P1V2_AUXUSB3_HUB1_CYPC0402X6S25V10%1UFUSB3_HUB1_CYP0.1UF25V10%X7R040210%X7R0.01UF50VX7R10%C0402USB3_HUB1_CYP50V10%X7R0.001UFUSB3_HUB1_CYP0.01UF50VX7RC040210%C0402USB3_HUB1_CYP0.001UF50V10%X7RUSB3_HUB1_CYP0.01UF50V10%USB3_HUB1_CYP0.001UF10%0.01UF50V10%X7RC0402USB3_HUB1_CYPC0402X7RC04020.001UF10%50VX7RUSB3_HUB1_CYPX7R10%50V0.01UFC0402X7R10%50V0.01UF0.001UFC0402X7R50V10%USB3_HUB1_CYPUSB3_HUB1_CYP50V10%0.01UFC0402X7RC04020.01UF10%X7RUSB3_HUB1_CYP50V0.001UFX7R50VC040210%USB3_HUB1_CYPUSB3_HUB1_CYP50V0.001UFC040210%X7R0.01UF50VX7R10%C0402USB3_HUB1_CYPX7R0.001UF50V10%C0402USB3_HUB1_CYP0.01UF10%X7RC040204020.01UF25V10%X7RUSB3_HUB1_CYP10%25VX6S1UFX6S10%25VC0402USB3_HUB1_CYP22UFC06036.3V20%X6SX7R10%50VUSB3_HUB1_CYPX7RUSB3_HUB1_CYPUSB3_HUB1_CYPUSB3_HUB1_CYPX7R10%25V0.1UF 0.01UFC0402USB3_HUB1_CYPX7RUSB3_HUB1_CYP0402USB3_HUB1_CYPC04020.01UF25V0.1UF10%50V0.1UFX7R50V0.1UFC0402USB3_HUB1_CYPUSB3_HUB1_CYPX7R25V1UFX6S10%BLM21PG221SN1DUSB3_HUB1_CYP
USB3.0 EXT HUB MAIN(2/2)
C0402X7RC040250V10%X7R25V10%1UFX6S50VIND0.01UFC0402SMLFICCYUSB3304-68LTXIINDSMLF6.3V22UFC0603X6S20%USB3_HUB1_CYPUSB3_HUB1_CYP040210%C0402USB3_HUB1_CYP25V10%X7R25V0.1UF10%0.01UF0.01UF50VX7R10%10%25VUSB3_HUB1_CYPUSB3_HUB1_CYP0402C0402X7R10%X7R0.01UF50VUSB3_HUB1_CYP040210%50VBLM21PG221SN1DSMLF10%X7RC0402USB3_HUB1_CYP22UF6.3V20%C04021UFUSB3_HUB1_CYP0402X7R0.1UF10%25VUSB3_HUB1_CYP0402X6SC0603040210%25VX7R0.1UFUSB3_HUB1_CYPUSB3_HUB1_CYPC04020.01UF10%X7R50V10%X7R25V0.1UF0402USB3_HUB1_CYP50VC0402X7R10%USB3_HUB1_CYP0.1UFUSB3_HUB1_CYP50VX7R10%50VC04020.001UFUSB3_HUB1_CYPUSB3_HUB1_CYPC0402USB3_HUB1_CYP0.1UF0402X7R10%25VUSB3_HUB1_CYP10%25VX6S1UFUSB3_HUB1_CYPC040222UF6.3V20%X6SC0603USB3_HUB1_CYP50VX7R10%0.001UFC04020.01UFUSB3_HUB1_CYP04020.1UFUSB3_HUB1_CYPX7RC0402USB3_HUB1_CYPX6S20%6.3V22UFC0603USB3_HUB1_CYPUSB3_HUB1_CYP25V10%USB3_HUB1_CYPUSB3_HUB1_CYPC040250V0.01UFC0402USB3_HUB1_CYP
C6067 C6071 C6073 C6075C6069
C6062C6060C6058C6056C6054
C6037C6036C6032 C6033 C6034 C6035
21
21
28
19
43
37
13
7
49
27
3
1
66
61
56
4
53
52
46
34
16
10
L6001
L6000
U6001
1 2
1 2 2/2
AVDD12_5
AVDD12_4
AVDD12_3
AVDD12_2
AVDD12_1
VDD_IO
AVDD33_4
AVDD33_3
AVDD33_2
AVDD33_1
DVDD12_7
DVDD12_6
DVDD12_5
AVDD12_6
DVDD12_4
DVDD12_8
DVDD12_3
VDD_EFUSE
DVDD12_2
DVDD12_1
AVDD_CLK AVDD_RXVDD_IOAVDD33AVDD_TXDVDD12
2
1
2
1
2
1
2
1
2
1
2
1
2
1
2
1
2
1
2
1
2
1
2
1
2
1
2
1
2
1
2
1
2
1
2
1
2
1
2
1
2
1
2
1
2
1
2
1
2
1
2
1
2
1
2
1
2
1
2
1
2
1
2
1
2
1
2
1
2
1
2
1
2
1
2
1
2
1
2
1
2
1
2
1
2
1
2
1
2
1
2
1
2
1
2
1
2
1
2
1
2
1
2
1
2
1C6040
SHEETDATE
DEPARTMENT
SIZE
PROJECT DOCUMENT NUMBER REV
REVIEWER
DESIGNER
123
7 3 2 1 6 5 4
E
A
B
C
E
D
C
B
A
7 6 5 4
D
C6082C6081C6080
C6068 C6070 C6072 C6074 C6076
C6077 C6078 C6079
C6066C6065C6064
C6063C6061C6059C6057C6055C6038 C6039
C6031C6030
C6052 C6053C6051C6050C6049C6048
C6047C6046
C6045C6044C6043C6042
C6041
C



MFR:TIMFR PN:TUSB8042AIRGCRQPN:AL0080420003RD2NDQPN:AL005734000MFR PN:USB5734T/MMFR:MRP
Thu Sep 14 16:12:48 2023<NAME_2><NAME_1>MB FABCGT AMDV02178 OF 365
USB3_HUB2_TIP1V2_CPU0_USB2_DVDD12
P3V3_AUXP3V3_AUXP3V3_AUX_CPU0_USB2_AVDD33P1V2_CPU0_USB2_DVDD12P3V3_AUXP1V2_CPU0_USB2_DVDD12P3V3_AUXP1V2_CPU0_USB2_DVDD12P3V3_AUXP3V3_AUXP3V3_AUXP3V3_AUXP3V3_AUXP3V3_AUXP5V_AUX
P3V3_AUX P3V3_AUX
P3V3_AUXP1V2_CPU0_USB2_DVDD12P3V3_AUX_CPU0_USB2_AVDD33180180180180180180178246176178235180180180180
178
180246176178235180179251176176179251
CHIPSMLFTUSB8042AIRGCRUSB3_HUB2USB_HUB2_TI_USB_VBUS_MRP_RESET_N
USB3_HUB2_TIUSB3_HUB2_MRPUSB3_HUB2_MRP1/16WUSB_HUB2_TI_USB_R1_MRP_RBIAS12K1%0402LFCHIPUSB3_CPU0_BMC_HUB2_TX_DPUSB3_CPU0_BMC_HUB2_TX_DN05%0402LFCHIP0USB_HUB2_TI_USB_DP_DN3_MRP_VDD12USB_HUB2_TI_USB_SSRXM_DN3_MRP_VDD12USB3_CPU0_BMC_RX_C2_DNUSB3_CPU0_BMC_RX_C2_DPUSB2_CPU0_P0_HUB2_R_DNUSB2_CPU0_P0_HUB2_R_DPUSB_HUB2_MRP_CFG_STRAP0402LF0402LFUSB_HUB2_TI_USB_SSRXP_DN1_MRP_VDD12USB3_HUB2_MRPUSB_HUB2_TI_USB_DP_DN1_MRP_CFG_STRAPUSB3_HUB2_MRPCHIPUSB3_HUB2_MRPCHIP0402LF
USB3_HUB2_MRPUSB3_HUB2_MRPUSB3_HUB2_TIUSB_HUB2_TI_NC_MRP_ATEST0402LFCHIP0402LFUSB3_HUB2_MRP0402LFUSB3_HUB2_TIEMPTY0402LFUSB3_HUB2_TI0402LF CHIP5%CHIP5%1/16W00402LF05%USB_HUB2_TI_OVERCUR3_MRP_CFG_BC_ENUSB_HUB2_TI_OVERCUR2_MRP_PROG_FUNC55%CHIPUSB3_HUB2_TI10K1UF0402LF1%0402LF1%10KCHIPUSB3_HUB2_TI0402LFUSB3_HUB2_TIUSB3_HUB2_TI0402LFCHIPUSB_HUB2_TI_OVERCUR1CHIP5%0USB3_HUB2_MRP5%EMPTY10K1/16WCHIP5%0RST_USB_HUB_N10%USB3_HUB2_MRPUSB3_HUB2_MRP0402LF25VX6SCHIP5%0402LF0USB3_HUB2_TI47KUSB3_HUB2_TIEMPTY1/16W0.1%1%EMPTY0402LFUSB_HUB2_TI_GRSTZ_MRP_PROG_FUNC10402LF4.7K1/16W0402LF1%USB3_HUB2_TIUSB3_HUB2_TIUSB_HUB2_TI_PWRCTL_POLUSB3_HUB2_MRP5%01K1/16WUSB3_HUB2_MRPUSB3_HUB2_TI0402LFUSB3_CPU0_BMC_TX_C2_DPUSB3_CPU0_BMC_RX_HUB2_DNUSB3_CPU0_BMC_RX_HUB2_DPUSB2_CPU0_P0_R2_DNCHIPIC
USB3.0 EXT HUB 2ND(1/2)USB_HUB2_TI_NC_MRP_ATEST
5%
0402LF1/16WCHIP9.53K1%
0
0
90.9K1/16WCHIP1%
10K1%CHIP0402LF1/16W5%0
X6S10%10UF16V5%05%0
1%4.7K1/16W0402LF1/16WCHIP1%4.7K4.7KCHIP0402LF1%10KCHIP200K1%1/16WCHIP0402LF5%CHIP0CHIP5%0402LF0CHIP0402LF0
0
0402LF200K1/16W1%CHIP200KEMPTY1%1/16W0402LFUSB2_CPU0_P0_R2_DP0RST_USB_HUB_N10K1%47K0402LFEMPTY0.1%1/16WEMPTYUSB_HUB2_MRP_RESET_NUSB3_HUB2_MRPUSB3_HUB2_MRP0402LFC0805CHIPUSB3_HUB2_TICHIP10K0402LFUSB3_HUB2_MRPCHIP0402LF5%1K0402LF1%1/16WUSB_HUB2_TI_USB_VBUSUSB3_HUB2_MRPUSB3_HUB2_TI1%0402LFUSB3_HUB2_TICHIP0402LF1/16WEMPTYUSB_HUB2_MRP_VBUS_DETUSB3_HUB2_MRPCHIP1%10K0402LF1/16WUSB3_CPU0_BMC_TX_C2_DNUSB_HUB2_TI_PWRCTL_POL_MRP_VBUS_DETCHIP0CHIP5%USB3_HUB2_TIC04020402LF1%10KSMB_USB_CPU0_HUB1_SCL0402LFUSB_HUB2_TI_OVERCUR25%CHIP1/16W1/16WCHIP5%0402LF0USB_HUB2_TI_OVERCUR1_MRP_PROG_FUNC45%CHIP0USB3_HUB2_TI0402LFSMB_USB_CPU0_HUB1_SDA00402LFCHIPEMPTY200K0402LFUSB_HUB2_TI_OVERCUR3USB3_HUB2_TIUSB3_HUB2_MRP1/16WUSB3_HUB2_MRPUSB_HUB2_MRP_CFG_BC_ENUSB3_HUB2_MRP5%01%0402LFUSB3_HUB2_TICHIP0402LFCHIP1/16WUSB3_HUB2_MRPUSB_HUB2_TI_OVERCUR4_MRP_I2C_SLV_CFG1USB_HUB2_TI_OVERCCUR4USB3_HUB2_MRPUSB3_HUB2_TIUSB3_HUB2_MRP1%USB3_HUB2_MRP
USB_HUB2_TI_PWRCTL2_MRP_VDD12USB_HUB2_TI_PWRCTL3_MRP_VDD3310K1%CHIP0402LFUSB_HUB2_MRP_I2C_SLV_CFG1USB_HUB2_MRP_PROG_FUNC6USB_HUB2_TI_TESTUSB_HUB2_TI_TEST_MRP_PROG_FUNC6USB_HUB2_TI_USB_DM_DN3_MRP_VDD330USB3_HUB2_MRP5%5%USB3_HUB2_MRP5%USB3_HUB2_MRP0402LFUSB3_HUB2_MRPUSB_HUB2_TI_USB_SSRXM_DN4_MRP_VDD12
R6329
R6320
R6289
R6298 R6297
R6301
R6302
R6303
C6089
R6315
R6318
R6319
R6325
R6328 R6333
R6272
R6273
R6327
R6326
48
55
26
19
11
3
56
27
20
12
4
58
29
22
14
6
59
30
23
15
7
64
53
24
17
9
1
54
25
18
10
2
TH49
41
32
33
35
36
43
44
47
46
60
50
U6002
1/2
NC_1 USB_R1
TEST
OVERCUR4z
OVERCUR3z
OVERCUR2z
OVERCUR1z
GRSTz
PWRCTL_POL
PWRCTL4||BATEN4
PWRCTL3||BATEN3
PWRCTL2||BATEN2
PWRCTL1||BATEN1
USB_VBUS
USB_SSTXM_DN4
USB_SSTXP_DN3
USB_DM_DN2
USB_SSTXM_DN1
USB_SSTXP_DN1
USB_SSRXM_DN1
USB_DP_DN1
USB_SSTXM_UP
USB_DP_UP
TH_VSS
USB_SSRXP_DN3
USB_SSRXM_DN4
USB_SSRXP_DN4
USB_DM_DN4
USB_DM_DN1
USB_SSTXP_DN4
USB_SSRXP_DN1
USB_DP_DN2
USB_SSRXP_UP
USB_DP_DN3
USB_DP_DN4
USB_SSRXM_DN3
USB_DM_UP
USB_SSTXP_UP
USB_SSTXM_DN3
USB_DM_DN3
USB_SSTXM_DN2
USB_SSTXP_DN2
USB_SSRXP_DN2
USB_SSRXM_DN2
USB_SSRXM_UP
2
1
2
1
2
1
R6332
2
1
R6331
21 2 1
21
2
1
2
1
2
1
21
21
21
2
1
2
1
21
21
21
21
2
1
2
1
2
1
21
21
21 21
21
2
1
21
2
1
21
21
21
21
21
2
1
2
1
C6088
21
2
1
2
1
21
21
2
1
21
21
2
1
2
1
2
1
21
2
1
2
1
R6312 R6310
R6311
R6288
R6287
R6286
R6285
R6296
R6295
R6300
R6299
R6259
R6258
R6263R6264
R6268
R6270
R6313
R6314
R6266
R6261
R6322
R6321 R6317
R6316
R6324
R6323
R6271
SHEETDATE
DEPARTMENT
SIZE
PROJECT DOCUMENT NUMBER REV
REVIEWER
DESIGNER
123
7 3 2 1 6 5 4
E
A
B
C
E
D
C
B
A
7 6 5 4
D
BI
BI
IN
OUT
ININ
ININ
OUTOUT
BIBI
BIBI
BI
IN
IN
IN
R6330
C



XTAL:
MFR PN:USB5734T/MMFR PN:TUSB8042AIRGCR3RDQPN:AL0057340002NDMFR:TIMFR:MRPQPN:AL008042000
TI=24MHZMRP=25MHZThu Sep 14 16:12:47 2023<NAME_2><NAME_1>MB FABCGT AMDV02179 OF 365P3V3_AUX_CPU0_USB2_AVDD33P3V3_AUX
P3V3_AUX
P1V2_CPU0_USB2_DVDD12P1V2_AUXP3V3_AUX
P3V3_AUXP3V3_AUXP3V3_AUX_CPU0_USB2_AVDD33P3V3_AUXP3V3_AUXP3V3_AUXP1V2_CPU0_USB2_DVDD12P3V3_AUX_CPU0_USB2_AVDD33USB3_HUB2_MRPUSB3_HUB2USB3_HUB2USB3_HUB20402LFSMLF24MHZUSB3_HUB25%50V0402LF0402MISC1/16WXTAL_USB_CPU0_HUB2_XINXTAL_USB_CPU0_HUB2_XOUT50V27PF5%NPO101/16W0402LFCHIP1%BLM21PG221SN1D179EMPTY1KUSB3_HUB2_MRPUSB_HUB2_TI_HS_SUSPEND0402LF1761782512511761781791%CHIP1MUSB3_HUB2USB_HUB2_MRP_CFG_NON_REM
USB3.0 EXT HUB 2ND(2/2)USB3_HUB2USB3_HUB2C0402USB3_HUB2USB3_HUB2USB3_HUB2USB3_HUB225V0.1UF10UF50V50V04020.01UF0.05PCOGX6SX7R10%10%X7R10%X7RC0402USB3_HUB250V50V25V1PFUSB3_HUB21PFCOGX7R50V10%C040210%X7R25V10%0402COG0.1UF0.01UF50VUSB3_HUB20.01UFC0402X7R0.05P0.05PUSB3_HUB2USB3_HUB2040210%X7RC04020.01UF50V25V 50VUSB3_HUB20.05P10%10%0.05P10%25V0.1UF10%10UF25V0.05P50V1PFUSB3_HUB2C0402C04020402X7RX7R1PF040210%0.1UF50VUSB3_HUB2USB3_HUB20.01UF1PFC0402USB3_HUB2USB3_HUB250VC0402X6SUSB3_HUB2C080510%USB3_HUB2BLM21PG221SN1D
USB3_HUB2_TI01/16W1%EMPTY0402LF10KCHIP1%1/16WUSB_HUB2_TI_VDD33_MRP_PRT_CTL4_GANGPWREMPTYUSB3_HUB2_MRPUSB3_HUB2_MRP1%1/16W0402LFEMPTY10K1/16W1%0402LF10KUSB3_HUB2_TI0USB3_HUB2_TI5%USB3_HUB2_TI0USB_HUB2_TI_VDD_MRP_USB3DN_RXDP4USB_HUB2_TI_VDD_MRP_USB3DN_TXDP4USB_HUB2_TI_VDD_MRP_USB3DN_RXDM15%USB_HUB2_TI_VDD_MRP_USB3DN_TXDM1
0C040210%
SMLF
INDINDSMLF1UF10%X7R25VX7R0402X7RC0402X7RCOG0.01UF1PFX7RX7RCOGC0402C0402COG0402X7RC0402C0402COG0402C04020.05PC04020.1UF040225VX7R10%C0402X7R10%C0402C0805
4.7K1/16WCHIP1%0402LFEMPTY1%4.7K05%5%0CHIP05%5%0CHIP0402LF05%5%0402LF0CHIP1%0402LF1%0 0402LF5%CHIP1%0402LF05%CHIP0USB3_HUB2_TI200KSMB_USB_CPU0_HUB1_SDA1/16W5%0402LF0402LF1/16WSMB_USB_CPU0_HUB1_SCL5%0402LFCHIPUSB3_HUB2_TI200KUSB3_HUB2_TICHIPCHIP0402LFUSB3_HUB2_MRP1K1%USB3_HUB2_TIUSB_HUB2_TI_FULLPWRMGMTZ_MRP_PROG_FUNC3EMPTYUSB3_HUB2_TIUSB3_HUB2_TIUSB3_HUB2_TI0402LF CHIPUSB_HUB2_TI_VDD_MRP_USB3DN_TXDP30402LF CHIP0402LF0402LF5%USB_HUB2_TI_VDD33_MRP_PROG_FUNC70402LF0402LF05%USB3_HUB2_TICHIPCHIPCHIPUSB3_HUB2_TIUSB_HUB2_MRP_PRT_CTL4_GANGPWRUSB3_HUB2_MRP1K0402LF1%4.7K0402LFCHIP1/16WUSB3_HUB2_TIUSB3_HUB2_TICHIPUSB3_HUB2_TISMB_USB_HUB2_TI_SDA_MRP_PRT_CTL2SMB_USB_HUB2_TI_SCL_MRP_PRT_CTL1USB_HUB2_TI_HS_SUSPEND_MRP_CFG_NON_REMICTUSB8042AIRGCRUSB3_HUB2
SMLFUSB_HUB2_TI_GANGED_MRP_I2C_SLV_CFG0USB_HUB2_TI_GANGED1/16W1PF0.05PCOGX6SUSB3_HUB225V10%50V50VUSB3_HUB2USB3_HUB2_MRPCOG0.01UFCHIP0.01UF50V50VUSB3_HUB2USB_HUB2_MRP_I2C_SLV_CFG00.1UF25V0.1UF10%0.05P1PFUSB3_HUB2 USB3_HUB2 USB3_HUB20.1UF25VUSB3_HUB210%50V1PFUSB3_HUB2 USB3_HUB250V0.01UFUSB3_HUB20.1UF25VUSB3_HUB210%50VUSB3_HUB2_MRPUSB3_HUB2
USB3_HUB2_TIUSB3_HUB2_TI0402LFUSB_HUB2_TI_SMBUSZ_MRP_PROG_FUNC21K1%1/16W1/16WEMPTYEMPTY1/16W0402LFUSB_HUB2_TI_GANGED_MRP_I2C_SLV_CFG0NPO0402LFUSB3_HUB2_TI27PF0402
XI
XO
VDD_31
VDD_21
VDD_57
VDD_5
VDD_8
AUTOENz||HS_SUSPEND
VDD_51
VDD33_63
SMBUSz||SS_SUSPEND
SCL||SMBCLK
GANGED||SMBA2||HS_UP
FULLPWRMGMTz||FULLAUTOz||SMBA1||SS_UP
VDD33_52
VDD33_34
VDD33_16
VDD_28
SDA||SMBDAT
VDD_13
R6284
R6257
R6309
R6307
R6306
R6308
R6281
R6282
R6277
R6278
R6294
R6292
R6283
C6119 C6120 C6121C6115 C6116 C6117C6112 C6113 C6114C6109 C6110 C6111C6106 C6107 C6108
C6103 C6104C6100 C6101C6097 C6098C6093 C6095 C6094
3 1
4 2
61
57
51
31
28
21
13
8
5
63
52
34
16
39
37
42
40
45
21
21
62 38
Y6000
U6002
L6004
L6003
1 2
1 2
X2
G2 G1
X1
2/2
2
1
2
1
2
1
21
21
2
1
2
1
2
1
2
1
21
21
21
21 21
21
2
1
2
1
21
21
21 2
1
21
2
1
21
2
1 2
1
2
1
21
21
2
1
2
1C6118
2
1
2
1
2
1
2
1
2
1
2
1
2
1
2
1
2
1
2
1
2
1
2
1
2
1
2
1
2
1
2
1C6105
2
1
2
1
2
1
2
1
2
1
2
1
2
1C6096
2
1
2
1
2
1
2
1
2
1
2
1C6092
R6260
R6304
R6305
R6279
R6280 R6265
R6274
R6269
R6262
R6275
R6276
R6267
R6290
R6291
SHEETDATE
DEPARTMENT
SIZE
PROJECT DOCUMENT NUMBER REV
REVIEWER
DESIGNER
123
7 3 2 1 6 5 4
E
A
B
C
E
D
C
B
A
7 6 5 4
D
OUT
IN
BI
BI
C6091C6090
R6293
C6102C6099
C



TO 2ND HUBFROM 2ND HUBTO 1ST HUBFROM CPUTO 2ND HUBTO 1ST HUBTO SCM
TO CPUTO SCMFROM CPUFROM 2ND HUBFROM SCM
FROM 1ST HUBFROM 2ND HUBTO 2ND HUBFROM 1ST HUBTO 1ST HUBFROM 1ST HUB
Thu Sep 14 16:12:47 2023<NAME_2><NAME_1>MB FABCGT AMDV02180 OF 365
1%1/20WEMPTY0201LF49.91/20WEMPTY49.90201LF1%49.90201LF1/20WEMPTY1%1%1/20WEMPTY0201LF49.949.91/20W0201LF1%EMPTY0201LF1/20WEMPTY1%49.9176176176
17617617817817815015017617817815017815017817817817817617629176176
29
292929 150150
29176176178178USB3_CPU0_BMC_HUB1_TX_DPUSB3_CPU0_BMC_HUB1_TX_DNUSB3_HUB2USB3_HUB225V0.1UF10%USB3_HUB1USB3_HUB10402X7R25V0.1UFC6023/C6025 C6024/C6026 CO-LAYOUTUSB3_HUB2USB3_HUB2USB3_HUB1USB2_CPU0_P0_HUB1_R_DPUSB3_HUB1CHIP1/20W0
USB3_CPU0_BMC_RX_C1_DPUSB3_CPU0_BMC_RX_C1_DNUSB3_CPU0_BMC_RX_C2_DPDIFF BUS_0.33UFDIFF BUS_0.33UFDIFF BUS_0.33UFDIFF BUS_0.33UF10%C6019/C6021 C6020/C6022 CO-LAYOUTUSB3_HUB2USB3_CPU0_BMC_HUB2_TX_DPUSB3_CPU0_BMC_HUB2_TX_DNUSB3_CPU0_BMC_TX_BUF_C_DNUSB3_CPU0_BMC_TX_BUF_C_DPCHIP0201LF0201LFUSB2_CPU0_P0_HUB1_R_DN0USB2_CPU0_P0_HUB2_R_DPUSB2_CPU0_P0_HUB2_R_DN
USB3_HUB2USB3_HUB2USB3_CPU0_BMC_RX_DNUSB3_CPU0_BMC_RX_C2_DNUSB3_HUB1USB3_HUB1C04026.3VX6SUSB3_CPU0_BMC_RX_DP
0201LF0201LFUSB2_CPU0_P0_R2_DNUSB2_CPU0_P0_R2_DPUSB3_CPU0_BMC_TX_C2_DNUSB3_CPU0_BMC_TX_C2_DPUSB3_CPU0_BMC_TX_C1_DNUSB3_CPU0_BMC_TX_C1_DPUSB2_CPU0_P0_DNUSB2_CPU0_P0_R1_DPUSB2_CPU0_P0_R1_DN5%01/20W
USB3_CPU0_BMC_RX_HUB_C_DNUSB3.0 EXT HUB USB SIGNAL SELECT
0402LF511/16WEMPTY5%0402LF1/16WEMPTY5%51USB2_CPU0_P0_DP0201LFUSB3_CPU0_BMC_TX_DPUSB3_CPU0_BMC_TX_DNR6194/R6196 R6195/R6197 CO-LAYOUT0USB2_HUB_EXT_DNUSB2_HUB_EXT_DP0CHIP5%0201LF0201LFCHIP
USB3_CPU0_BMC_RX_HUB_C_DPDIFF BUS_0.33UFDIFF BUS_0.33UF6.3V10%C0402X6SUSB3_CPU0_BMC_RX_HUB1_DPC6015/C6017 C6016/C6018 CO-LAYOUTUSB3_HUB1USB3_CPU0_BMC_RX_HUB1_DNUSB3_HUB10.1UF040210%USB3_HUB2USB3_CPU0_BMC_RX_HUB2_DNUSB3_CPU0_BMC_RX_HUB2_DPUSB3_HUB2X7R25V
CHIP00USB3_HUB1CHIPCHIP0201LFCHIPR6190/R6192/R339 R6191/R6193/R340 CO-LAYOUT0USB3_HUB1USB3_HUB2USB3_HUB2C6003/C6013/R341 C6004/C6014/R342 CO-LAYOUT04020.1UF 25V X7R10%USB3_HUB125V0.1UFUSB3_HUB1USB3_HUB2
21
21
21
21 21
21
C6017
C6018
C6003
C6004
C6013
C6014
C6026
C6025
C6024
C6023
21
21
21
21 21
21
C6022
C6021
C6020
C6019 C6016
C6015
21 21
2
1
2
1
R341
21 21
21 21
21 21
21 21
2
1
2
1
2
1
2
1
2
1
2
1
21 21
21 2121 21
21 21
CAD NOTE:
CAD NOTE:
CAD NOTE:
CAD NOTE:
CAD NOTE:
CAD NOTE:
R339
R6197R6196
R6194R6195R6190R6191
R6193R6192
SHEETDATE
DEPARTMENT
SIZE
PROJECT DOCUMENT NUMBER REV
REVIEWER
DESIGNER
123
7 3 2 1 6 5 4
E
A
B
C
E
D
C
B
A
7 6 5 4
D
ININ
ININ OUT OUT
ININ
OUTOUT
OUTOUT
BIBI
BIBI
BIBI
OUTOUT
ININ
ININ
OUTOUT
OUTOUTININ
BIBI
BIBIBIBI
R342
R344 R346
R343 R345
R340
C



Thu Aug 24 10:14:58 2023181 OF 365V02MB FABCGT AMD<NAME_2><NAME_1>Blank
SHEETDATE
DEPARTMENT
SIZE
PROJECT DOCUMENT NUMBER REV
REVIEWER
DESIGNER
123
7 3 2 1 6 5 4
E
A
B
C
E
D
C
B
A
7 6 5 4
D
C



9ZXL045 ADDRESS: 0XDE(8-BIT)/0X6F(7-BIT)Thu Sep 14 16:12:56 2023<NAME_2><NAME_1>MB FABCGT AMDV02182 OF 365P3V3_AUX
P3V3_AUXP3V3_AUXP3V3_9ZXL045_P0_VDDRP3V3_9ZXL045_P0_VDDAP3V3_9ZXL045_P0_VDDP3V3_9ZXL045_P0_VDDAP3V3_9ZXL045_P0_VDDP3V3_9ZXL045_P0_VDDRP3V3_AUXP3V3_AUX2828182151288277182277288299299310310151182 182FM_9ZXL045_P0_3_OE_NFM_9ZXL045_P0_2_OE_NFM_9ZXL045_P0_1_OE_N1/16W0402LF10K1%CLK_100M_CPU0_CLK13_DPCLK_100M_CPU0_CLK13_DNCLK_9ZXL045_P0_SADR0C0402X7R X7R X7R10%25V25V6.3V040220%1/10WFCM2012KF-601T/0.5ASMLFP3V3_9ZXL045_P0C04020.1UF25V10%1%1/16W10K1%0402LFCHIPNC_U314_FBOUTNC_U314_FBOUT_NSMB_9ZXL045_P0_SCLICFCM2012KF-601T/0.5ASMLFFM_9ZXL045_P0_0_OE_NCLK_100M_RETIMER_CPU0_P1_R_DNCLK_100M_RETIMER_CPU0_P0_R_DPCLK_9ZXL045_P0_HIBWCHIPCHIP1/16W10K1%0402LF10K1%0402LF1/16WCHIPX6S110%10%0.1UF0.1UF0.1UF
4.75K
1
1/16WCLK BUFFER _ 9ZXL045 _ CPU0 RETIMER
10%X7R04020.1UF25V04020402040210%
CHIPCHIP1/16W10K0402LF
IND
EMPTY0402LF
10%25V0.1UF25V
1%
04026.3V20%10UFC0402X6S20%1%10K1%0402LFNC_U314_NC1NC_U314_NC01/16W10KCHIPCLK_100M_RETIMER_CPU0_P0_R_DNCLK_100M_RETIMER_CPU0_P1_R_DPCLK_100M_RETIMER_CPU0_P2_R_DPCLK_100M_RETIMER_CPU0_P2_R_DNCLK_100M_RETIMER_CPU0_P3_R_DPCLK_100M_RETIMER_CPU0_P3_R_DNNC_U314_NC3NC_U314_NC2X6S X7RSMLF9ZXL0451EKILFT1%10UF 0.1UF6.3V 25V10UF0603LFCHIPCHIP0402LFSMB_9ZXL045_P0_SDAX7R0402INDX7R1/10W0603LF
1%1/16W1%4.75K0402LFCLK_9ZXL045_P0_SADR01/16WCLK_9ZXL045_P0_HIBWCHIPFM_9ZXL045_P0_DEV_EN
R4493
R4475
5
26
24
18
15
2
31
29
25
21
16
12
6
7
30
17
11
10
8
9
33
4
3
28
27
23
22
20
19
14
13
32
1
21
21
U314
L19
L20
vSADR0_tri
NC2
NC3
VDD0
DIF3
DIF1
EPAD_GND
^HIBW_BYPM_LOBW#
VDD1
VDDA
NC0
DIF3#
DIF2#
vOE2#
DIF2
DIF1#
vOE1#
DIF0
DIF0#
^CKPWRGD_PD#
VDD2
SMBCLK
FBOUT_NC#
NC1
SMBDAT
vOE3#
vOE0#FBOUT_NC
VDD4
VDD3
VDDR
DIF_IN#
DIF_IN
1 2
1 2
2
1
2
1
2
1
2
1
2
1
2
1
2
1
2
1
2
1
2
1
2
1
2
1
2
1
2
1
2
1
21
2
1
2
1
21
2
1
2
1
R4476
C2328
C77
C76
R6802 R4520R4519R4518
SHEETDATE
DEPARTMENT
SIZE
PROJECT DOCUMENT NUMBER REV
REVIEWER
DESIGNER
123
7 3 2 1 6 5 4
E
A
B
C
E
D
C
B
A
7 6 5 4
D
OUTOUT
OUTOUTOUTOUTOUTOUT
IN
OUT OUT
ININ
IN
IN
IN
C2339C81C80C79C2329
R4491
R4492
C2334
C78
R4489
R4490
C



9ZXL045 ADDRESS: 0XD8(8-BIT)/0X6C(7-BIT)Thu Sep 14 16:12:57 2023<NAME_2><NAME_1>MB FABCGT AMDV02183 OF 365P3V3_AUXP3V3_AUXP3V3_9ZXL045_P1_VDDRP3V3_AUXP3V3_9ZXL045_P1_VDDRP3V3_9ZXL045_P1_VDDAP3V3_AUXP3V3_9ZXL045_P1_VDDP3V3_9ZXL045_P1_VDD P3V3_9ZXL045_P1_VDDAP3V3_AUX3323213211833543431831833323433545518355151151CLK_100M_RETIMER_CPU1_P1_R_DPCLK_100M_RETIMER_CPU1_P0_R_DNCLK_100M_RETIMER_CPU1_P0_R_DPCLK_9ZXL045_P1_HIBW20%0.1UF 0.1UF 0.1UF0.1UFFCM2012KF-601T/0.5A1%CHIP0.1UF25V10UFFM_9ZXL045_P1_DEV_EN0402LFCHIP10K1%1/16W0402LFCHIP10K1%1/16WFM_9ZXL045_P1_3_OE_NFM_9ZXL045_P1_2_OE_NNC_U10_NC2NC_U10_NC3FM_9ZXL045_P1_1_OE_NFM_9ZXL045_P1_0_OE_N10K1%1/16W10KCHIP0402LF1/16W1%0402LFCHIP1/16W1%10KCHIP0402LF6.3VC0402X6S20%10UF6.3VC0402X7R10%040210%25V1%10%FCM2012KF-601T/0.5ACLK_100M_RETIMER_CPU1_P3_R_DNCLK_100M_RETIMER_CPU1_P2_R_DPCLK_9ZXL045_P1_HIBWCHIP1/16WCLK_9ZXL045_P1_SADR0CHIP1/16W
SMLFSMLFP3V3_9ZXL045_P10603LF25V 25V0.1UF10%X7R040225V10%X7R10%0402X7RX7R10%040225VX7R0402SMLF04020.1UF1
10K0402LFCHIP1%0402LF10K1%0402LF4.75K0402LF1%EMPTYCLK BUFFER _ 9ZXL045 _ CPU1 RETIMER4.75K
INDCHIP1/10WIC1 04029ZXL0451EKILFT
1%1/16WCLK_100M_RETIMER_CPU1_P1_R_DNCLK_100M_RETIMER_CPU1_P2_R_DNCLK_100M_RETIMER_CPU1_P3_R_DP0603LF 1/10WINDC04026.3V10UFX6S
1/16WNC_U10_NC1CLK_100M_CPU1_CLK13_DPNC_U10_FBOUTCLK_9ZXL045_P1_SADR0CLK_100M_CPU1_CLK13_DNNC_U10_NC0NC_U10_FBOUT_NSMB_9ZXL045_P1_SDASMB_9ZXL045_P1_SCLX7RX6S20%25V
R560
R6803 R594 R593R592
R586
R555
5
26
24
18
15
2
31
29
25
21
16
12
6
7
30
17
11
10
8
9
33
4
3
28
27
23
22
20
19
14
13
32
1
21
21
U10
L2
L1
vSADR0_tri
NC2
NC3
VDD0
DIF3
DIF1
EPAD_GND
^HIBW_BYPM_LOBW#
VDD1
VDDA
NC0
DIF3#
DIF2#
vOE2#
DIF2
DIF1#
vOE1#
DIF0
DIF0#
^CKPWRGD_PD#
VDD2
SMBCLK
FBOUT_NC#
NC1
SMBDAT
vOE3#
vOE0#FBOUT_NC
VDD4
VDD3
VDDR
DIF_IN#
DIF_IN
1 2
1 2
2
1
2
1
2
1
2
1
2
1
2
1
2
1
2
1
2
1
2
1
2
1
2
1
2
1
2
1
2
1
2
1
2
1
21
21
2
1
2
1
C28
C83
C82
SHEETDATE
DEPARTMENT
SIZE
PROJECT DOCUMENT NUMBER REV
REVIEWER
DESIGNER
123
7 3 2 1 6 5 4
E
A
B
C
E
D
C
B
A
7 6 5 4
D
IN
OUTOUT
OUT
OUTOUTOUTOUTOUT
IN
OUTOUT
ININ
IN
IN
R578
R579
C75C99C98C90C58
C84
C68
R580
R585
C



TCA9548 ADDR: 0XE0 (8-BIT) /0X70 (7-BIT)
Thu Sep 14 16:13:03 2023<NAME_2><NAME_1>MB FABCGT AMDV02184 OF 365P1V8_AUX
P1V8_AUX
P1V8_CPU1_RT_1DP1V8_CPU0_RT_1D1511511842771842771842881842991843101842991843101842881841841848118481184184332184354184354184343
184184184184299184299184310184310184288184288184277184277184343184343184354184354184332184332184 321184 321184343184332184321184321SMB_MUX_RT_SCL0201LF CHIP1%33.2SMB_MUX_RT_SDA0201LF CHIP1%33.2SMB_MUX_RT_R1_SDASMB_MUX_RT_R1_SCLSMB_RT_CPU0_P0_R_SDASMB_RT_CPU0_P0_R_SCLSMB_RT_CPU0_P1_R_SDA0201LF0201LF0201LF0201LF0201LFSMB_RT_CPU0_P0_SDASMB_RT_CPU0_P0_SCLSMB_RT_CPU0_P1_SCL5%00201LFCHIP0201LF0201LFCHIP5%CHIP5%SMB_MUX_RT_R2_SCLCONN3_210-HP1-030BR1IO0201LFSMB_MUX_RT_R2_SDASMB_RT_CPU0_P2_R_SDASMB_RT_CPU0_P3_R_SDASMB_RT_CPU0_P2_R_SCLSMB_RT_CPU0_P3_R_SCLSMB_RT_CPU0_P1_R_SCLTHLF00C0201RT_SMB_MUX_ADDR0RT_SMB_MUX_ADDR1RT_SMB_MUX_ADDR2CHIPCHIP0.1UFSMB_RT_CPU0_P1_SDACHIPSMB_RT_CPU0_P3_SCLTCA9548APWRRST_SMB_RT_R1_NRST_SMB_RT_NCHIP0201LFRST_SMB_RT_R1_NSMB_RT_CPU1_P1_R_SCLSMB_RT_CPU1_P3_R_SDASMB_RT_CPU1_P3_R_SCLSMB_RT_CPU1_P2_R_SDA0201LF CHIP5%SMB_RT_CPU1_P0_SCLSMB_RT_CPU1_P1_SDASMB_RT_CPU1_P1_SCLSMB_RT_CPU1_P3_SDASMLF0CHIP5%5%0201LF CHIP0SMB_RT_CPU1_P2_SCLSMB_RT_CPU1_P3_SCLICSMB_RT_CPU1_P2_SDA0201LF
RT_SMB_MUX_ADDR01/20WCHIP0201LFRT_SMB_MUX_ADDR1RT_SMB_MUX_ADDR2SMB_RT_CPU0_P2_R_SCLSMB_RT_CPU0_P2_R_SDASMB_RT_CPU0_P3_R_SCLSMB_RT_CPU0_P3_R_SDASMB_RT_CPU0_P1_R_SDASMB_RT_CPU0_P1_R_SCLSMB_RT_CPU0_P0_R_SCLSMB_RT_CPU0_P0_R_SDASMB_RT_CPU1_P2_R_SCLSMB_RT_CPU1_P2_R_SDASMB_RT_CPU1_P3_R_SDASMB_RT_CPU1_P3_R_SCLSMB_RT_CPU1_P1_R_SCLSMB_RT_CPU1_P1_R_SDASMB_RT_CPU1_P0_R_SCLSMB_RT_CPU1_P0_R_SDACHIP4.7K0201LF5%1/20W5%4.7KEMPTY4.7K1/20W5%0201LF5%4.7K1/20WEMPTY0201LF5%1/20WCHIP0201LF4.7KEMPTY0201LF5%1/20W4.7K0201LFCHIP1K0201LFCHIP1K0201LFCHIP1KCHIP1K0201LF1K0201LFCHIP1K0201LFCHIP0201LFCHIP1K0201LFCHIP1K1%1/20W1K0201LFCHIP1K0201LFCHIP0201LF1KCHIP1K0201LFCHIP0201LF1KCHIPCHIP0201LF1K0201LFCHIP1K1KCHIP0201LF1/20W1%SMB_RT_CPU1_P2_R_SCL5%000201LFCHIP5%5%0201LF0201LFCHIPCHIP0201LFCHIP0201LFSMB_RT_CPU0_P3_SDA05%X7S10%
SMBUS - RETIMER
5%05%CHIP00 0201LF00CHIP5%010VCHIP5%00SMB_RT_CPU1_P1_R_SDASMB_RT_CPU1_P0_R_SDASMB_RT_CPU1_P0_R_SCL0201LF1%1/20WSMB_RT_CPU1_P0_SDACHIP10K005%5%5%SMB_RT_CPU0_P2_SDASMB_RT_CPU0_P2_SCL5%CHIPCHIP5%0
R6780
R6779
R1514
R1515
R6776
C7500
R6761
R6759
R6760
R6757
R6756
R6758
R6755
R6754
R6748
R6749
R6746
R6747
R6737
R6736
R6811
R6810
3
2
1
24
23
19
17
15
13
10
8
6
4
22
20
18
16
14
11
9
7
5
3
12
21
2
1
JP6500
U6020
1
2
3
SD4
SC4
SD5
SC5
SD6
SC6
SD7
SC7
A2 SCL
SDA
VCC
GND
SC3
SD3
SC2
SD2
SC1
SD1
SC0
SD0
RESET#
A1
A0
21 21
21 21
2
1
21
2
1
R6771
2
1
R6772
2
1
R6775
2
1
R6770
2
1
R6774
2
1
R6773
2
1
21
21
21
21
21
21
21
21
21
21 21
21 21
21
21 21
21
21
21
21
21 21
21 21
21
21
21 21
21
21
21 21
SHEETDATE
DEPARTMENT
SIZE
PROJECT DOCUMENT NUMBER REV
REVIEWER
DESIGNER
123
7 3 2 1 6 5 4
E
A
B
C
E
D
C
B
A
7 6 5 4
D
INININ
OUT
OUT
OUT
OUT
OUT
OUT
OUT
OUT
BIOUT
BIOUT
BIOUT
BIOUTBIOUT
OUT
OUT
OUT
OUT
OUTBIOUTBI
OUT
OUT
OUTBI
OUT
INBI
IN
IN
OUT
OUT
OUT OUT
R6778
R6769
R6768
R6766
R6767
R6765
R6764
R6763
R6762
R6753
R6752
R6751
R6750
R6739
R6738
R6719
R6718
C



FOR RT I2C MUX SIDEFOR RT I2C MUX SIDEFOR RT EEPROM SIDEFOR RT EEPROM SIDE
TCA9548 ADDR: 0XE0 (8-BIT) /0X70 (7-BIT)
Thu Sep 14 16:13:05 2023<NAME_2><NAME_1>MB FABCGT AMDV02185 OF 365
CHIPP1V8_CPU0_RT_1DP1V8_CPU1_RT_1DP1V8_CPU1_RT_1D
P1V8_AUX
P1V8_AUXP1V8_CPU1_RT_1DP1V8_CPU0_RT_1DP1V8_CPU0_RT_1D2881861851851851862771851851851851851851851851851851851851858118518618618618618618618618618618518518515115118618618618618618618618681185186186 301186 301186312186279186279186323186334186312186290186290186334186356186323186356186345186345185185185299186186299310186186310186288277186343186354186186343186354332186186332321 186186 3210201LFSMB_RT_CPU0_P1_ROM_MUX_1D_SCL1/20W1%1KCHIP1KCHIP0201LF0201LFCHIP1K0201LFCHIP1K0201LFCHIP1K0201LF1KCHIP0201LF1KCHIP0201LF1KCHIP0201LFCHIP1K1KCHIP0201LF1KCHIP0201LF1KCHIP0201LF1KCHIP0201LF1KCHIP0201LF1KCHIP0201LF0201LFCHIP1K1%1/20WSMB_RT_CPU0_P3_ROM_MUX_2D_R_SCLSMB_RT_CPU0_P1_ROM_MUX_2D_R_SCLSMB_RT_CPU0_P0_ROM_MUX_2D_R_SCLSMB_RT_CPU0_P0_ROM_MUX_1D_SDACHIP4.7K4.7K1/20WSMB_RT_CPU0_P0_ROM_MUX_2D_R_SDA0201LFCHIP4.7K1/20WSMB_RT_CPU0_P1_ROM_MUX_2D_R_SDASMB_RT_CPU0_P2_ROM_MUX_2D_R_SDASMB_RT_CPU0_P2_ROM_MUX_2D_R_SCLSMB_RT_CPU0_P3_ROM_MUX_2D_R_SDASMB_RT_CPU1_P2_ROM_MUX_2D_R_SCLSMB_RT_CPU1_P2_ROM_MUX_2D_R_SDASMB_RT_CPU1_P1_ROM_MUX_2D_R_SDASMB_RT_CPU1_P3_ROM_MUX_2D_R_SDASMB_RT_CPU1_P3_ROM_MUX_2D_R_SCLSMB_RT_CPU1_P1_ROM_MUX_2D_R_SCLSMB_RT_CPU1_P0_ROM_MUX_2D_R_SDASMB_RT_CPU1_P0_ROM_MUX_2D_R_SCL0201LF4.7K CHIPCHIP 0201LF0201LFCHIPCHIP4.7K 0201LF0201LFCHIP4.7K0201LFCHIP4.7K4.7KCHIP 0201LFCHIP 0201LF4.7KCHIP 0201LF4.7K CHIP 0201LF4.7K CHIP 0201LFCHIP4.7K 0201LF4.7K5%0201LFCHIP 0201LF4.7K CHIP 0201LFSMB_RT_CPU1_P1_ROM_MUX_2D_R_SCLRST_SMB_RT_ROM_R1_NSMB_RT_CPU1_P2_ROM_MUX_2D_SDASMB_RT_CPU1_P2_ROM_MUX_2D_SCLSMB_RT_CPU1_P3_ROM_MUX_2D_SCLSMB_RT_CPU1_P1_ROM_MUX_2D_SCLSMB_RT_CPU1_P3_ROM_MUX_2D_SDASMB_RT_CPU1_P1_ROM_MUX_2D_SDASMB_RT_CPU1_P0_ROM_MUX_2D_SCLSMB_RT_CPU1_P0_ROM_MUX_2D_SDARST_SMB_RT_ROM_NSMB_RT_CPU1_P2_ROM_MUX_2D_R_SDASMB_RT_CPU1_P2_ROM_MUX_2D_R_SCLSMB_RT_CPU1_P3_ROM_MUX_2D_R_SDASMB_RT_CPU1_P3_ROM_MUX_2D_R_SCLSMB_RT_CPU1_P1_ROM_MUX_2D_R_SDASMB_RT_CPU1_P0_ROM_MUX_2D_R_SCLSMB_RT_CPU1_P0_ROM_MUX_2D_R_SDART_ROM_SMB_MUX_ADDR2RT_ROM_SMB_MUX_ADDR1RT_ROM_SMB_MUX_ADDR0SMB_MUX_RT_ROM_R1_SCLSMB_MUX_RT_ROM_SCLSMB_MUX_RT_ROM_R1_SDASMB_MUX_RT_ROM_SDASMB_RT_CPU0_P2_ROM_MUX_2D_SDASMB_RT_CPU0_P2_ROM_MUX_2D_R_SDASMB_RT_CPU0_P2_ROM_MUX_2D_SCLSMB_RT_CPU0_P2_ROM_MUX_2D_R_SCLSMB_RT_CPU0_P1_ROM_MUX_2D_SCLSMB_RT_CPU0_P1_ROM_MUX_2D_R_SCLSMB_RT_CPU0_P3_ROM_MUX_2D_SDASMB_RT_CPU0_P3_ROM_MUX_2D_R_SDASMB_RT_CPU0_P0_ROM_MUX_2D_SCLSMB_RT_CPU0_P0_ROM_MUX_2D_R_SCLSMB_RT_CPU0_P1_ROM_MUX_2D_SDASMB_RT_CPU0_P1_ROM_MUX_2D_R_SDASMB_RT_CPU0_P0_ROM_MUX_2D_SDASMB_RT_CPU0_P0_ROM_MUX_2D_R_SDASMB_RT_CPU0_P3_ROM_MUX_2D_SCLSMB_RT_CPU0_P3_ROM_MUX_2D_R_SCL5%0201LF CHIP00201LF05%CHIPCHIP5%00201LF0201LF5%0CHIP0201LF05%CHIP0201LF5%0CHIP5%0201LF0CHIP05%CHIP0201LF05%CHIP0201LF10%10VC0201X7S0.1UF00201LF CHIP5%5%CHIP00201LF0201LF5%CHIP00201LF CHIP05%0201LF5%0CHIP0201LF5%0CHIP5%00201LF CHIP0CHIP5%0201LF5%00201LF CHIP0201LF5%0CHIPSMLFICTCA9548APWRRST_SMB_RT_ROM_R1_N1%10K1/20W0201LFSMB_RT_CPU0_P2_ROM_R_SCLSMB_RT_CPU0_P2_ROM_R_SDASMB_RT_CPU0_P3_ROM_R_SCLSMB_RT_CPU0_P0_ROM_R_SCLSMB_RT_CPU0_P0_ROM_R_SDASMB_RT_CPU1_P0_ROM_R_SDASMB_RT_CPU1_P1_ROM_R_SDACHIPSMB_RT_CPU0_P3_ROM_R_SDASMB_RT_CPU0_P1_ROM_R_SCLSMB_RT_CPU0_P1_ROM_R_SDA0201LF0201LFCHIPCHIP1K1KSMB_RT_CPU1_P1_ROM_R_SCLSMB_RT_CPU1_P3_ROM_R_SDASMB_RT_CPU1_P0_ROM_R_SCLSMB_RT_CPU1_P3_ROM_R_SCLSMB_RT_CPU1_P2_ROM_R_SDASMB_RT_CPU1_P2_ROM_R_SCL1KSMBUS - RETIMER EEPROMRT_ROM_SMB_MUX_ADDR0RT_ROM_SMB_MUX_ADDR2RT_ROM_SMB_MUX_ADDR10201LF1/20W5%4.7KCHIP0201LF4.7K5%1/20WCHIP0201LF0201LF1/20W4.7K5%EMPTY EMPTY0201LF5%4.7K1/20W0201LFCHIP1/20W5%4.7KEMPTY4.7K5%1/20W0201LF1KCHIP1KCHIP0201LF0201LF1K0201LFCHIP1K0201LF1K0201LF1K0201LF1KCHIP0201LFCHIP1KCHIP0201LF1K0201LFCHIP0201LF0201LFCHIPCHIPCHIP1K1K0201LF1%1/20W1K4.7K4.7KCHIPCHIP5%1K1/20W0201LFCHIP1%SMB_RT_CPU0_P2_ROM_MUX_1D_SCLSMB_RT_CPU0_P2_ROM_MUX_1D_SDASMB_RT_CPU0_P3_ROM_MUX_1D_SCLSMB_RT_CPU0_P3_ROM_MUX_1D_SDASMB_RT_CPU0_P1_ROM_MUX_1D_SDASMB_RT_CPU0_P0_ROM_MUX_1D_SCLSMB_RT_CPU1_P2_ROM_MUX_1D_SCLSMB_RT_CPU1_P3_ROM_MUX_1D_SCLSMB_RT_CPU1_P2_ROM_MUX_1D_SDASMB_RT_CPU1_P3_ROM_MUX_1D_SDASMB_RT_CPU1_P1_ROM_MUX_1D_SCLSMB_RT_CPU1_P1_ROM_MUX_1D_SDASMB_RT_CPU1_P0_ROM_MUX_1D_SCLSMB_RT_CPU1_P0_ROM_MUX_1D_SDA185185185185185185185185185185185185185185185185
R851
R850
R797
R799
R830
R829
R828
R832
R831
R833
C365
R802
R801
R803
R806
R805
R808
R809
R807
R848
24
23
19
17
15
13
10
8
6
4
22
20
18
16
14
11
9
7
5
3
12
21
2
1
U22
SD4
SC4
SD5
SC5
SD6
SC6
SD7
SC7
A2 SCL
SDA
VCC
GND
SC3
SD3
SC2
SD2
SC1
SD1
SC0
SD0
RESET#
A1
A0
21 21 21 21 21 21
21 21
21 21 21 21 21 21 21 21
21R1383
21R1382
21R1379
21R1375
21R1371 21R1374
21R1366 21R1367
21R1407
21R1403
21R1402
21R1399
21R1394
21R1393
21R1390
21R1361
21 21
21 21
21 21 21
21 21
21
21
21
21
21
21
21
21
21
2
1
21 21
21
21 21
21 21
21
21
21
21
21
21
21
21
21
21
2
1
2
1
R844
2
1
R847
2
1
R843
2
1
R842
2
1
R846
2
1
R845
SHEETDATE
DEPARTMENT
SIZE
PROJECT DOCUMENT NUMBER REV
REVIEWER
DESIGNER
123
7 3 2 1 6 5 4
E
A
B
C
E
D
C
B
A
7 6 5 4
D
OUTOUTOUTOUT
OUT
BIIN
OUTBI
BI
BIOUT
OUTBIOUT
OUT
OUT
OUT
IN
OUT
OUT
OUT
OUT
INININ
BIOUTBIOUTBIOUTBIOUT
OUT
OUT
OUT
OUT
OUT
OUT
OUT
OUT
OUT
OUTOUT
OUTOUTOUT
OUT
OUT
IN
OUTOUTOUTOUTOUT
OUT
OUTOUT
OUT
OUT
OUTOUTOUTOUTOUTOUTOUT
OUT
OUTOUTOUTOUT
OUT
R1469R1468R1463R1462R1451R1448
R1436R1437
R1432R1431R1428R1420R1418R1415R1411R1410
R6706
R6707
R6735
R6734
R810
R812
R826
R827
R834
R835
R836
R837
R839
R838
R840
R841
R849
C



Thu Sep 14 16:13:11 2023<NAME_2><NAME_1>MB FABCGT AMDV02186 OF 365P3V3_AUXP3V3_AUXP3V3_AUXP3V3_AUXP3V3_AUXP3V3_AUXP3V3_AUX
P3V3_AUX18533218518532118532181185186185356185310185310
18527918527918518518527718527781185186
811851868118518618534581185186185185185343185345185343811851861851851853541853561853548118518618533218518518533418533418532318532318581185186185288185288185185290185185290185185185312185312185299185185 301185 301185185299
10V1KSMB_RT_CPU1_P1_ROM_MUX_1D_SCLSMB_RT_CPU1_P0_ROM_MUX_2D_SCLSMB_RT_CPU1_P0_ROM_MUX_1D_SDASMB_RT_CPU1_P0_ROM_MUX_1D_SCLRST_SMB_RT_ROM_R1_NFM_SMB_RT_ROM_MUX2_SELSMB_RT_CPU1_P3_ROM_R_SDA0201LF CHIP01KCHIP0201LFPI3CSW12ZUAEXSMLFIC1KCHIP0201LF0CHIP0201LFCHIP0201LF1KCHIP0201LF0SMLFPI3CSW12ZUAEXICX7S10%C020110V0.1UF0.1UF10VC020110%X7S1KCHIP0201LF0CHIP0201LFICPI3CSW12ZUAEXSMLF0.1UF10V10%C0201X7S0.1UF10V10%C0201X7SPI3CSW12ZUAEXICSMLF1KCHIP0201LF0201LF CHIP0X7S10%C020110V0.1UFICPI3CSW12ZUAEXSMLF0201LF CHIP1K0201LF CHIP0X7S10%C020110V0.1UFICPI3CSW12ZUAEXSMLFCHIP0201LF0CHIP0201LF0.1UF10V10%C0201X7SPI3CSW12ZUAEXICSMLF0CHIP0201LF1KCHIP0201LF0.1UF10%C0201X7SICPI3CSW12ZUAEXSMLF
SMB_RT_CPU0_P3_ROM_MUX_1D_SCLSMB_RT_CPU0_P3_ROM_MUX_1D_SDA
SMB_RT_CPU0_P0_ROM_R_SDASMB_RT_CPU0_P0_ROM_R_SCLSMB_RT_CPU0_P0_ROM_MUX_2D_SDASMB_RT_CPU0_P0_ROM_MUX_2D_SCLSMB_RT_CPU0_P0_ROM_MUX_1D_SDASMB_RT_CPU0_P0_ROM_MUX_1D_SCLFM_SMB_RT_ROM_MUX5_SELRT_ROM_MUX5_OE_NRST_SMB_RT_ROM_R1_N
RST_SMB_RT_ROM_R1_NRST_SMB_RT_ROM_R1_NSMB_RT_CPU1_P2_ROM_R_SDARST_SMB_RT_ROM_R1_NSMB_RT_CPU1_P2_ROM_MUX_2D_SDASMB_RT_CPU1_P2_ROM_MUX_2D_SCLSMB_RT_CPU1_P2_ROM_MUX_1D_SDAFM_SMB_RT_ROM_MUX4_SELRT_ROM_MUX4_OE_NSMB_RT_CPU1_P2_ROM_R_SCLSMB_RT_CPU1_P2_ROM_MUX_1D_SCLRST_SMB_RT_ROM_R1_NSMB_RT_CPU1_P3_ROM_MUX_2D_SDASMB_RT_CPU1_P3_ROM_MUX_2D_SCLSMB_RT_CPU1_P3_ROM_MUX_1D_SDART_ROM_MUX3_OE_NFM_SMB_RT_ROM_MUX3_SELSMB_RT_CPU1_P3_ROM_R_SCLSMB_RT_CPU1_P3_ROM_MUX_1D_SCLRST_SMB_RT_ROM_R1_NSMB_RT_CPU1_P1_ROM_MUX_1D_SDASMB_RT_CPU1_P1_ROM_MUX_2D_SDASMB_RT_CPU1_P1_ROM_MUX_2D_SCLRT_ROM_MUX2_OE_NSMB_RT_CPU1_P1_ROM_R_SDASMB_RT_CPU1_P1_ROM_R_SCLRT_ROM_MUX1_OE_NFM_SMB_RT_ROM_MUX1_SELSMB_RT_CPU1_P0_ROM_R_SDASMB_RT_CPU1_P0_ROM_R_SCL
SMBUS-RETIMER EEPROM MUX
SMB_RT_CPU1_P0_ROM_MUX_2D_SDARST_SMB_RT_ROM_R1_NRT_ROM_MUX6_OE_NFM_SMB_RT_ROM_MUX6_SELSMB_RT_CPU0_P1_ROM_MUX_1D_SCLSMB_RT_CPU0_P1_ROM_MUX_1D_SDASMB_RT_CPU0_P1_ROM_MUX_2D_SCLSMB_RT_CPU0_P1_ROM_R_SCLSMB_RT_CPU0_P1_ROM_MUX_2D_SDASMB_RT_CPU0_P1_ROM_R_SDASMB_RT_CPU0_P3_ROM_MUX_2D_SCLSMB_RT_CPU0_P3_ROM_MUX_2D_SDASMB_RT_CPU0_P3_ROM_R_SCLSMB_RT_CPU0_P3_ROM_R_SDART_ROM_MUX7_OE_NFM_SMB_RT_ROM_MUX7_SELSMB_RT_CPU0_P2_ROM_MUX_1D_SDASMB_RT_CPU0_P2_ROM_MUX_2D_SDAFM_SMB_RT_ROM_MUX8_SELSMB_RT_CPU0_P2_ROM_R_SCLSMB_RT_CPU0_P2_ROM_R_SDASMB_RT_CPU0_P2_ROM_MUX_2D_SCLSMB_RT_CPU0_P2_ROM_MUX_1D_SCLRT_ROM_MUX8_OE_N
R1209
R1206
R1210
R1211
R1200
R1198
R1199
R1201
10
9
6
5
7
8
4
3
2
1
10
9
6
5
7
8
4
3
2
1
10
9
6
5
7
8
4
3
2
1
10
9
6
5
7
8
4
3
2
1
10
9
6
5
7
8
4
3
2
1
10
9
6
5
7
8
4
3
2
1
10
9
6
5
7
8
4
3
2
1
10
9
6
5
7
8
4
3
2
1
U47
U46
U49
U48
U43
U41
U42
U45
D+
GND
1D-
VDD
S
OE#
D-
2D-
2D+
1D+
D+
GND
1D-
VDD
S
OE#
D-
2D-
2D+
1D+
D+
GND
1D-
VDD
S
OE#
D-
2D-
2D+
1D+
D+
GND
1D-
VDD
S
OE#
D-
2D-
2D+
1D+
D+
GND
1D-
VDD
S
OE#
D-
2D-
2D+
1D+
D+
GND
1D-
VDD
S
OE#
D-
2D-
2D+
1D+
D+
GND
1D-
VDD
S
OE#
D-
2D-
2D+
1D+
D+
GND
1D-
VDD
S
OE#
D-
2D-
2D+
1D+
21 21 R1217
21 R121621
21 R121821
2
1
2
1
21 R121921
2
1
2
1
21 R121421
2
1
21 R121221
2
1
21 R121321
2
1
21 21 R1215
2
1
C1071
C1070
C1072
C1073
C1068
C1066
C1067
C1069
SHEETDATE
DEPARTMENT
SIZE
PROJECT DOCUMENT NUMBER REV
REVIEWER
DESIGNER
123
7 3 2 1 6 5 4
E
A
B
C
E
D
C
B
A
7 6 5 4
D
BIOUT
BIOUT
INBI
BIIN BIOUT
IN
BIINBIIN BIOUT
IN
BI
BIIN
IN BIOUT
IN
BIIN
OUTBI
BIIN
BIIN
IN
BI
BIOUT
IN
IN
IN
IN
IN
BIINBIIN
BIINBIIN
BI
BIIN
IN
OUTBI
C



CAD NOTE: R5051 R5052 CO-LAYVDDBT_RTC_G POWERED FROM 3V: POP R5052 R5054 R5055,DEPOP R5051 R5053 R5056AHL03003097VDDBT_RTC_G POWERED FROM 1.5 OR 1.8V: POP R5051 R5053 R5056, DEPOP R5052 R5054 R5055CAD NOTE:CAD NOTE: R5053 R5054 CO-LAYFPGA2ND SOURCE OF U167
2-3 BIOS LOAD DEFAULT1-2 NORMAL OPERATION(DEFAULT)CLEAR CMOS JUMPER
Thu Sep 14 16:13:03 2023<NAME_2><NAME_1>MB FABCGT AMDV02187 OF 365
P1V5_BATP3V3_RTC_AUXP3V3_AUX18718718782187
1871870402LFX6SX7R10%50V100NFTHLFP3V_BATCHIP1%1/16W0402LF1KP3V_BAT_R10KSMLFNCP698SQ15T1G1/16WCHIPBAT_LDO_EN10%25V
BAT_LDO_ENP1V5_BAT_INCLR_CMOSP1V5_BAT_OUTU9_NRCLR_CMOS_NP1V5_BAT_OUT_RP1V5_BAT_INP3V3_RTC_AUX_RIOCONN2_AAA-BAT-029-Y191KCHIP1%1/16W0402LF C04020.1UFX7R16V10%5%1/16WCHIP0402LFSMLFBAT54CWIC5%01/16WCHIP0402LF05%1/16W
TPS71715DCKRSMLFEMPTY0.01UFC040210%EMPTY50VICSMLF2N7002KDW0402LFCHIPC04021UF0402LF 1/16W100CHIP1%25VX6S10%C04021K0402LF0C040225V10%X6S1UFX6S10%25V10UFC0805THLFCONN3_210-HP1-030BR1
BATTERY
1/16W0402LF1%EMPTYP1V5_BAT_OUTIOEMPTY1UF5%EMPTYC04021K1%1/16WP3V3_STBY_R
2
1
R1777
2
1 C5032
2
1 C1567
2
1 C1564
21R1779
2
1 C193
2
1C45
41
52
36
Q8
3
1
2
U166
2
1
C1563
2
1
R1776
R5054
R5053R5051
R5052
R5101
32
1 4
3
2
1
5
4
1
2
3
2 1
U167
JP12
U9
BT2
C
B
A
OUT
NR||FB
IN
EN
GND
2 1
EN
VIN VOUT
GND
1
2
3
D2D1
S2S1
G2G1
21R1775
2
1
21
2
1
21
2
1
21
SHEETDATE
DEPARTMENT
SIZE
PROJECT DOCUMENT NUMBER REV
REVIEWER
DESIGNER
123
7 3 2 1 6 5 4
E
A
B
C
E
D
C
B
A
7 6 5 4
D
OUT
IN
IN
IN
IN
OUT
OUT
OUT
C22
C



OD OUTPUTPUSH PULL OUTPUTThu Sep 14 16:12:30 2023<NAME_1>GT AMD<NAME_2>MB FABCV02188 OF 365P3V3_AUXP5V
P5V_AUXP12V_AUXP12V_AUX
P3V3_AUXP3V3P3V3P3V3P3V3_AUXP3V3P3V3_AUXP12V_AUXP12V_AUXP5VP5V
P5VP3V3_AUXP1V8_AUXCHIPPWRGD_P5V_R10402LF0402LF5%0402LFPJT138KIC10K
C0805
PWRGD_P5V_RVR_P5V_EN_N0402LFCHIP1%100KPWRGD_P3V3_R2CHIP0402LFEMPTYPWRGD_P3V3_R1BSS138DW-7-FPWRGD_P3V3_EN_NCHIP5%P5V & P3V3 SWITCH1%CHIP100K040225V0.1UF10%X7RICSMLFAPX809-29SAG-71/16W0402LF5%10KPWRGD_P3V3_ENCHIP5%SMLFSMLFICC04025%1/16WCHIP0402LF
1206LF
0402LF1/16WSMLFPJT138K1%1%1/16WCHIP0402LFIC100K1%1/16WPWRGD_P5V_N0402LF1/16WCHIPIC001%1/16WEMPTY10KIC05%5%CHIP10K25VX7REMPTYICSMLFIC1/16W0402LF1/16WCHIP5%0100K1206LFC0805X6S10%16V10UF10%50V100NFIC16V10UFEMPTY10%16V10%X6SC0805X7R50V100NF10KCHIP0402LFFM_P5V_EN1%VR_P5V_ENC0402X7R2431%CHIP2431%1/4W2431/4WCHIP1/4WCHIP0.22UF100NFX7R10%50V10UF16VX6S10%C080516V10UFC0805X6S10UFC0805X7R50V10%100NFC040210%16VX7R1%10%1/16WCHIP0402LF1%SMLFPSMNR58-30YLH2431%CHIPC0402SMLFX7R0402LFPSMNR58-30YLHEMPTYCHIP1/16W0402LF5%10%CHIP0CHIP1%10KPJT138KSMLFPWRGD_P5V_R2EMPTY0402LF10%0.22UFSW_P3V3_EN_NSW_P3V3_EN_ISO_RSW_P3V3_EN_R1K0402LF5%PJT138KICSMLFC04024.7K5%1/16WCHIP0402LFPWRGD_P5V_R_NSMLFPJT138K0402LFSW_P3V3_EN_ISOCHIPSMLFRT9818C-44GVBAT547F100K4.7K1%100K1%IC1/16W1206LF1/4W1%VR_P5V_EN_N1K1/16W50V100NF10K1/16W0402LF00402LF33188818181 80
18810UF10%
PWRGD_P3V3_EN_R
SMLFSW_P3V3_ENVR_P5V_EN_D_R1C0402CHIP1/16WVR_P5V_EN_D_RC040225V10%0402LFICPJT138KVR_P5V_EN_DSMLF2N7002KIC1206LF0402LF
21 R1362
2
1
41
52
36
Q27
2
1
G2
G1
G1
G
G2
G2
G1
S2 D2D1S1
D1S1S DS2 D2
S2 D2D1S1
R1493
R1492
C9226
R1491
R6501
21R6500
R569R6050
R335
R334
R333
3
2
1
5
2
5
2
3
1
2
G
4 31 64 31 6S D
U6006
Q3
Q3
Q1
Q1
U100
U324
Q57
Q56
D1
Q37
Q37
GND
RESET#
VDD
S
G
D
1
25
3
31
1
25
3
GND
RESET_L
VCC
D2D1
S2
G2G1
S1
D1G1S3 S2 S14
D1G1S3 S2 S14
2
1
2
1
2
1
2
1
2
1
2
1
2
1
R554
2
1
21
R4942
1
21
21
2
1
R496
2
1
21
2
1
2
1
2
1
2
1
2
1
2
1
2
1
2
1
2
1
2
1
2
1
2
1
21
2
1
2
1
2
1
2
1
2
1
2
12
1
2
1
2
1
21
C6500
R568
R487
R490
R480
R479
C6122
5
3
2
1
5
3
2
1
31
5
2
4
4
4 31 6
SHEETDATE
DEPARTMENT
SIZE
PROJECT DOCUMENT NUMBER REV
REVIEWER
DESIGNER
123
7 3 2 1 6 5 4
E
A
B
C
E
D
C
B
A
7 6 5 4
D
IN
IN
IN
OUT
OUT
OUT
C29
R552
R492
R482
R4641R4640R4639
C61
C1331
C57C1170C1042
C1340C60C1333C1332
R4638
C1227
R1654
R336
C



BOM NOTERBRAVOUT=0.6(1+RA/RB)=5.003V
P5V_AUXISAT=13A10.3*11.2*4.0PCMB104E-4R7MSTBCTRANSIENT TOLERANCE = +/-5.0%OUTPUT RIPPLE & NOISE = +/-1.0%DC TOLERANCE = +/-1.5%OUTPUT VOLTAGE = 5.0VDESIGN SPECIFICATIONIMAX = 2.1ATDC = 1.8AOCP(IMAX*120%) = 4ACURRENT STEP = 1ASLEW RATE = 1A/USWORK FREQUENCY = 600KHZ
2ND NA1ST3RDDCR=15MOHMPR8089 CHANGE TO CS31402FB03PC1877 CHANGE TO CH1156F0B00PC1848 CHANGE TO CH5222KEB01BOM CHANGE R&C TABLE3RD AL000548006/TPS548A28RWWR/TI2ND AL053318002/RS53318LR/REEDSEMI1ST AL008633007/MPQ8633AGLE-C807-Z/MPSThu Sep 14 16:12:40 2023<NAME_2><NAME_1>MB FABCGT AMDV02189 OF 3651/16WCHIPMPQ8633AGLE-C807-ZC0402P12V_AUXP5V_AUXP5V_AUX_VCCP5V_AUX_VCC85190263268243254SW_P5V_AUX_FLT0402LF5%CHIP5%0402LFX6S20%16V0.1UF25V10%C0805X6SX6SINDBLM18SN220TN1D/8000MASMLFC080522UFC0402X6S10%16V1UF16V22UF20%C0805X6S16V20%22UF47PF0402LF11.8K0.1UF0.1%IC 0402X7R10%0.1UF25VX6SC080522UF10V20%22UFC080520%10VX6SALUM20%6.3VSMLF220UF4.7UHIND86.6KCHIP1%5%0402LFCHIP010K1/16W25VC0402X7R10%0.22UF50V04025%NPO25V16.9K25VC0402X6S10%PWRGD_P5V_AUXSW_P5V_AUX_SWP5V_AUX_FBP5V_AUX_CSSW_P5V_AUX_BSTPWRGD_P5V_AUX_RCHIP1UF1/16W1%1/16W01/16WP5V_AUX_EN0CHIPP5V_AUX_MODEMB0_P12V_STBY_PWRGDSMLF1%0402LFP5V_AUX_REF0402LFCHIPSMLF1/16W10%X7R04020402LFMPQ8633A/P5V_AUX
2
1 PC1852
2
1 PC1856
2
1 PC1855
2
1 PC1845
21
PL8065
21PR8092
2
1
R2356
PC1847
2
1
PR8091
21
PC18772
1
PC1853
2
1
PR8089
PC1846
2
1 PC1898
2
1 PC1850
2
1
PC1848
2
1 PC1849
21
PL8064
R6097
PR3337
R231621
10
19
5
20
6
9
11_18
4
7
8
3
1
2
U326
1 2
VIN2
CS
MODE
TRK_REF
SW
RGND
VCC
AGND
FB
BST
EN
PGND
PGOODVIN1
1 221
21
21
2
1
2
1
2
1PC1648
SHEETDATE
DEPARTMENT
SIZE
PROJECT DOCUMENT NUMBER REV
REVIEWER
DESIGNER
123
7 3 2 1 6 5 4
E
A
B
C
E
D
C
B
A
7 6 5 4
D
IN
OUT
C



TO IMPROVE INPUT RIPPLEBASE ON POCBOM CHANGE R&C TABLE2ND PR836 EMPTYPC569 CHANGE TO CH12206JB00PC8008 CHANGE TO CH5473KE9021STEM-15AM17VG1-QS14.3*12.9*8.0DCR=1.5M OHMISAT=53A@100CSLEW RATE = 2.5A/USOCP = 32AIMAX = 21ATRANSIENT TOLERANCE = 330MVTDC = 19AOUTPUT RIPPLE & NOISE < 50MVOUTPUT VOLTAGE = 3.3V+/-5%DESIGN SPECIFICATIONESR=9.5M OHMCURRENT STEP = 10.5AWORK FREQUENCY = 600KHZ
VO=0.8(1+RA/RB)=3.3VRARB
P3V3_AUXESR=9.5M OHMTSS=4MS2ND AL003889000/IR3889MTRPBF/INFINEON1ST AL003284002/NCP3284AMNTXG/ONSEMIBOM NOTEThu Sep 14 16:12:22 2023<NAME_2><NAME_1>MB FABCGT AMDV02190 OF 365
PWRGD_P5V_AUXP12V_AUXP3V3_AUXP3V3_AUXP12V_AUXP12V_AUXP3V3_AUX81 85270189851K1%1/16W0402LFCHIP22UF16VX6S20%22UF16V20%X6SC080520%P3V3_AUX_ENP3V3_AUX_VCCP3V3_AUX_VDRV22UF16V22UF20% 20%X6SSMLF100NH/16AINDSMLFCHIP0402LF20%22UFPWRGD_P3V3_AUX0402P3V3_AUX_FBX6S10%16VX7R25V0.1UFX6SC080510%X6SNC_HICCUPICC08052.2UFP3V3_AUX_VOS1%1K1/16W0402LFCHIPSW_P3V3_AUX_BOOT_R5%EMPTY5%0SW_P3V3_AUX_BOOT5%0402LF50V1000PFEMPTY1/16W0402CHIP50V10V560UF20%1.5UH/53ASMLFPWRGD_P3V3_AUX_R1NCP3284AMNTXG20%16V22UF16V10%0402LFEMPTY1/16W510K20%C0805
NCP3284/P3V3_AUX10%0.1UFX7R25V10V20%X6SC080522UF20%X6S22UF10VC0805X6SC0805THLF560UF6.3VOSCONOSCON6.3V20%THLF47K 0.1% 0402LF10PF1%NPO0.22UF10% X7R25V16V1UF10%X7R06030402X6S20%22UFC080522UF16VX6S20%C080522UF16VTHLF20%OSCONTHLF270UF20%X6S16V16V22UFX6S20%C040225VX6S0.1UF1CHIP 0402LF1%C060321.5KCHIP0402LF1%1/16W1/16WEMPTY1.5K0402LF1%4.7UF16VC060305%1/16WCHIP1/16WCHIP5%010%EMPTY1%NC_PU9_2NC_PU9_1NC_PU9_3P3V3_AUX_SSNC_PU9_4P3V3_AUX_ILIMP3V3_AUX_MODE0402C080586.6K04021/16W5%C080522UF15K0.1%1/16WCHIP0402LF25V0.1UFSW_P3V3_AUX_FLT16V20%X6S270UF16V16V10%X6S X6SC08050402LF0402LF0402LF1/16W20%0CHIP1/16WIND1/16WSW_P3V3_AUX_BOOTRSW_P3V3_AUX_SWC0805 C080516V22UF 22UFC0805OSCON22UF16VC0805C0805X6S20%16V22UFX6SX6S20%16V
PC8014PC8013PC2344
PC1599 PC1600
21R6099
2
1
21 PR836
PC8008
PC2261
21
PL8045
2
1 PC591
2
1 PC581
2
1
PR832
2
1
PR8073
2
1 PC1869
2
1
2
1 PC1868
21
PL8066
21PC5692
1
PR830
21PR835
21
PC568
2
1 PC577
2
1 PC8071
2
1 PC576
PC2343
2
1 PC571
2
1 PC570
PC2342PC2263
PC8567
PC2262
2
1
PC566PC3
PC2260
21 PR8389
2
1
PR834
2
1
PR833
2
1
PC1870
C5015
PR831
PC1867PC1866
R1571
31
28
3
5
4
11_18
29
20_24
25
2
7_10-1934
33
36
1
35
37
6
30
27
26
32
PU9
1 2
1 2
GL2
SS
GL1
VDRV
EN
AGND
VOS
PGOOD
PVIN
SW
NC1
PGND
HICCUP#
VSNS-
VCC
PHASE
ILIM
BOOT
FB
VIN
MODE||FSET
NC2
2
1
2
1
2
1
2
1
2
1
2
1
2
1
2
1
2
1
2
1
2
1
2
1
2
1
2
1
2
1PC1649
2
1
2
1
R3117
2
1
R3118
SHEETDATE
DEPARTMENT
SIZE
PROJECT DOCUMENT NUMBER REV
REVIEWER
DESIGNER
123
7 3 2 1 6 5 4
E
A
B
C
E
D
C
B
A
7 6 5 4
D
OUT
IN
C



Thu Aug 24 10:15:04 2023<NAME_2><NAME_1>MB FABCGT AMDV02191 OF 365Blank
SHEETDATE
DEPARTMENT
SIZE
PROJECT DOCUMENT NUMBER REV
REVIEWER
DESIGNER
123
7 3 2 1 6 5 4
E
A
B
C
E
D
C
B
A
7 6 5 4
D
C



IRATED=5A@125CRBRAFCCM/FSW=600KHZPVDD_33_S5PVDD_33_S5 SPECIFICATIONOUTPUT VOLTAGE=3.3VDC & AC=3.13-3.46VTDC=6A
VOUT=0.6(1+RA/RB)=3.3V2ND NA2ND AL053318002/RS53318LR/REEDSEMI3RD PC118 CHANGE TO CH5222KEB01BOM NOTE3RD AL000548006/TPS548A28RWWR/TI
3RD=CX0002200002ND=CX220Z06Z00DCR=5M OHM7*7*32ND=CV-15I0MZ03PCMC063-1R5MNISAT=16A@100CDCR=15MOHMCURRENT STEP=2AOVER CURRENT PROTECTION=9AEDC=6.2AEFFICENCY>90%@TDCSLEW RATE=2A/USWORK FREQUENCY=600KHZ
1ST AL008633007/MPQ8633AGLE-C807-Z/MPS1STBOM CHANGE R&C TABLEThu Sep 14 16:12:40 2023<NAME_2><NAME_1>MB FABCGT AMDV02192 OF 365C0402PVDD_33_S5PVDD_33_S5_VCCPVDD_33_S5_VCCP12V_AUX8181331UF25VC0402X6S10%25V10%X6S1UFEMPTY10%25V04020.1UF5%X7R1000PFFM_PWRGD_PVDD33_S5SW_PVDD_33_S5_BST_R50V16V22UFSW_P12V_AUX_PVDD_33_S5_FLTX6S20%X6S22UFC080522UFX6S20%C0402SMLFBLM18SN220TN1D/8000MAX6S20%
PVDD_33_S510%0.1UFX7R25V0402C080516V22UF20%X6SC080516V22UFX6S10KC080522UF16V20%16V56K1%NPO5%100PF50V040212.4K1%1/16WX7R10%0.1UF040225V6.98K1%CHIP1/16W0402LF22UFPVDD_33_S5_FBPVDD_33_S5_REFPVDD_33_S5_CSMPQ8633AGLE-C807-Z16V22UF20%CHIP0402LF01/16WCHIP5%PVDD33_S5_ENPVDD_33_S5_MODE040225VX6S0.1UF10%16V20%16VINDICC080520%16VX6SC0805C0805X7RC0805X6S20%04020402LF5%1/16W0402LFPWRGD_PVDD33_S50402LF5%0CHIP1/16WSW_PVDD_33_S5_BST0.1UF25VC08051/16WCHIP0402LFX6S22UFINDSW_PVDD_33_S5_SWSMLF1.5UH
PL72
21
10
19
5
20
6
9
11_18
4
7
8
3
1
2
PU55
2
1
PC128
2
1 PC136
2
1 PC135
2
1 PC134
21 R225
2
1
R453PC126
2
1 PC123
2
1 PC130
2
1 PC129
21
PR455
21
PC1322
1
PR454
2
1 PC127
2
1
PR452
2
1 PC120
2
1 PC119
21
PL71
PC6000
2
1C348
2
1
PC118
PR8000
PC8001 PC8000
C5002
PR6000
21 1 2
VIN2
CS
MODE
TRK_REF
SW
RGND
VCC
AGND
FB
BST
EN
PGND
PGOODVIN1
1 2
21
2
1
2
1
2
1
2
1
21
2
1
SHEETDATE
DEPARTMENT
SIZE
PROJECT DOCUMENT NUMBER REV
REVIEWER
DESIGNER
123
7 3 2 1 6 5 4
E
A
B
C
E
D
C
B
A
7 6 5 4
D
OUT
IN
C



IRM REV1.09IRM REV1.09SVI3 ADDRESS=PORT0 (0X2)EFFICIENCY > 90% @TDCWORK FREQUENCY=600KHZMAX LOAD RELEASE=95APVDDCR_SOC_P0 SPECFICATIONDEFAULT POWER-ON VID=0.9VSVI3 ADDRESS=PORT0 (0X1)EFFICIENCY > 90% @TDCWORK FREQUENCY=600KHZLOAD-LINE=0.4MOHMMAX LOAD RELEASE=200AMAX LOAD STEP=200AOCP=276A (EDC*1.2)MIN AC=VID-EDC*LL-110MVVID=0.75-1.2VDC=+/-20MVDIFFERENTIAL PAIRTRACE WIDTH = 10MIL0X61
MAX LOAD STEP=45AOCP=156A (EDC*1.2)MIN AC=VID-150MVMAX AC=VID+150MVTDC=105AEDC=130A
RENESAS 0/681 OHM
TRACE SPACING = 5MILDIFFERENTIAL PAIRTRACE WIDTH = 10MILTRACE SPACING = 5MIL
DEFAULT POWER-ON VID=0.9VPVDDCR_CPU0_P0 SPECFICATIONVID=0.55-1.5VDC=+/-20MVMAX AC=VID+200MVTDC=175AEDC=230A
/75K OHMVRINFINEONMPS0X4FPR531,PR440,PR441 = EMPTYPC470 = CH5103KEB01PC463,PC464 = CH12206KB14PU42 = TBD/MP2857GQKT-001C-ZPR5 = CS00002JB13PR440,PR441,PC463,PC464 = EMPTYPR599 = CS24992FB07PC7 = CH21006JB10PC470 =CH5103KEB01PC469,PC472 = CH31004KB17PR292,PR314 = CS37502FB05PR290,PC462,PR531 = EMPTY3RD SOURCE:MPS BOMPC462 = CH3104J1B00PC472,PC469 = CH11006JB00PR306,PR307 = CS01002FB07PR5 = CS21002FB060X4F/681 OHMADDRESS(7-BIT) CONFIG/RPMBUS ADDRESS AND CONFIGBOM NOTEMAIN SOURCE:RENESAS BOMPU42 = TBD/RAA229620GNP#HA02ND SOURCE:INFENEON BOMPR290 = CS25362FB02PU42 = TBD/XDPE192C3BThu Sep 14 16:12:17 2023<NAME_2><NAME_1>MB FABCGT AMDV02193 OF 365
1%1/16WPVDDCR_CPU0_P0_RESET_N_RPVDDCR_CPU0_P0_OCP_N_RCHIP 1/16W1993300PF0402LFCHIPVSENSE_PVDDCR_CPU0_P0_DPI17
PVDD18_S5_P0P3V3_AUXPVDDCR_CPU0_P0P3V3_AUXP5V_AUX
P3V3_AUX
PVDD18_S5_P0P12V_AUXPVDD18_S5_P0P3V3_AUXPVDDCR_SOC_P0PVDDCR_CPU0_P0_PWM2PVDDCR_CPU0_P0_PMALERT_R5%PVDDCR_CPU0_P0_PMALERT193194194195195195195196196198198198 199199194
198196198196194278027
78151193151193194 195 196 198 199151193
1941951962727193828282
272719315183812782PVDDCR_CPU0_P0_IMON2PVDDCR_CPU0_P0_IMON3PVDDCR_CPU0_P0_PWM3PVDDCR_CPU0_P0_IMON4PVDDCR_CPU0_P0_PWM4PVDDCR_CPU0_P0_IMON5PVDDCR_CPU0_P0_PWM5PVDDCR_SOC_P0_IMON1PVDDCR_SOC_P0_PWM1PVDDCR_SOC_P0_TEMP1PVDDCR_SOC_P0_EN//ADDR_CFGPVDDCR_SOC_P0_IMON3PVDDCR_SOC_P0_PWM3NC_PVDDCR_CPU0_P0_IMON9NC_PVDDCR_CPU0_P0_PWM9PVDDCR_CPU0_P0_PWM1
PVDDCR_SOC_P0_IMON2VSENSE_PVDDCR_SOC_P0_VSEN1PVDDCR_CPU0_P0_VINSENPVDDCR_CPU0_P0_VMONPVDDCR_CPU0_P0_PWM6PWRGD_PVDDCR_CPU0_P0_R
PVDDCR_SOC_P0_PWM2VSENSE_PVDDCR_CPU0_P0_VSEN0NC_PVDDCR_CPU0_P0_PWM7NC_PVDDCR_CPU0_P0_PWM8PVDDCR_CPU0_P0_PMSDA_RPVDDCR_CPU0_P0_EN_RSVID_PVDDCR_CPU0_P0_SVD_R1NC_PVDDCR_CPU0_P0_IMON8NC_PVDDCR_CPU0_P0_IMON7SVID_PVDDCR_CPU0_P0_SVTO_RPVDDCR_CPU0_P0_IMON6SVID_PVDDCR_CPU0_P0_SVC_R1PVDDCR_CPU0_P0_PMSCL_RSVID_PVDDCR_CPU0_P0_SVTI_RPVDDCR_CPU0_P0_IMON1RAA229620GNP#HA0ICSMLF1%49.9SVID_PVDDCR_CPU0_P0_SVTO1/16W0402LFCHIP1%05%0402LFCHIP0EMPTY0402LF0402LFCHIP1/16W01/16W0402LFCHIPPVDDCR_CPU0_P0_ENCHIP1/16WSVID_PVDDCR_CPU0_P0_SVTI10PF50V5%1/16W50V5%SVID_PVDDCR_CPU0_P0_SVC_RX7R1000PF5%0402LF1/16W5%
PVDDCR_CPU0_P0_RESET_NCHIP 1/16WCHIP0402LF0402LF0402PVDDCR_CPU0_P0/PVDDCR_SOC_P0 VR CONTROLLER1%
1/16W0402SMB_SCM_2_R3_SCL10%50V1/16WSMB_SCM_2_R3_SDACONN3_210-HP1-030BR1CHIP335%1000PF
CHIP
1/16W
1/16W0402LFPWRGD_PVDDCR_SOC_P0_REMPTY1000PF1UF0402X7R1000PFX7R50V04020.1UFPVDDCR_CPU0_P0_VCCS0402LF0
04020402X7R0402LF1/16W5%04025%50V10PFSMB_SCM_2_R3_SCL1/16W
PVDDCR_CPU0_P0_TEMP01%470PF0402LFEMPTY1/16W5%1/16WCHIP
0EMPTYVSENSE_PVDDCR_SOC_P0_DPVSENSE_VSS_SENSE_A_P0PVDDCR_SOC_P0_EN1%PVDDCR_SOC_P0_EN_RC1000PFCHIPX7R
0402
0402CHIP
THLFIO5%
PVDDCR_SOC_P0_EN_GD
EMPTY1K1/16W1%
6.3V5%0402LF10%10K1%
5%5%0CHIP 1/16W
25V1UF
5%0402LF04020402LFPJA3415AE
0402LFCHIP1%110%C040216VX6SX6S20%10UF6.3VC040210%04020.1UFX7R25V10%X7R1/16W00402LFCHIP 0402LF5%01/16W0402LF5%01/16WCHIP040250V10%040250V470PF10%X7R
EMPTY1000PF5%1/16W1K 1%EMPTY1K1K5%10%01K1%0402LFX7R 10%040250V040225V0.1UF10%X7RCHIP01/16WEMPTY1%4.99K
1%1%1K1/16WCHIP0402LF49.91/16WCHIP49.91KCHIP1/16W1%681X7R25V0.1UF0402LFCHIPIC1/16WCHIP1%1K0402LFBSS138KIC1/16W40.2K1%
1K
PVDDCR_CPU0_P0_OCP_N1/16W0402LF1/16WEMPTYEMPTY0402LF0402LF1000PF50VX7R10K
PVDDCR_CPU0_P0_VCC
5%1/16W5%5%1/16W0402LF50V 5%X7R
X7R50V040250V04025%49.95%1%1%0402LF0CHIP00402LF
0
CHIP1/16W1K1%EMPTY040250V3300PF00402LF330402LF5%1/16WCHIPPWRGD_PVDDCR_SOC_P0
1/16W33 5%1/16W0402LF0402LF1%CHIP0402LF5%0402LFCHIP0402LFCHIPVSENSE_VSS_SENSE_A_P01/16WEMPTY49.91/16W10PF0402LFSMB_SCM_2_R3_SDA0402LF49.91%1/16W040250VCHIPCHIP0402LFSVID_PVDDCR_CPU0_P0_SVD_RCHIPPWRGD_PVDDCR_CPU0_P0
R6089
PR8006
PR8005
21C5017
21C5018
40
25
45
46
19
48
47
TH
43
44
23
24
21
22
39
26
18
12
11
10
9
8
7
6
5
4
3
2
1
13
14
20
16
41
15
42
17
27
28
29
30
31
32
33
34
35
36
37
38
PU42
21
PR316
2
1 PC471
2
1 PC470
2
1 PC12
21
PR531
21
PR440
PR441
2
1 PC472
2
1 PC469
21
C467
21
R8311
21
R8308
21
R8309
21
R8310
2
1
PR294
2
1
R8293
2
1
R8289
2
1
R8287
2
1 C298
21
PR306
2
1 PC464
21
PR307
21
R8313
21
PC466
21
C465
2
1 PC7
21
PR314
2
1
PR295
2
1
PR296
21
R82982
1 PR292
21
R8299
2
1 PC462
2
1
PR5
G
PQ13
2
1 PR285
G
PQ17
21
PR290
2
1
PR284
2
1
R8286
21
R8282
2
1 PC13
21
C468
21 R8312
21
R8304
21
PR305
21
R8300
2
1 C302
2
1 C299
2
1 PC463
21
R8301
21
R315
PR599
21R83172
1
PR297
2
1 C461
2
1
PR283
SDS D
C5011
3
2
1
PJ1
S
G
D
G
1
2
3
CS10
PWM10
CS9
PWM9
CS8
PWM8
CS7
PWM7
CS0
PWM0
TEMP1
EN1||ADDR_CFG
TH_GND
OCP_L
CS2
PWM2
CS3
PWM3
PWM11
CS1
RGND1
VSEN1
VDDIO
TEMP0
VINSEN
VMON||IINSEN
VCCS
PWM6
PG0
PWM1
VSEN0
PWM5
PWM4
PMSDA
RGND0
EN0
nPMALERT
SVD
PG1
CS4
CS5
RESET_L
SVTO
CS6
SVC
PMSCL
SVTI
VCC
CS11
SD
21
21
2
1
2
1
SHEETDATE
DEPARTMENT
SIZE
PROJECT DOCUMENT NUMBER REV
REVIEWER
DESIGNER
123
7 3 2 1 6 5 4
E
A
B
C
E
D
C
B
A
7 6 5 4
D
IN
IN
IN
IN
IN
OUT
IN
BI
OUT
OUT
IN
OUT
IN
IN
IN
IN
OUT
INBI
OUT
OUT
IN
OUT
IN
OUT
IN
OUT
IN
IN
OUT
OUT
IN
OUT
IN
OUT
IN
OUT
IN
IN
C



6.3*8IRIPPLE:5.08AESR=10M OHM2ND=CVA50^0MZ07DCR=0.09M OHM6.0*6.1*7.0ISAT:70A@100CPVDDCR_CPU0_P0_PHASE2PVDDCR_CPU0_P0_PHASE1
11.0*7.5*12.5DCR=1-4,0.105M OHM2ND=CV+15^0TZ01DCR=2-3,0.27M OHMISAT:70A@100CPGL6303.151HLT7.3*4.3*1.9ESR=9.0M OHMMAIN=CH122KM8801PG2292.500HLT3RD=CVA50^0MZ08DCR=2-3,0.27M OHM2ND=CV+15^0TZ01DCR=1-4,0.105M OHM11.0*7.5*12.5ISAT:70A@100CPGL6303.151HLT2ND=CC72703MD39PC473_1,PC474_2,PC544_3,PC545_4,PC566_5,PC150_6 = EMPTYPR445,PR324,PR325,PR350,PR351,PR355,PR433 = EMPTYPR446,PR322,PR323,PR348,PR349,PR354,PR432 = CS00002JB13PU6,PU43,PU46,PU47,PU48,PU10 = AL087000A03/MP87000GMJTH-C11D-Z3RD SOURCE:MPS BOMPR322,PR323,PR348,PR349,PR354,PR432 = CS00002JB13MAIN SOURCE:RENESAS BOMBOM NOTEPU6,PU43,PU46,PU47,PU48,PU10 = AL099390004/ISL99390FRZ-TR5935PU6,PU43,PU46,PU47,PU48,PU10 = AL021590000/TDA215902ND SOURCE:INFENEON BOMPR320,PR321,PR346,PR347,PR353,PR431 = CS00002JB13PR324,PR325,PR350,PR351,PR355,PR433 = EMPTYPC473_1,PC474_2,PC544_3,PC545_4,PC566_5,PC150_6 = EMPTY
Thu Sep 14 16:12:17 2023<NAME_2><NAME_1>MB FABCGT AMDV02194 OF 365
SW_P12V_AUX_PVDDCR_CPU0_P0_FLTSW_P12V_AUX_PVDDCR_CPU0_P0_FLTPVDDCR_CPU0_P0P12V_AUXPVDDCR_CPU0_P0PVDDCR_CPU0_P0
PVDDCR_CPU0_P0_PVCCPVDDCR_CPU0_P0_PVCCP3V3_AUXP5V_AUX0.22UF0402LFCHIP19319419519619819919419519619319419519319319319319419519619319319419519619819919419610%C0402SW_PVDDCR_CPU0_P0_BOOT15.6C0402X6S10%10%SW_PVDDCR_CPU0_P0_BOOT1_RC1%1/16W5.6SW_PVDDCR_CPU0_P0_BOOT2_RCSW_PVDDCR_CPU0_P0_BOOT21/16W0402LF1%CHIPEMPTYNC_PVDDCR_CPU0_P0_DNC1PVDDCR_CPU0_P0_VCCS0.1UFPVDDCR_CPU0_P0_TEMP010%THLF0.1UF25VSMLFISL99390FRZ-TR5935PVDDCR_CPU0_P0_VCC2560PF10%16V0.22UFSMLFSPCAP0402LFIND_CPU0_P0_CPL1IND270UF20%X6SX6S0402NC_PVDDCR_CPU0_P0_GL2_1SW_PVDDCR_CPU0_P0_SW1_RC25V1UFX6SCHIPSW_PVDDCR_CPU0_P0_PH2SW_PVDDCR_CPU0_P0_SW2PVDDCR_CPU0_P0_VOS2X6SC0805X6SX7R0402PVDDCR_CPU0_P0 VR PHASE 1&2
0402LF1K1%CHIP1/16W22UF20%X6SC08054V4V22UFX6SC080520%0.1UF25V0402X7R10%X7R040210%SMLF50NH/86AOSCON16V270UF20%20%THLFOSCON16VIND150NHSMLF16VX7R4V220UFSMLFSPCAP20%4V22UF20%X6SC080520%X6SC08054V22UFSPCAP20%SMLF4V220UF4V20%220UFSPCAPSMLF4V220UF20%220UF20%SPCAPSMLF4VSMLFIND150NHX7R0402
X6S16V22UF16V20%22UF20%22UF16VC040210%25V0.1UFX7RC0402X6S10%2.2UF10V0402LF2.21%CHIP1/16W0402LF1/16W8.87K1%C0402X6S10%2.2UF01/16W22UF16VC080516V20%22UF22UF20%10%0402LF05%CHIP1/16W1/8WEMPTY1%1.50402LF
ICX7R10%25V0402X6S10%C04022.2UF1%CHIP1/16W2.20402LFICX6S10%2.2UF10VC04028.87K1%EMPTY 1/16WX7R10%0.1UF25V0402
0402LF05%1/16WEMPTY0402LF05%CHIP1/16W
IND_CPU0_P0_CPL2PVDDCR_CPU0_P0_IMON1PVDDCR_CPU0_P0_LSET1NC_PVDDCR_CPU0_P0_GL1_2NC_PVDDCR_CPU0_P0_GL2_2PVDDCR_CPU0_P0_PWM1PVDDCR_CPU0_P0_IMON2PVDDCR_CPU0_P0_PWM2PVDDCR_CPU0_P0_TEMP0PVDDCR_CPU0_P0_LSET210V0402LFPVDDCR_CPU0_P0_VCCSNC_PVDDCR_CPU0_P0_DNC20402LFIND_CPU0_P0_CPL1
10V1/8WC0805EMPTYPVDDCR_CPU0_P0_VOS116VC0805PVDDCR_CPU0_P0_VCC1SMLF040250VX6S20%C0402EMPTY50V10%1.51%EMPTYIND_CPU0_P0_CPL5SW_PVDDCR_CPU0_P0_SW2_RC5%SW_PVDDCR_CPU0_P0_PH1SW_PVDDCR_CPU0_P0_SW1560PFNC_PVDDCR_CPU0_P0_GL1_125V1UF25V0.1UFISL99390FRZ-TR5935C0805C0805
PR447
2
1 PC502_1
2
1 PC500_1
2
1 PC497
PC479
21
PL53
2
1 PC492
2
1 PC491
4
32
1
PL512
1
PC489
2
1 PC498
2
1 PC501_2
2
1
PC490
2
1 PC487_1
2
1 PC485_1
2
1 PC483_1
21
PR322
2
1 PC178
2
1 PC479_1
2
1 PC477_C0P0_1
2
1
PR318
21
PR320
2
1 PC475
21
PR324
2
1
PR495
2
1 PC488_2
2
1 PC486_2
2
1 PC484_2
2
1 PC480_2
21
PR325
2
1
PR496
2
1 PC473_1
2
1 PC476
21
PR321
2
1 PC474_2
2
1 PC499_2
2
1 PC496
2
1 PC495
2
1 PC494
2
1 PC108
4
32
1
PL52
2
1 PC482_2
21
PR323
2
1 PC179
1
30
25_29
3
36
10_19
39
34
4
32
40
7_9-20_24
5
37
38
41
6
35
31
33
2
PU6
2
1 PC478_C0P0_2
2
1
PR319
1
30
25_29
3
36
10_19
39
34
4
32
40
7_9-20_24
5
37
38
41
6
35
31
33
2
PU43
PR446PR445
PC481_1
1 2
1 4
32
1 4
32
PGND2
GL2
GL1
DNC
EN
PGND3
VOS
VIN2
PGND1
SW
LSET
IOUT
TOUT_FLT
PVCC
PHASE
VIN1
BOOT
AGND
VCC
REFIN
PWM
PGND2
GL2
GL1
DNC
EN
PGND3
VOS
VIN2
PGND1
SW
LSET
IOUT
TOUT_FLT
PVCC
PHASE
VIN1
BOOT
AGND
VCC
REFIN
PWM
2
1
2
1
SHEETDATE
DEPARTMENT
SIZE
PROJECT DOCUMENT NUMBER REV
REVIEWER
DESIGNER
123
7 3 2 1 6 5 4
E
A
B
C
E
D
C
B
A
7 6 5 4
D
BI
BIBI
BI
OUT
OUT
IN
IN
OUT
IN
OUT
IN
C



DCR=1-4,0.105M OHMPGL6303.151HLTISAT:70A@100C11.0*7.5*12.52ND=CV+15^0TZ01DCR=2-3,0.27M OHM
DCR=2-3,0.27M OHMDCR=1-4,0.105M OHM2ND=CV+15^0TZ0111.0*7.5*12.5ISAT:70A@100CPGL6303.151HLT
PVDDCR_CPU0_P0_PHASE3
PVDDCR_CPU0_P0_PHASE4Thu Sep 14 16:12:18 2023<NAME_2><NAME_1>MB FABCGT AMDV02195 OF 365
SW_P12V_AUX_PVDDCR_CPU0_P0_FLT
PVDDCR_CPU0_P0_PVCC
PVDDCR_CPU0_P0_PVCC
SW_P12V_AUX_PVDDCR_CPU0_P0_FLTPVDDCR_CPU0_P0
PVDDCR_CPU0_P0
193194195196198199193194195196193193
193194195196198199193194195196193193195
194 1950402 C04025.6CHIP22UF20%X6SSW_PVDDCR_CPU0_P0_SW322UF0402LFX7R25V1UF
SW_PVDDCR_CPU0_P0_PH410%50V560PF
ISL99390FRZ-TR5935560PF
PVDDCR_CPU0_P0_VCCSPVDDCR_CPU0_P0_PWM4PVDDCR_CPU0_P0_LSET4NC_PVDDCR_CPU0_P0_DNC4PVDDCR_CPU0_P0_TEMP0PVDDCR_CPU0_P0_IMON4PVDDCR_CPU0_P0_VCC4SW_PVDDCR_CPU0_P0_SW4NC_PVDDCR_CPU0_P0_GL2_4NC_PVDDCR_CPU0_P0_GL1_4SW_PVDDCR_CPU0_P0_SW4_RC
PVDDCR_CPU0_P0_VOS3PVDDCR_CPU0_P0_VCCSPVDDCR_CPU0_P0_LSET3NC_PVDDCR_CPU0_P0_DNC3PVDDCR_CPU0_P0_IMON3PVDDCR_CPU0_P0_TEMP0PVDDCR_CPU0_P0_PWM3PVDDCR_CPU0_P0_VCC3SW_PVDDCR_CPU0_P0_SW3_RCSW_PVDDCR_CPU0_P0_PH3
PVDDCR_CPU0_P0_VOS4IND_CPU0_P0_CPL3
IND_CPU0_P0_CPL2 IND_CPU0_P0_CPL3
040225V0.1UF10%X7RC040210V2.2UF10%X6SISL99390FRZ-TR5935ICSMLF1/16WEMPTY1%8.87K0402LF1/16WCHIP1%2.20402LF10%C040210V2.2UFX6S0402LF1.51%EMPTY1/8WC0402EMPTY25V0.1UF10%X7R22UF16VC0805X6S22UF20%16VC08051/16WCHIP5%00402LF040225V0.1UF10%X7R1/16WEMPTY1%8.87K0402LFC040210V2.2UF10%X6S1/16WCHIP1%2.2SMLFICC040210V2.2UF10%X6S0.1UF1%0402LF1.5EMPTY1/8W10%EMPTYC040250V20%16VC0805X6S16VC0805
1/16WCHIP5%00402LF150NHINDSMLF040216V0.22UF10%X7RC080520%16V22UFX6SC0805X6S20%22UF4VC0805X6S20%22UF4V
040216V0.22UF10%X7R150NHINDSMLF16V22UF20%C0805X6SC0805X6S20%22UF4VC0805X6S20%22UF4V
PVDDCR_CPU0_P0 VR PHASE 3&4
040210%25VNC_PVDDCR_CPU0_P0_GL1_3NC_PVDDCR_CPU0_P0_GL2_3X6S20%
10%X6SC0402
1UF25V10%X6S1/16WCHIP1%0402LFSW_PVDDCR_CPU0_P0_BOOT4 SW_PVDDCR_CPU0_P0_BOOT4_RC5.6
1%0402LF1/16WSW_PVDDCR_CPU0_P0_BOOT3 SW_PVDDCR_CPU0_P0_BOOT3_RC
2
1 PC564_3
2
1 PC562_3
2
1 PC558_3
4
32
1
PL592
1
PC560
2
1 PC565_4
2
1 PC563_4
2
1 PC559_4
2
1
PC561
4
32
1
PL60
21
PR351
2
1 PC556_3
2
1 PC554_3
2
1 PC550_3
21
PR348
2
1 PC180
2
1
PR498
2
1 PC552_3
2
1 PC548_C0P0_3
1
30
25_29
3
36
10_19
39
34
4
32
40
7_9-20_24
5
37
38
41
6
35
31
33
2
PU46
2
1
PR344
2
1 PC546
2
1 PC544_3
2
1 PC557_4
2
1 PC553_4
2
1 PC549_C0P0_4
2
1
PR345
21
PR347 1
30
25_29
3
36
10_19
39
34
4
32
40
7_9-20_24
5
37
38
41
6
35
31
33
2
PU47
2
1 PC547
2
1 PC545_4
21
PR346
21
PR350
2
1 PC555_4
2
1 PC551_4
21
PR349
2
1 PC181
2
1
PR499
PGND2
GL2
GL1
DNC
EN
PGND3
VOS
VIN2
PGND1
SW
LSET
IOUT
TOUT_FLT
PVCC
PHASE
VIN1
BOOT
AGND
VCC
REFIN
PWM
1 4
32
1 4
32
PGND2
GL2
GL1
DNC
EN
PGND3
VOS
VIN2
PGND1
SW
LSET
IOUT
TOUT_FLT
PVCC
PHASE
VIN1
BOOT
AGND
VCC
REFIN
PWM
SHEETDATE
DEPARTMENT
SIZE
PROJECT DOCUMENT NUMBER REV
REVIEWER
DESIGNER
123
7 3 2 1 6 5 4
E
A
B
C
E
D
C
B
A
7 6 5 4
D
IN
OUT
BIBI
BI
OUT
OUT
IN
IN
OUT
IN
C



PGL6312.121AHLTISAT:60A@100C2ND=CV+12^0EZ04DCR=0.17M OHM6.5*6.5*10.0
PVDDCR_CPU0_P0_PHASE5
DCR=1-4,0.105M OHM2ND=CV+15^0TZ012ND=CV+15^0TZ01DCR=1-4,0.105M OHMDCR=2-3,0.27M OHM11.0*7.5*12.5ISAT:70A@100CPGL6303.151HLTISAT:70A@100CPGL6303.151HLT11.0*7.5*12.5DCR=2-3,0.27M OHMPVDDCR_CPU0_P0_PHASE6
Thu Sep 14 16:12:40 2023<NAME_2><NAME_1>MB FABCGT AMDV02196 OF 365
PVDDCR_CPU0_P0_PVCCSW_P12V_AUX_PVDDCR_CPU0_P0_FLTSW_P12V_AUX_PVDDCR_CPU0_P0_FLTPVDDCR_CPU0_P0PVDDCR_CPU0_P0
PVDDCR_CPU0_P0_PVCC193193194195196193193
193194195196198199 194196196193194195196193193194195196198199C0402CHIP5.610%SW_PVDDCR_CPU0_P0_BOOT5_RCSW_PVDDCR_CPU0_P0_BOOT50402LF1%1/16W5.6SW_PVDDCR_CPU0_P0_BOOT6_RCSW_PVDDCR_CPU0_P0_BOOT6CHIP1/16W0402LF1%EMPTYIND0402SMLF150NH560PF1UF16VX6SC0805SW_PVDDCR_CPU0_P0_SW5_RCC04021.5C08050.1UFX7RC0402SW_PVDDCR_CPU0_P0_PH50402LF25VX6SC080520%ISL99390FRZ-TR593510%PVDDCR_CPU0_P0_PWM51/16W0402LF2.21%CHIP1/16WPVDDCR_CPU0_P0_VCC6PVDDCR_CPU0_P0_IMON62.2UF10V10%X6S0402LF20%1UF25VSMLF50V50V10%
16V
PVDDCR_CPU0_P0_TEMP0PVDDCR_CPU0_P0_PWM6
PVDDCR_CPU0_P0_VCCSICX6S
PVDDCR_CPU0_P0 VR PHASE 5&6SMLFICISL99390FRZ-TR59354V22UF20%X6SC08054V22UF20%X6SC080520%22UF16VX6SIND150NHSMLF10%16V0.22UF
4V22UF20%X6SC08054V22UF20%X6SC0805X6S16V22UF20%X7R10%0.22UF16V
22UF20%EMPTY10%560PFX6S10%2.2UF10VC04022.21%CHIPX6S10%2.2UF10VC04028.87K1%EMPTY 1/16WX7R10%0.1UF25V04020402LF05%CHIP1/16W1/8WEMPTY0402LF1%16V20%22UFC0805X6SC080522UFX6S10%25V0.1UFX7R10%25V04021%1.50402LF1/8WEMPTY0402LF05%CHIP1/16WC0402X6S10%2.2UF10VC04021/16WEMPTY1%8.87K0402LFX7R10%0.1UF25V0402IND_CPU0_P0_CPL5IND_CPU0_P0_CPL6IND_CPU0_P0_CPL6SW_PVDDCR_CPU0_P0_PH6SW_PVDDCR_CPU0_P0_SW5NC_PVDDCR_CPU0_P0_GL1_5NC_PVDDCR_CPU0_P0_GL2_5PVDDCR_CPU0_P0_VCC5NC_PVDDCR_CPU0_P0_DNC5PVDDCR_CPU0_P0_LSET5PVDDCR_CPU0_P0_IMON5PVDDCR_CPU0_P0_TEMP0PVDDCR_CPU0_P0_VOS5SW_PVDDCR_CPU0_P0_SW6_RCPVDDCR_CPU0_P0_VOS6SW_PVDDCR_CPU0_P0_SW6NC_PVDDCR_CPU0_P0_GL1_6NC_PVDDCR_CPU0_P0_GL2_6NC_PVDDCR_CPU0_P0_DNC6PVDDCR_CPU0_P0_VCCSPVDDCR_CPU0_P0_LSET6
0402X7R040216V22UFC0805X6S
IND120NH/69AC0402IND_CPU0_P0_CPL0SMLF
1
30
25_29
3
36
10_19
39
34
4
32
40
7_9-20_24
5
37
38
41
6
35
31
33
2
PU10
2
1 PC576_5
2
1 PC575_5
2
1 PC573_5
4
32
1
PL612
1
PC574
2
1 PC166_6
2
1 PC163_6
2
1 PC159_6
2
1
PC161
4
32
1
PL70
21
PL50
2
1 PC572_5
2
1 PC571_5
2
1 PC569_5
2
1 PC184
21
PR354
2
1 PC570_5
2
1 PC568_C0P0_5
2
1
PR352
2
1 PC567
21
PR353
2
1 PC566_5
21
PR355
2
1
PR501
2
1 PC158_6
2
1 PC157_6
2
1 PC154_6
21
PR432
2
1 PC153_6
2
1 PC182
2
1
PR500
21
PR433
1
30
25_29
3
36
10_19
39
34
4
32
40
7_9-20_24
5
37
38
41
6
35
31
33
2
PU48
2
1 PC152_C0P0_6
2
1
PR430
2
1 PC151
21
PR431
2
1 PC150_6
PGND2
GL2
GL1
DNC
EN
PGND3
VOS
VIN2
PGND1
SW
LSET
IOUT
TOUT_FLT
PVCC
PHASE
VIN1
BOOT
AGND
VCC
REFIN
PWM
1 4
32
1 4
321 2
PGND2
GL2
GL1
DNC
EN
PGND3
VOS
VIN2
PGND1
SW
LSET
IOUT
TOUT_FLT
PVCC
PHASE
VIN1
BOOT
AGND
VCC
REFIN
PWM
SHEETDATE
DEPARTMENT
SIZE
PROJECT DOCUMENT NUMBER REV
REVIEWER
DESIGNER
123
7 3 2 1 6 5 4
E
A
B
C
E
D
C
B
A
7 6 5 4
D
OUT
OUT
BIBI
IN
BI
OUT
OUT
IN
IN
IN
C



Thu Aug 24 10:15:08 2023<NAME_2><NAME_1>MB FABCGT AMDV02197 OF 365Blank
SHEETDATE
DEPARTMENT
SIZE
PROJECT DOCUMENT NUMBER REV
REVIEWER
DESIGNER
123
7 3 2 1 6 5 4
E
A
B
C
E
D
C
B
A
7 6 5 4
D
C



BOM NOTEMAIN SOURCE:RENESAS BOMPR360,PR361,PR366 = CS00002JB13PR358,PR359,PR365 = CS00002JB13PR362,PR363,PR367 = EMPTYPC577_7,PC578_8,PC605_9 = EMPTYPU49,PU50,PU51 = AL021590000/TDA215902ND SOURCE:INFENEON BOMPU49,PU50,PU51 = AL099390004/ISL99390FRZ-TR5935PU49,PU50,PU51 = AL087000A03/MP87000GMJTH-C11D-ZPC577_7,PC578_8,PC605_9=EMPTYPR362,PR363,PR367=EMPTYPR360,PR361,PR366 = CS00002JB13PVDDCR_SOC_P0_PHASE22ND=CC72703MD396.3*8IRIPPLE:5.08AESR=10M OHM6.0*6.1*7.0ISAT:70A@100C
3RD SOURCE:MPS BOM
ISAT:70A@100CPGL6303.151HLT11.0*7.5*12.5DCR=1-4,0.105M OHMDCR=2-3,0.27M OHM2ND=CV+15^0TZ013RD=CVA50^0MZ08DCR=0.09M OHMPG2292.500HLT2ND=CVA50^0MZ072ND=CH747LM88227.3*4.3*1.9ESR=4.5M OHMISAT:70A@100CPGL6303.151HLT11.0*7.5*12.5DCR=1-4,0.105M OHMDCR=2-3,0.27M OHM2ND=CV+15^0TZ01
PVDDCR_SOC_P0_PHASE1
Thu Sep 14 16:12:18 2023<NAME_2><NAME_1>MB FABCGT AMDV02198 OF 365
C0805X6S20%
5.6SW_PVDDCR_SOC_P0_BOOT2_RCSW_PVDDCR_SOC_P0_BOOT2CHIP1/16W0402LF1%
SW_PVDDCR_SOC_P0_BOOT11/16W0402LF22UF16V20%16V22UF22UFX6S25V10%X6SX6S25V
X6S10%10V2.2UF0402LFPVDDCR_SOC_P0_VCC2PVDDCR_SOC_P0_IMON20.1UF10%C080525V1UFC0805SW_PVDDCR_SOC_P0_SW2SW_PVDDCR_SOC_P0_PH2ICSMLFEMPTY560PF50VC040210%
4V22UF20%X6SC08050402LF1K1%CHIP1/16W4V22UF20%X6SC0805X7R04020.1UF25V10%0.1UF0402X7R10%25VSMLF50NH/86A16VTHLFOSCON150NHSMLFX7R10%16VSPCAP20%470UF2.5VSMLF470UF2.5V20%SPCAPSMLF470UFEMPTY20%2.5VSMLF4V22UFX6SC080520%4V22UFX6SC080520%X6SC080520%SMLFIND150NHX7R04020.22UF16V10%
C080550V1%0.1UFX7R10%IC2.2UF10VC0402X6S10%0402LF1%CHIP1/16W2.22.2UF10VC0402X6S10%8.87KEMPTY 1/16W0.1UF10%X7R040225V0CHIP1/16W5%0402LFX6SX6SC040204021/8WEMPTY1%1.50402LF0402LF0CHIP5%1/16W2.2UF10VC0402X6S10%2.21%CHIP1/16WC04021%8.87K0402LFEMPTY 1/16W0402X7R0.1UF25V10%PVDDCR_SOC_P0_LSET2
IND_SOC_P0_CPL2
IND_SOC_P0_CPL2IND_SOC_P0_CPL3
NC_PVDDCR_SOC_P0_GL1_1NC_PVDDCR_SOC_P0_GL2_1PVDDCR_SOC_P0_LSET1PVDDCR_SOC_P0_PWM1PVDDCR_SOC_P0_IMON1NC_PVDDCR_SOC_P0_DNC1PVDDCR_CPU0_P0_VCCSPVDDCR_SOC_P0_VOS1
SW_PVDDCR_SOC_P0_SW2_RCPVDDCR_SOC_P0_VOS2NC_PVDDCR_SOC_P0_GL1_2NC_PVDDCR_SOC_P0_GL2_2PVDDCR_SOC_P0_PWM2PVDDCR_SOC_P0_TEMP1PVDDCR_CPU0_P0_VCCSNC_PVDDCR_SOC_P0_DNC2PVDDCR_SOC_P0 VR PHASE 1&2
PVDDCR_SOC_P0_VCC10402LFPVDDCR_SOC_P0_TEMP1SW_PVDDCR_SOC_P0_PH1SW_PVDDCR_SOC_P0_SW110%560PF22UF22UF16V0.22UFC0805C040222UF1UF16V20%20%20%16V 16V22UF 22UFX6SC0805IND270UF20%16V20%X6SC0805IND0402C0402ISL99390FRZ-TR593510%25V20%16V22UF16VC0805X6SX6SC080520%5.604021%SW_PVDDCR_SOC_P0_BOOT1_RCSW_PVDDCR_SOC_P0_SW1_RC1.51/8WEMPTY0402LF22UF16V20%X6SX7R193198
198199193193199 198 196 195 194 193
193193 199198198 196 195 194 193193 199198SW_P12V_AUX_PVDDCR_SOC_P0_FLTPVDDCR_SOC_P0P12V_AUXPVDDCR_SOC_P0PVDDCR_SOC_P0
PVDDCR_CPU0_P0_PVCC
PVDDCR_CPU0_P0_PVCCSW_P12V_AUX_PVDDCR_SOC_P0_FLTCHIPEMPTYSMLFISL99390FRZ-TR59351%199
PC8010
PC8009
1
30
25_29
3
36
10_19
39
34
4
32
40
7_9-20_24
5
37
38
41
6
35
31
33
2
PU50
2
1 PC187
PR334
2
1 PC602_1
PC583
21
PL65
2
1 PC596PC593_1
2
1 PC598
2
1 PC603_2
2
1 PC600_2
PC595_2
2
1 PC592_2
4
32
1
PL64
2
1 PC591_1
2
1 PC589_1
2
1 PC587_1
2
1 PC185
2
1
PR502
2
1 PC585_1
1
30
25_29
3
36
10_19
39
34
4
32
40
7_9-20_24
5
37
38
41
6
35
31
33
2
PU49
2
1 PC581_SOP0_1
2
1
PR356
2
1 PC579
21
PR358
21
PR362
2
1 PC586_2
21
PR363
2
1 PC582_SOP0_2
2
1
PR357
2
1 PC580
21
PR359
2
1 PC604_1
2
1 PC599
4
32
1
PL632
1
PC593
2
1 PC601
2
1 PC597
2
1
PC594
21
PR360
2
1 PC583_1
2
1 PC577_7
2
1 PC590_2
2
1 PC588_2
2
1 PC584_2
21
PR361
2
1
PR503
2
1 PC578_8
PGND2
GL2
GL1
DNC
EN
PGND3
VOS
VIN2
PGND1
SW
LSET
IOUT
TOUT_FLT
PVCC
PHASE
VIN1
BOOT
AGND
VCC
REFIN
PWM
1 2
1 4
32
1 4
32
PGND2
GL2
GL1
DNC
EN
PGND3
VOS
VIN2
PGND1
SW
LSET
IOUT
TOUT_FLT
PVCC
PHASE
VIN1
BOOT
AGND
VCC
REFIN
PWM
2
1
2
1
2
1
SHEETDATE
DEPARTMENT
SIZE
PROJECT DOCUMENT NUMBER REV
REVIEWER
DESIGNER
123
7 3 2 1 6 5 4
E
A
B
C
E
D
C
B
A
7 6 5 4
D
OUT
IN
BI
BI
OUT
OUT
IN
BI
IN
OUT
IN
C



PVDDCR_SOC_P0_PHASE3DCR=1-4,0.105M OHMDCR=2-3,0.27M OHM2ND=CV+15^0TZ0111.0*7.5*12.5ISAT:70A@100CPGL6303.151HLT2ND=CV+22Y0EZ01HCME656510Q-221QLDCR=0.17M OHM6.5*6.5*10.0ISAT:30A@100C
Thu Sep 14 16:12:18 2023<NAME_2><NAME_1>MB FABCGT AMDV02199 OF 365
PVDDCR_SOC_P0SW_P12V_AUX_PVDDCR_SOC_P0_FLTPVDDCR_CPU0_P0_PVCC198193198193193193194195196198C040210%25V1UFISL99390FRZ-TR5935PVDDCR_SOC_P0_VCC31%5.6SW_PVDDCR_SOC_P0_BOOT3_RCSW_PVDDCR_SOC_P0_BOOT3CHIP 0402LF1/16W1%1.5C040210%X7R
PVDDCR_SOC_P0 VR PHASE 3
ICSMLF0402 C0805X6S22UF16V20%22UFC0805X6S16V20%C080522UF16V20%X7R10%0.22UF16V04024V20%X6SC080522UF4V22UF20%X6SC0805SMLF150NHIND0.22UH/33A22UF16V20%X6S10%2.2UF10VC04020402LF2.21%CHIP1/16W10%2.2UF10VC0402X6S560PF50VEMPTY0402LF05%CHIP1/16W1/8WEMPTY1%0402LF0402LF8.87KEMPTY 1/16WX7R10%0.1UF25V0402IND_SOC_P0_CPL3IND_SOC_P0_CPL0SW_PVDDCR_SOC_P0_PH3PVDDCR_SOC_P0_IMON3SW_PVDDCR_SOC_P0_SW3_RCPVDDCR_SOC_P0_VOS3NC_PVDDCR_SOC_P0_GL2_3NC_PVDDCR_SOC_P0_GL1_3PVDDCR_SOC_P0_LSET3NC_PVDDCR_SOC_P0_DNC3PVDDCR_SOC_P0_TEMP1PVDDCR_SOC_P0_PWM3PVDDCR_CPU0_P0_VCCSINDSMLFX6SX6S10%25VSW_PVDDCR_SOC_P0_SW3C0805X6S0.1UF
PL62
PC612_3
2
1
PC612
2
1 PC614_3
2
1 PC607_SOP0_3
2
1
PR364
2
1 PC606
2
1 PC188
21
PR367
2
1
PR505
2
1 PC605_9
1
30
25_29
3
36
10_19
39
34
4
32
40
7_9-20_24
5
37
38
41
6
35
31
33
2
PU51
2
1 PC609_3
2
1 PC613_3
2
1 PC611_3
2
1 PC615_3
4
32
1
PL66
2
1 PC610_3
2
1 PC608_3
21
PR366
21
PR365 21
PGND2
GL2
GL1
DNC
EN
PGND3
VOS
VIN2
PGND1
SW
LSET
IOUT
TOUT_FLT
PVCC
PHASE
VIN1
BOOT
AGND
VCC
REFIN
PWM
1 4
321 2
SHEETDATE
DEPARTMENT
SIZE
PROJECT DOCUMENT NUMBER REV
REVIEWER
DESIGNER
123
7 3 2 1 6 5 4
E
A
B
C
E
D
C
B
A
7 6 5 4
D
OUT
IN
BI
OUT
IN
C



MAIN SOURCE:RENESAS BOMPU12 = TBD/RAA229620GNP#HA02ND SOURCE:INFENEON BOMTRACE SPACING = 5MILTRACE WIDTH = 10MILDIFFERENTIAL PAIR
/1.07KCONFIG/RTRACE SPACING = 5MILTRACE WIDTH = 10MILDIFFERENTIAL PAIRIRM REV1.09SVI3 ADDRESS=PORT1 (0X2)MAX LOAD RELEASE=37AMAX LOAD STEP=44AEDC=140AVID=0.9-1.2VEFFICIENCY > 90% @TDCLOAD-LINE=0.4MOHMMAX LOAD RELEASE=200AEDC=230ATDC=175AMAX AC=VID+200MVDC=+/-20MVVID=0.55-1.5VDEFAULT POWER-ON VID=0.9VEFFICIENCY > 90% @TDCIRM REV1.09OCP=168A (EDC*1.2)DEFAULT POWER-ON VID=1.1VPVDDIO_P0 SPECFICATIONSVI3 ADDRESS=PORT1 (0X1)WORK FREQUENCY=600KHZMAX LOAD STEP=200AOCP=276A (EDC*1.2)DC & AC=+/-80MV
/66.5K
TDC=120APVDDCR_CPU1_P0 SPECFICATIONMIN AC=VID-EDC*LL-110MVWORK FREQUENCY=600KHZ
MPS 0X4E0X4EVRINFINEONRENESASPC67 = CH3104J1B00PC68,PC71 = CH12206KB14PC77,PC78 = CH11006JB00PC76 = CH5103KEB01PR67 = CS21072FB04PR68,PR69 = CS01002FB07PR532,PR32 = EMPTYPR54 = CS21002FB06PR53 = CS25362FB02PU12 = TBD/XDPE192C3BPR532,PR32 = EMPTYPC76=CH5103KEB01PC74 = CH21006JB10PC68,PC71 = EMPTYPC77,PC78 = CH31004KB17PR600 = CS24992FB07PR74 = CS37502FB05PR67 = CS36652FB03PR54 = CS00002JB13PR53,PC67 = EMPTY3RD SOURCE:MPS BOMBOM NOTEPU12 = TBD/MP2857GQKT-001B-Z1/1.96K0X62ADDRESS(7-BIT)PMBUS ADDRESS AND CONFIGThu Sep 14 16:12:40 2023<NAME_2><NAME_1>MB FABCGT AMDV02200 OF 365
VSENSE_PVDDCR_CPU1_P0_DP10%CHIP
PVDDCR_CPU1_P0/PVDDIO_P0 VR CONTROLLER81PVDDCR_CPU1_P0_EN1_ADDR_CFGI6CHIP1/16W1%PVDDIO_P0_EN_G1%0402LF1KPVDDIO_P0_EN PVDDIO_P0_EN_R1/16WCHIP
0402LFSVID_PVDDCR_CPU1_P0_SVTIPVDDCR_CPU1_P0_SMB_ALERT0402LFX7R0402CHIPPVDDCR_CPU1_P0_RESET_NCHIPPVDDCR_CPU1_P0_OCP_N1/16W1000PFPVDDCR_CPU1_P0_VINSEN
1/16WSVID_PVDDCR_CPU1_P0_SVC_R0402LF5%1/16WCHIP00402LF5%CHIP5%50VCHIP10PF33CHIP1%1/16WEMPTY5%CHIP1000PFCHIP 1/16W0402LF
0402LF1/16W
04021000PF
CHIP49.9CHIPCHIP0402LFEMPTYX7R
1/16W
1000PF
1/16W5%335%
33CHIP5%0402LF1/16W49.9005%CHIP0402
1%1/16W
1K1K1K1K1%1K
0402LF6.3VVSENSE_VSS_SENSE_B_P0VSENSE_PVDDIO_P0_DPVSENSE_VSS_SENSE_C_P0ICCHIP10K0402LF1%1%1.96KICPJA3415AE0402LF1/16W1/16WCHIP0402LF49.91%1/16WCHIP0402LF1%1/16W1%0402LFEMPTY040210PFEMPTY50V040210PF5%50V1/16WEMPTY0402LFEMPTY1/16W1%1%0402LF
10%X7R04021/16WCHIP5%00402LF1%1K50V5%EMPTY0402EMPTY1%4.99K0402LF1/16W04020.1UF25VX7R10%X7R 040210%1UF0402LF5%1%1K10%3300PFCHIP1%1K0402LF470PF0402040250V470PF10%X7R1/16W5%00402LF5%01/16W5%50V1000PF5%0CHIP1K0402LF50V0.1UF0402X7R10%040225V0.1UF10%X7RX6S10UF6.3V16V1UF10%X6S1/16W1CHIP
25V0.1UF0402LF1/16W0CHIP5%00402LF
04021000PF1/16W0402LFCHIP5%50V05%1/16W1%10K
C040220%25V50V001/16W0402LF1/16WCHIPCHIP49.91%0402LF1/16WCHIPX7R50V0402
CHIP40.2KX7R04025% 50V
X7R50V1/16WEMPTY04025%
0402LF
0402LF0EMPTY1/16W1/16W5%50V5%1/16WCHIP0402LF
5%
PVDDCR_CPU1_P0_TEMP0PVDDCR_CPU1_P0_RESET_N_RPVDDIO_P0_TEMP1
SMB_SCM_2_R5_SCLVSENSE_PVDDIO_P0_VSEN11/16W5%0402LF
50V10%X7R
1%1%0402X7RVSENSE_PVDDCR_CPU1_P0_VSEN0
PWRGD_PVDDIO_P0BSS138K1%0402LF1/16W100
5%0402LF3300PF0402X7R1000PFCHIPEMPTY01/16WPWRGD_PVDDCR_CPU1_P0SVID_PVDDCR_CPU1_P0_SVD_R0402LFFM_PVDDCR_CPU1_P0_EN0402LFCHIP 1/16WSVID_PVDDCR_CPU1_P0_SVTO49.91%ICRAA229620GNP#HA0SMLFPVDDCR_CPU1_P0_IMON1PVDDCR_CPU1_P0_VCCSVID_PVDDCR_CPU1_P0_SVTI_RSMB_CLK_PVDDCR_CPU1_P0_RSVID_PVDDCR_CPU1_P0_SVC_R1PVDDCR_CPU1_P0_IMON6SVID_PVDDCR_CPU1_P0_SVTO_RNC_PVDDCR_CPU1_P0_IMON7NC_PVDDCR_CPU1_P0_IMON8PWRGD_PVDDIO_P0_R
SVID_PVDDCR_CPU1_P0_SVD_R1PVDDCR_CPU1_P0_SMB_ALERT_RPVDDCR_CPU1_P0_EN_RNC_PVDDCR_CPU1_P0_PWM8NC_PVDDCR_CPU1_P0_PWM7PVDDIO_P0_PWM2
PWRGD_PVDDCR_CPU1_P0_RPVDDCR_CPU1_P0_PWM6PVDDCR_CPU1_P0_VMONPVDDIO_P0_IMON2
PVDDCR_CPU1_P0_PWM1PVDDIO_P0_PWM4PVDDIO_P0_IMON4PVDDIO_P0_PWM3PVDDIO_P0_IMON3PVDDCR_CPU1_P0_OCP_N_RPVDDIO_P0_PWM1PVDDIO_P0_IMON1PVDDCR_CPU1_P0_PWM5PVDDCR_CPU1_P0_IMON5PVDDCR_CPU1_P0_PWM4PVDDCR_CPU1_P0_IMON4PVDDCR_CPU1_P0_PWM3PVDDCR_CPU1_P0_IMON3PVDDCR_CPU1_P0_PWM2PVDDCR_CPU1_P0_IMON2271512727207278281
82 83
203202201206205
2062052032022012778
82278227 203205203205
2012062062062062052052032032022022022022012015%1510402LF201
P12V_AUXP3V3_AUXPVDDIO_P0P3V3_AUX
PVDD18_S5_P0
P3V3_AUX
PVDD18_S5_P0P5V_AUXP3V3_AUX
PVDD18_S5_P0PVDDCR_CPU1_P01/16WEMPTYSMB_SCM_2_R5_SDA SMB_DIO_PVDDCR_CPU1_P0_RPVDDCR_CPU1_P0_VCCSC04020402LF
0402LF
R6086
PR8007
PR8008
21C5004
21C5005
40
25
45
46
19
48
47
TH
43
44
23
24
21
22
39
26
18
12
11
10
9
8
7
6
5
4
3
2
1
13
14
20
16
41
15
42
17
27
28
29
30
31
32
33
34
35
36
37
38
PU12
21PR76
2
1
PC75
2
1
PC76
2
1 PC14
2
1 PC15
21C807021R8056
21R8057
21R8058
21C8069
21R8071
21
PR62
21
R61
21R8072
21R8073
2
1
PC68
21PR68
21
PR32
PR532
2
1 PC77
2
1 PC78
21
R8075
21PR69
2
1
PC71
21R8070
21
R8063
21
R8064
21
PC73
2
1
PC74PR600
21C807221R8065
21R8066
21
PR74
2
1
PC67
2
1
R8048
2
1
R8045
2
1
R8043
2
1
PR41
21PR51
2
1 C305
2
1 C304
2
1 C303
2
1
R8042
2
1
PR40
21PR49
21PR52
21PR50
2
1
PR55
G
PQ10
2
1 PR67
21
PR53
2
1
PR54
G
PQ14
2
1 C8066
21
R8047
SDS D
C5013
S
G
D
G
CS10
PWM10
CS9
PWM9
CS8
PWM8
CS7
PWM7
CS0
PWM0
TEMP1
EN1||ADDR_CFG
TH_GND
OCP_L
CS2
PWM2
CS3
PWM3
PWM11
CS1
RGND1
VSEN1
VDDIO
TEMP0
VINSEN
VMON||IINSEN
VCCS
PWM6
PG0
PWM1
VSEN0
PWM5
PWM4
PMSDA
RGND0
EN0
nPMALERT
SVD
PG1
CS4
CS5
RESET_L
SVTO
CS6
SVC
PMSCL
SVTI
VCC
CS11
SD
21
21
2
1
2
1
SHEETDATE
DEPARTMENT
SIZE
PROJECT DOCUMENT NUMBER REV
REVIEWER
DESIGNER
123
7 3 2 1 6 5 4
E
A
B
C
E
D
C
B
A
7 6 5 4
D
OUT
OUT
IN
OUT
IN
OUT
BI
IN
IN
IN
OUT
IN
IN
IN
IN
OUT
OUT
IN
OUT
IN
OUT
IN
OUT
IN
OUT
IN
OUT
IN
OUT
IN
OUT
IN
OUT
IN
IN
OUT
IN
IN
IN
C



PR82,PR81,PR90,PR89,PR95,PR420 = CS00002JB132ND=CC72703MD39PGL6303.151HLTISAT:70A@100CPVDDCR_CPU1_P0_PHASE1
2ND=CV+15^0TZ01DCR=2-3,0.27M OHMDCR=1-4,0.105M OHM11.0*7.5*12.5ISAT:70A@100CPGL6303.151HLTMAIN=CH122KM8801ESR=9M OHM7.3*4.3*1.96.3*82ND=CV+15^0TZ01DCR=2-3,0.27M OHMDCR=1-4,0.105M OHM11.0*7.5*12.5ESR=10M OHMISAT:70A@100CPG2292.500HLT6.0*6.1*7.0PVDDCR_CPU1_P0_PHASE2IRIPPLE:5.08A3RD SOURCE:MPS BOMPR84,PR83,PR92,PR91,PR96,PR421 = EMPTYPC84_1,PC83_2,PC114_3,PC113_4,PC132_5,PC111_6 = EMPTYPR442,PR84,PR83,PR92,PR91,PR96,PR421 = EMPTYPR443,PR81,PR82,PR89,PR90,PR95,PR420 = CS00002JB13PU13,PU2,PU15,PU14,PU16,PU11 = AL087000A03/MP87000GMJTH-C11D-ZPC84_1,PC83_2,PC114_3,PC113_4,PC132_5,PC111_6 = EMPTYPR78,PR77,PR86,PR85,PR93,PR7 = CS00002JB13PU13,PU2,PU15,PU14,PU16,PU11 = AL021590000/TDA21590BOM NOTEMAIN SOURCE:RENESAS BOMPU13,PU2,PU15,PU14,PU16,PU11=AL099390004/ISL99390FRZ-TR59352ND SOURCE:INFENEON BOMDCR=0.09M OHM2ND=CVA50^0MZ073RD=CVA50^0MZ08
Thu Sep 14 16:12:18 2023<NAME_2><NAME_1>MB FABCGT AMDV02201 OF 365
NC_PVDDCR_CPU1_P0_DNC1SW_PVDDCR_CPU1_P0_BOOTR10402LFTHLFOSCONEMPTYPVDDCR_CPU1_P0P12V_AUX
PVDDCR_CPU1_P0PVDDCR_CPU1_P0SW_P12V_AUX_PVDDCR_CPU1_P0_FLTSW_P12V_AUX_PVDDCR_CPU1_P0_FLT
PVDDCR_CPU1_P0_PVCCP3V3_AUXP5V_AUX
PVDDCR_CPU1_P0_PVCC201202203201200200
201202203200200
201202203200200201202203205206200200201202203205206C0402X6S10%25V1UF5.6SW_PVDDCR_CPU1_P0_BOOT1_RSW_PVDDCR_CPU1_P0_BOOT11/16W1%CHIP5.6SW_PVDDCR_CPU1_P0_BOOT2_RSW_PVDDCR_CPU1_P0_BOOT2CHIP1%1/16W0402LFNC_PVDDCR_CPU1_P0_GL2_1PVDDCR_CPU1_P0_LSET1X6SC08050.22UF0.22UFISL99390FRZ-TR593510%
PVDDCR_CPU1_P0 VR PHASE 1&2
0402LF1K1%CHIP1/16WX6S4V22UF20%C080510%X7R040225V0.1UF4V22UF20%X6SC0805X7R10%0.1UF25V040250NH/86ASMLFIND20%THLF270UF16V
4V22UF20%X6SC0805SMLF4V220UF20%SPCAPSMLF4V220UF20%SPCAP4VSMLFSPCAP20%220UFSPCAP20%4V220UFSMLF4V220UFSPCAP20%SMLF4V22UF20%X6SC0805
20%OSCON270UF16VC0805X6S22UF16V20%X6SC080522UF16V20%SMLF150NHIND10%X7R16V0402C080522UF16V20%X6S10%X6S25V1UFEMPTY10%560PF50VC0402040225V0.1UFX7R01/16W5%0402LFCHIPC0805X6S22UF16V20%22UF16V20%1/8W1%1.5C0805X6S22UF16V20%INDSMLF150NHX7R04020402LF0CHIP1/16W5%EMPTY10%560PFEMPTY1/8W1%1.50402LF10%0.1UF25V0402
SMLFICISL99390FRZ-TR5935SMLFIC
X6S10%2.2UF10VC04020402LF2.21%CHIP1/16W0402LF05%EMPTY1/16WX6S10%2.2UF10VC04020402LF05%CHIP1/16W0402LF8.87K1%EMPTY1/16W2.2UFX6S10%10VC04021/16W0402LF2.21%CHIPX7R10%0.1UF25V0402X6S10%2.2UF10VC04021/16WEMPTY1%8.87K0402LFX7R10%0.1UF25V0402
IND_CPU1_P0_CPL1IND_CPU1_P0_CPL2IND_CPU1_P0_CPL5NC_PVDDCR_CPU1_P0_GL1_1PVDDCR_CPU1_P0_VCC1PVDDCR_CPU1_P0_VOS1IND_CPU1_P0_CPL1SW_PVDDCR_CPU1_P0_SW2_RCNC_PVDDCR_CPU1_P0_GL2_2NC_PVDDCR_CPU1_P0_GL1_2SW_PVDDCR_CPU1_P0_BOOTR2PVDDCR_CPU1_P0_VOS2SW_PVDDCR_CPU1_P0_SW2PVDDCR_CPU1_P0_VCC2NC_PVDDCR_CPU1_P0_DNC2PVDDCR_CPU1_P0_PWM1PVDDCR_CPU1_P0_IMON1
PVDDCR_CPU1_P0_TEMP0PVDDCR_CPU1_P0_PWM2
PVDDCR_CPU1_P0_TEMP0PVDDCR_CPU1_P0_LSET2PVDDCR_CPU1_P0_VCCSPVDDCR_CPU1_P0_IMON2PVDDCR_CPU1_P0_VCCS
C040250V10%16VX7RSW_PVDDCR_CPU1_P0_SW1C04020402LFSW_PVDDCR_CPU1_P0_SW1_RC
PR444
2
1
PC105_1
2
1
PC102_1
2
1
PC99
21 PL12
2
1
PC104
2
1
PC108_2
2
1 PC100
2
1 PC98
2
1 PC97
2
1 PC102
2
1
PC106_2
2
1
PC91_1
4
32
1
PL102
1 PC92
2
1
PC89_1
2
1
PC87_1
2
1 PC189
PR82
2
1
PC85_1
21
PR84
2
1
PC96_2
2
1
PC93_2
2
1
PR506
2
1
PC90_2
2
1 PC94
21
PR83
PR81
2
1
PR507
2
1
PC86_2
1
30
25_29
3
36
10_19
39
34
4
32
40
7_9-20_24
5
37
38
41
6
35
31
33
2
PU13
1
30
25_29
3
36
10_19
39
34
4
32
40
7_9-20_24
5
37
38
41
6
35
31
33
2
PU2
2
1 PC81_C1P0_1
2
1
PR79
PR443
2
1
PR78
2
1 PC82_C1P0_2
2
1
PR80
2
1 PC84_1
2
1 PC80
2
1
PR77
PC85
2
1 PC103
2
1
PC101
2
1
PC95_1
2
1
PC88_2
4
32
1
PL11
2
1 PC190
2
1 PC79
PR442
2
1 PC83_2
1 2
1 4
32
1 4
32
PGND2
GL2
GL1
DNC
EN
PGND3
VOS
VIN2
PGND1
SW
LSET
IOUT
TOUT_FLT
PVCC
PHASE
VIN1
BOOT
AGND
VCC
REFIN
PWM
PGND2
GL2
GL1
DNC
EN
PGND3
VOS
VIN2
PGND1
SW
LSET
IOUT
TOUT_FLT
PVCC
PHASE
VIN1
BOOT
AGND
VCC
REFIN
PWM
2
1
SHEETDATE
DEPARTMENT
SIZE
PROJECT DOCUMENT NUMBER REV
REVIEWER
DESIGNER
123
7 3 2 1 6 5 4
E
A
B
C
E
D
C
B
A
7 6 5 4
D
BI
IN
OUT
BI
IN
BI
OUT
BI
OUT
IN
OUT
IN
C



PVDDCR_CPU1_P0_PHASE4PVDDCR_CPU1_P0_PHASE3
11.0*7.5*12.5PGL6303.151HLTISAT:70A@100CDCR=1-4,0.105M OHMDCR=2-3,0.27M OHM2ND=CV+15^0TZ01DCR=2-3,0.27M OHM11.0*7.5*12.52ND=CV+15^0TZ01DCR=1-4,0.105M OHMISAT:70A@100CPGL6303.151HLT
Thu Sep 14 16:12:19 2023<NAME_2><NAME_1>MB FABCGT AMDV02202 OF 365PVDDCR_CPU1_P0_PVCCPVDDCR_CPU1_P0_PVCCSW_P12V_AUX_PVDDCR_CPU1_P0_FLTPVDDCR_CPU1_P0
SW_P12V_AUX_PVDDCR_CPU1_P0_FLTPVDDCR_CPU1_P0
200201202203200200201202203205206200201202203200200200201202203205206200
202201202C0402X6S0402LFCHIP5.6C040210%25V1UFX6S25VX7RSW_PVDDCR_CPU1_P0_BOOT3_RSW_PVDDCR_CPU1_P0_BOOT30402LF1/16W1%5.6SW_PVDDCR_CPU1_P0_BOOT4_RSW_PVDDCR_CPU1_P0_BOOT41%0402LFCHIP1/16W
04020.22UF10%16VSMLFISL99390FRZ-TR5935SW_PVDDCR_CPU1_P0_BOOTR4SW_PVDDCR_CPU1_P0_SW4
C0402
PVDDCR_CPU1_P0_PWM4PVDDCR_CPU1_P0_TEMP0PVDDCR_CPU1_P0_LSET4PVDDCR_CPU1_P0_VCCSPVDDCR_CPU1_P0_VCC4PVDDCR_CPU1_P0_PWM3PVDDCR_CPU1_P0_TEMP0PVDDCR_CPU1_P0_IMON4NC_PVDDCR_CPU1_P0_DNC4PVDDCR_CPU1_P0_LSET3PVDDCR_CPU1_P0_VCCSPVDDCR_CPU1_P0_IMON3PVDDCR_CPU1_P0_VCC3NC_PVDDCR_CPU1_P0_DNC3PVDDCR_CPU1_P0_VOS3PVDDCR_CPU1_P0_VOS4NC_PVDDCR_CPU1_P0_GL2_4NC_PVDDCR_CPU1_P0_GL1_4NC_PVDDCR_CPU1_P0_GL1_3NC_PVDDCR_CPU1_P0_GL2_3SW_PVDDCR_CPU1_P0_SW4_RCIND_CPU1_P0_CPL3IND_CPU1_P0_CPL2 IND_CPU1_P0_CPL3
X7R10%0.1UF25V04020402LF8.87K1%EMPTY1/16WX6S10%2.2UF10VC0402X7R10%0.1UF25V04020402LF2.21%CHIP1/16WX6S10%2.2UF10VC04020402LF8.87K1%EMPTY1/16WIC
SMLFICISL99390FRZ-TR593510%0.1UF0402X6S10%2.2UF10V0402LF2.21%CHIP1/16WX6S10%2.2UF10VC0402X7R10%0.1UF25V
1/8WEMPTY1%1.50402LFEMPTY10%560PF50VC04020402LF05%CHIP1/16WX7R040210%16V0.22UFSMLFIND150NH20%16V22UFC0805X6S20%16V22UFX6SC080520%16V22UFC0805X6S0402LF05%CHIP1/16WC08054V22UF20%X6SC08054V22UF20%X6SEMPTY10%560PF50VC040220%16V22UFC0805X6S0402SMLFIND150NH20%16V22UFC0805X6S20%16V22UFC0805X6SC08054V22UF20%X6SC08054V22UF20%X6S
PVDDCR_CPU1_P0 VR PHASE 3&4
1.51%1/8WEMPTYSW_PVDDCR_CPU1_P0_SW3SW_PVDDCR_CPU1_P0_BOOTR3X7RSW_PVDDCR_CPU1_P0_SW3_RC1UF25V10%
2
1
PC130_3
2
1
PC129_3
2
1
PC126_3
2
1
PC124_3
4
32
1
PL142
1 PC122
2
1
PC120_3
2
1
PC118_3
2
1 PC192
PR90
2
1
PC127_4
2
1
PC125_4
2
1
PC123_4
2
1
PR510
2
1
PC119_4
2
1
PC117_4
2
1 PC121
2
1
PR509
2
1 PC116_3
2
1 PC112_C1P0_3
2
1 PC110
2
1
PC115_4
1
30
25_29
3
36
10_19
39
34
4
32
40
7_9-20_24
5
37
38
41
6
35
31
33
2
PU15
1
30
25_29
3
36
10_19
39
34
4
32
40
7_9-20_24
5
37
38
41
6
35
31
33
2
PU14
2
1
PR86
2
1 PC111_C1P0_4
2
1
PR87
2
1 PC114_3
2
1 PC109
2
1
PR85
2
1
PC128_4
21
PR92
4
32
1
PL13
21 PR91
2
1 PC191
PR89
2
1
PR88
2
1 PC113_4
1 4
32
1 4
32
PGND2
GL2
GL1
DNC
EN
PGND3
VOS
VIN2
PGND1
SW
LSET
IOUT
TOUT_FLT
PVCC
PHASE
VIN1
BOOT
AGND
VCC
REFIN
PWM
PGND2
GL2
GL1
DNC
EN
PGND3
VOS
VIN2
PGND1
SW
LSET
IOUT
TOUT_FLT
PVCC
PHASE
VIN1
BOOT
AGND
VCC
REFIN
PWM
SHEETDATE
DEPARTMENT
SIZE
PROJECT DOCUMENT NUMBER REV
REVIEWER
DESIGNER
123
7 3 2 1 6 5 4
E
A
B
C
E
D
C
B
A
7 6 5 4
D
IN
OUT
BIBI
IN
BI
OUT
IN
OUT
IN
OUT
C



PVDDCR_CPU1_P0_PHASE6DCR=1-4,0.105M OHMDCR=2-3,0.27M OHM2ND=CV+15^0TZ0111.0*7.5*12.5ISAT:70A@100CPGL6303.151HLTDCR=1-4,0.105M OHMPGL6303.151HLTISAT:70A@100C11.0*7.5*12.5DCR=2-3,0.27M OHM2ND=CV+15^0TZ01
PVDDCR_CPU1_P0_PHASE5
PGL6312.121AHLTISAT:60A@100C6.5*6.5*10.0DCR=0.17M OHM2ND=CV+12^0EZ04Thu Sep 14 16:12:19 2023<NAME_2><NAME_1>MB FABCGT AMDV02203 OF 365
PVDDCR_CPU1_P0SW_P12V_AUX_PVDDCR_CPU1_P0_FLT
PVDDCR_CPU1_P0SW_P12V_AUX_PVDDCR_CPU1_P0_FLTPVDDCR_CPU1_P0_PVCCPVDDCR_CPU1_P0_PVCC203203200201202203205206200
2012022032002002012022032052062002012022032002002002010402CHIP1%10%
PVDDCR_CPU1_P0 VR PHASE 5&6ICC0402EMPTY10%50V4V22UF20%X6SC08054V22UF20%X6SC080520%16VC0805X6S22UF20%X6S22UFIND150NHSMLFX7R04020.22UF16VC0805X6S22UF16VX6S10%1UF25VX7R10%0.1UF25VEMPTY10%560PF50VC04024V22UF20%X6SC08054V22UF20%X6SC0805CHIP1/16W0402LF05%C0805X6S22UF16V20%C0805X6S22UF16V1/8WEMPTY1%1.50402LFX6SC080522UF16V20%X6S10%1UF25VC0402X7R10%0.1UF25VIND150NHSMLF0.22UF16V10%X7R04020402LF05%CHIP1/16W1%1/8W1.50402LFEMPTY
X6S10%2.2UF10VC04020402LF2.21%CHIP1/16WX6S10%2.2UF10VC0402SMLFICX6S10%10V2.2UF0402LF8.87K1%EMPTY1/16W2.21%CHIP1/16WX6S10%2.2UF10VC0402X7R10%0.1UF25V04020402LF8.87K1%EMPTY1/16WX7R10%0.1UF25V0402SW_PVDDCR_CPU1_P0_SW6IND_CPU1_P0_CPL6SW_PVDDCR_CPU1_P0_SW5_RCIND_CPU1_P0_CPL6PVDDCR_CPU1_P0_VOS5PVDDCR_CPU1_P0_VOS6SW_PVDDCR_CPU1_P0_SW6_RCNC_PVDDCR_CPU1_P0_GL2_6NC_PVDDCR_CPU1_P0_GL1_6SW_PVDDCR_CPU1_P0_BOOTR6NC_PVDDCR_CPU1_P0_GL1_5SW_PVDDCR_CPU1_P0_SW5NC_PVDDCR_CPU1_P0_DNC5PVDDCR_CPU1_P0_VCC5PVDDCR_CPU1_P0_LSET5PVDDCR_CPU1_P0_VCCSPVDDCR_CPU1_P0_IMON5PVDDCR_CPU1_P0_VCC6NC_PVDDCR_CPU1_P0_DNC6PVDDCR_CPU1_P0_TEMP0PVDDCR_CPU1_P0_LSET6PVDDCR_CPU1_P0_VCCSPVDDCR_CPU1_P0_IMON6PVDDCR_CPU1_P0_TEMP0PVDDCR_CPU1_P0_PWM6PVDDCR_CPU1_P0_PWM5NC_PVDDCR_CPU1_P0_GL2_5IND_CPU1_P0_CPL516VC0805ISL99390FRZ-TR593520%20%0402
SMLFIND120NH/69A560PFIND_CPU1_P0_CPL01%0402LF1/16WCHIPSW_PVDDCR_CPU1_P0_BOOT6 SW_PVDDCR_CPU1_P0_BOOT6_R5.60402LF1/16WSW_PVDDCR_CPU1_P0_BOOT5_R0402LF C0402ISL99390FRZ-TR5935SMLFC04025.6SW_PVDDCR_CPU1_P0_BOOTR5SW_PVDDCR_CPU1_P0_BOOT5
1
30
25_29
3
36
10_19
39
34
4
32
40
7_9-20_24
5
37
38
41
6
35
31
33
2
PU11
2
1 PC154
2
1
PC141_5
2
1
PC140_5
2
1
PC139_5
2
1
PC138_5
4
32
1
PL152
1 PC137
2
1
PC134_5
2
1 PC157
PR95
2
1
PC123_6
2
1
PC120_6
21 PR96
2
1
PC119_6
2
1
PC118_6
2
1
PR158
2
1
PC116_6
2
1
PC115_6
4
32
1
PL72
1 PC117
2 1
PL9
21 PR421
2
1
PR155
2
1
PR94
2
1 PC131
1
30
25_29
3
36
10_19
39
34
4
32
40
7_9-20_24
5
37
38
41
6
35
31
33
2
PU16
2
1 PC113_C1P0_6
2
1
PR93
2
1
PR416
2
1 PC112
2
1 PC132_5
2
1
PR7
2
1 PC111_6
2
1
PC136_5
2
1
PC135_5
2
1
PC114_6
PR420
2
1 PC133_C1P0_5
PGND2
GL2
GL1
DNC
EN
PGND3
VOS
VIN2
PGND1
SW
LSET
IOUT
TOUT_FLT
PVCC
PHASE
VIN1
BOOT
AGND
VCC
REFIN
PWM
1 4
32
1 4
3212
PGND2
GL2
GL1
DNC
EN
PGND3
VOS
VIN2
PGND1
SW
LSET
IOUT
TOUT_FLT
PVCC
PHASE
VIN1
BOOT
AGND
VCC
REFIN
PWM
SHEETDATE
DEPARTMENT
SIZE
PROJECT DOCUMENT NUMBER REV
REVIEWER
DESIGNER
123
7 3 2 1 6 5 4
E
A
B
C
E
D
C
B
A
7 6 5 4
D
OUT
IN
BIBI
OUT
BI
IN
OUT
IN
IN
OUT
C



Thu Aug 24 10:15:12 2023<NAME_2><NAME_1>MB FABCGT AMDV02204 OF 365Blank
SHEETDATE
DEPARTMENT
SIZE
PROJECT DOCUMENT NUMBER REV
REVIEWER
DESIGNER
123
7 3 2 1 6 5 4
E
A
B
C
E
D
C
B
A
7 6 5 4
D
C



6.0*6.1*7.0DCR=0.09M OHMPG2292.500HLT
BOM NOTEPVDDIO_P0_PHASE22ND=CV+15^0TZ01DCR=2-3,0.27M OHMDCR=1-4,0.105M OHMPGL6303.151HLTISAT:70A@100C11.0*7.5*12.53RD=CVA50^0MZ082ND=CVA50^0MZ07ISAT:70A@100CESR=10M OHMIRIPPLE:5.08A2ND=CC72703MD396.3*8ESR=4.5M OHM7.3*4.3*1.92ND=CH747LM8822PGL6303.151HLTISAT:70A@100C11.0*7.5*12.5DCR=1-4,0.105M OHMDCR=2-3,0.27M OHM2ND=CV+15^0TZ013RD SOURCE:MPS BOMPR103,PR104,PR111,PR112=EMPTYPR98,PR97,PR106,PR105 = CS00002JB132ND SOURCE:INFENEON BOMMAIN SOURCE:RENESAS BOM
PVDDIO_P0_PHASE1
PU17,PU18,PU19,PU20 =AL099390004/ISL99390FRZ-TR5935PR101,PR102,PR109,PR110=CS00002JB13PC145_7,PC146_8,PC175_9,PC176_10 = EMPTYPC145_7,PC146_8,PC175_9,PC176_10=EMPTYPU17,PU18,PU19,PU20=AL087000A03/MP87000GMJTH-C11D-ZPR103,PR104,PR111,PR112 = EMPTYPR101,PR102,PR110,PR109 = CS00002JB13PU17,PU18,PU19,PU20 = AL021590000/TDA21590Thu Sep 14 16:12:41 2023<NAME_2><NAME_1>MB FABCGT AMDV02205 OF 365PVDDIO_P0_LSET2206 205 2022032.2 PVDDIO_P0P12V_AUXSW_P12V_AUX_PVDDIO_P0_FLTPVDDIO_P0PVDDIO_P0SW_P12V_AUX_PVDDIO_P0_FLTPVDDCR_CPU1_P0_PVCCPVDDCR_CPU1_P0_PVCC
PVDDIO_P0_VR PHASE 1&2PVDDIO_P0_VCC20402LF205205206
200205206200200201202203205206200205206200200200201200
270UF0.1UF22UF16V20%X6SC080516V16VOSCONTHLF20%20%X6S22UFC080516V20%C040220%X6S22UF10%X7RSW_PVDDIO_P0_BOOT1SMLFICISL99390FRZ-TR5935040225V0.1UF10%X7R X6S10%1UF25VC0805X6S16V0402LF1K1%CHIP1/16W4V22UF20%X6SC08054V22UF20%X6SC0805X7R10%25V04020.1UFX7R25V040210%50NH/86ASMLFINDSMLFIND150NH10%X7R16V0402560PF50VEMPTY10%1%1/8WEMPTY1.50402LFSPCAP20%470UF2.5VSMLFSMLF2.5V470UF20%SPCAPSMLFEMPTY20%470UF2.5V4V22UF20%X6SC08054V22UF20%X6SC08051/16W05%CHIP0402LFC0805X6S22UF16V20%C0805X6S22UF16V20%22UF16V20%X6SC0805X6S10%1UF25VC04020402X7R10%0.22UF16VSMLFIND150NH0402LF05%CHIP1/16WEMPTY10%560PF50VC04021.50402LF1%1/8WEMPTY
X6S2.2UF10VC040210%0402LF2.21%CHIP1/16WX6S10%2.2UF10VC04021%1/16W0402LF8.87KEMPTY10%0.1UF25V040225V0402ICSMLF10VX6S10%C04022.2UF1%CHIP1/16WX6S10%2.2UF10VC04028.87K1%EMPTY1/16W25VIND_PVDDIO_P0_CPL2SW_PVDDIO_P0_SW1_RCIND_PVDDIO_P0_CPL2IND_PVDDIO_P0_CPL3SW_PVDDIO_P0_SW2_RC
SW_PVDDIO_P0_BOOTR1SW_PVDDIO_P0_SW2SW_PVDDIO_P0_BOOTR2SW_PVDDIO_P0_SW1NC_PVDDIO_P0_GL1_1NC_PVDDIO_P0_GL2_1PVDDIO_P0_VOS1NC_PVDDIO_P0_DNC1PVDDIO_P0_IMON1PVDDIO_P0_TEMP1PVDDCR_CPU1_P0_VCCSPVDDIO_P0_LSET1PVDDIO_P0_PWM1PVDDIO_P0_VCC1
NC_PVDDIO_P0_GL1_2NC_PVDDIO_P0_GL2_2PVDDIO_P0_VOS2PVDDIO_P0_TEMP1PVDDIO_P0_IMON2PVDDCR_CPU1_P0_VCCSPVDDIO_P0_PWM2X7RC04020.1UFISL99390FRZ-TR5935NC_PVDDIO_P0_DNC20402LF0.1UF0402X7R10%1%CHIP1/16W0402LFSW_PVDDIO_P0_BOOT2 SW_PVDDIO_P0_BOOT2_R5.61/16WCHIP1%0402LFSW_PVDDIO_P0_BOOT1_R5.60.22UFC080522UF
1
30
25_29
3
36
10_19
39
34
4
32
40
7_9-20_24
5
37
38
41
6
35
31
33
2
PU17
2
1
PC148_1
2
1
PC150_1
2
1
PC152_1
2
1
PC154_1
PR410
2
1
PC169_1
2
1
PC166_1
2
1
PC107
PC148
21
PL19
2
1
PC164
2
1 PC158_1
4
32
1
PL17
2
1 PC155
2
1 PC158
2
1
PR221
2
1
PC165
2
1
PC162
2
1
PC160
2
1
PC170_2
2
1
PC168_2
PR103
2
1
PC159_2
2
1
PC157_2
2
1
PC153_2
2
1
PC151_2
2
1 PC156
4
32
1
PL18
PR104
2
1 PC159
2
1
PR223
21
PR101
2
1 PC147_IOP0_1
2
1
PR100
2
1 PC143
2
1
PR98
2
1 PC145_7
2
1
PC149_2
PR102
1
30
25_29
3
36
10_19
39
34
4
32
40
7_9-20_24
5
37
38
41
6
35
31
33
2
PU182
1 PC144_IOP0_2
2
1
PR99
2
1 PC142
2
1
PR97
2
1 PC146_8
PC7000
PGND2
GL2
GL1
DNC
EN
PGND3
VOS
VIN2
PGND1
SW
LSET
IOUT
TOUT_FLT
PVCC
PHASE
VIN1
BOOT
AGND
VCC
REFIN
PWM
1 2
1 4
32
1 4
32
PGND2
GL2
GL1
DNC
EN
PGND3
VOS
VIN2
PGND1
SW
LSET
IOUT
TOUT_FLT
PVCC
PHASE
VIN1
BOOT
AGND
VCC
REFIN
PWM
2
1
2
1
SHEETDATE
DEPARTMENT
SIZE
PROJECT DOCUMENT NUMBER REV
REVIEWER
DESIGNER
123
7 3 2 1 6 5 4
E
A
B
C
E
D
C
B
A
7 6 5 4
D
OUT
IN
BI
OUT
BI
IN
BI
OUT
IN
OUT
IN
C



PVDDIO_P0_PHASE4HCME656510Q-221QLISAT:30A@100C6.5*6.5*10.0DCR=0.17M OHM2ND=CV+22Y0EZ01
DCR=2-3,0.27M OHM2ND=CV+15^0TZ01PGL6303.151HLT11.0*7.5*12.5DCR=1-4,0.105M OHMISAT:70A@100C2ND=CV+15^0TZ01DCR=2-3,0.27M OHMDCR=1-4,0.105M OHMPGL6303.151HLT11.0*7.5*12.5ISAT:70A@100C
PVDDIO_P0_PHASE3
Thu Sep 14 16:12:19 2023<NAME_2><NAME_1>MB FABCGT AMDV02206 OF 365
PVDDIO_P0PVDDIO_P0
SW_P12V_AUX_PVDDIO_P0_FLTSW_P12V_AUX_PVDDIO_P0_FLTPVDDCR_CPU1_P0_PVCCPVDDCR_CPU1_P0_PVCC205206
2002052062002002002012022032052062002002052062002002012022032052062065.6SW_PVDDIO_P0_BOOT3_RSW_PVDDIO_P0_BOOT3CHIP1/16W1%0402LF5.6SW_PVDDIO_P0_BOOT4_RSW_PVDDIO_P0_BOOT41/16W1%0402LFCHIP
C0402X6S10%25VSW_PVDDIO_P0_BOOTR3
PVDDIO_P0_VR PHASE 3&4SMLFICISL99390FRZ-TR59354V22UF20%X6SC08054V22UF20%X6SC08054V22UF20%X6SC080516V20%C0805X6S22UF150NHSMLFINDC0805X6S22UF16V20%16VX7R0.22UF0402C0805X6S22UF16V20%50VC0402560PF10%EMPTY1.51/8W1%4V22UF20%X6SC08055%0402LF0CHIP1/16WC0805X6S22UF16V20%C0805X6S22UF16V20%C0805X6S22UF16V20%X6S10%1UF25VC0402X7R10%0.22UF16V04020.22UH/33ASMLFINDIND150NHSMLF0402LF05%CHIP1/16W560PF50V10%C0402EMPTY1/8WEMPTY1%1.50402LF
1UFX7R10%0.1UF0402SMLFICISL99390FRZ-TR5935X6S10%2.2UF10VC04020402LF2.21%CHIP1/16WX6S10%2.2UF10VC04028.87K1%1/16WEMPTY0402LFX7R10%0.1UF25V0402X7R10%0.1UF25V0402X6S10%2.2UF10VC04020402LF2.21%CHIP1/16WX6S10%2.2UF10VC04020402LF8.87K1%EMPTY1/16WX7R10%25V04020.1UFSW_PVDDIO_P0_BOOTR4SW_PVDDIO_P0_SW4IND_PVDDIO_P0_CPL3SW_PVDDIO_P0_SW3_RCIND_PVDDIO_P0_CPL4IND_PVDDIO_P0_CPL0SW_PVDDIO_P0_SW4_RC
SW_PVDDIO_P0_SW3NC_PVDDIO_P0_GL2_3PVDDIO_P0_VOS3PVDDIO_P0_IMON3PVDDIO_P0_TEMP1NC_PVDDIO_P0_DNC3PVDDIO_P0_PWM3PVDDIO_P0_LSET3PVDDIO_P0_VCC3PVDDCR_CPU1_P0_VCCSPVDDIO_P0_VOS4NC_PVDDIO_P0_GL2_4NC_PVDDIO_P0_GL1_4PVDDIO_P0_IMON4PVDDIO_P0_PWM4NC_PVDDIO_P0_DNC4PVDDIO_P0_LSET4PVDDIO_P0_VCC4PVDDIO_P0_TEMP1PVDDCR_CPU1_P0_VCCS
25V0402LFNC_PVDDIO_P0_GL1_3EMPTYIND_PVDDIO_P0_CPL410%
1
30
25_29
3
36
10_19
39
34
4
32
40
7_9-20_24
5
37
38
41
6
35
31
33
2
PU20
2
1
PC190_3
2
1 PC187_3
4
32
1
PL21
2
1
PC184_3
2
1
PC181_3
2
1 PC166
2
1
PC189_4
PR111
2
1 PC188_4
2
1
PC185_4
2
1
PC180_4
4
32
1
PL20
PR112
2
1 PC163
2
1
PR291
2
1
PC179_3
2
1
PC177_3
PR110
1
30
25_29
3
36
10_19
39
34
4
32
40
7_9-20_24
5
37
38
41
6
35
31
33
2
PU19
2
1 PC174_IOP0_3
2
1 PC172
2
1
PR106
2
1 PC175_9
2
1
PC178_4
PR109
2
1 PC173_IOP0_4
2
1
PR107
2
1 PC171
2
1
PR105
2
1 PC176_10
2
1
PC192_3
2
1
PC191_4
2
1 PC186
2
1
PR379
2
1
PC182_4
2
1 PC183
2
1
PR108
PL16
2 1
PGND2
GL2
GL1
DNC
EN
PGND3
VOS
VIN2
PGND1
SW
LSET
IOUT
TOUT_FLT
PVCC
PHASE
VIN1
BOOT
AGND
VCC
REFIN
PWM
1 4
32
12
1 4
32
PGND2
GL2
GL1
DNC
EN
PGND3
VOS
VIN2
PGND1
SW
LSET
IOUT
TOUT_FLT
PVCC
PHASE
VIN1
BOOT
AGND
VCC
REFIN
PWM
SHEETDATE
DEPARTMENT
SIZE
PROJECT DOCUMENT NUMBER REV
REVIEWER
DESIGNER
123
7 3 2 1 6 5 4
E
A
B
C
E
D
C
B
A
7 6 5 4
D
OUT
IN
BI
OUT
BI
BI
IN
OUT
IN
OUT
IN
C



MAIN SOURCE:RENESAS BOMBOM NOTETRACE SPACING = 5MILPMBUS ADDRESS AND CONFIG/21.5K0X49CONFIG/R/4.64K0/3.09K0X49MPSADDRESS(7-BIT)0X63
IRM REV1.09EFFICIENCY > 90% @TDCWORK FREQUENCY=600KHZMAX LOAD RELEASE=35AMAX LOAD STEP=25ADC & AC=1.045-1.155VOUTPUT VOLTAGE=1.1VOCP=96A (EDC*1.2)PVDD11_S3_P0 SPECFICATIONPU21 = TBD/RAA229621GNP#HA0PR3 = CS21002FB06PR113 = CS25362FB02PC198 = CH11006JB00PC199 = CH5103KEB013RD SOURCE:MPS BOMPR126 = CS22672FB03PR419,PR36,PR412 = EMPTYPR121 = CS01002FB07PC194 = CH12206KB14PC193 = CH3104J1B00DIFFERENTIAL PAIREDC=80ATDC=65A
RENESASINFINEON
TRACE WIDTH = 10MILPU21 = TBD/XDPE19283BPR37,PR33,PR34,PR35 = EMPTYPC199=CH5103KEB01PC5 = CH21006JB10PC198 = CH31004KB17PR601 = CS24992FB07PR125 = CS37502FB05PR126 = CS33402FB06PC194,PR113,PC193 = EMPTYPR37,PR33,PR34,PR35,PR419,PR36 = EMPTYPR3 = CS00002JB13PU21 = TBD/MP2856GUT-0021-Z2ND SOURCE:INFENEON BOM
VR Thu Sep 14 16:12:19 2023<NAME_2><NAME_1>MB FABCGT AMDV02207 OF 365P12V_AUX05%1/16WEMPTYCHIP0402LFVSENSE_VSS_SENSE_C_P0PVDD11_S3_P0_PWM2208NC_PVDD11_S3_P0_PWM33300PFP3V3_AUXPVDD18_S5_P0
P3V3_AUX
PVDD18_S5_P0
P3V3_AUX
P5V_AUX
PVDD11_S3_P0
PVDD11_S3_P0 VR CONTROLLER0.1UF1/16W1%1/16W3.09KPVDD11_S3_P0_ADDR_CFGNC_PVDD11_S3_P0_IMON5NC_PVDD11_S3_P0_PWM50402LFNC_PVDD11_S3_P0_IMON8NC_PVDD11_S3_P0_PWM8PVDD11_S3_P0_TEMP1PVDD11_S3_P0_OCP_N_RNC_PVDD11_S3_P0_IMON6NC_PVDD11_S3_P0_PWM6PVDD11_S3_P0_PWM1NC_PVDD11_S3_P0_IMON7PVDD11_S3_P0_VDDIOPVDD11_S3_P0_VINSENPVDD11_S3_P0_VMON
PWRGD_PVDD11_S3_P0_R
NC_PVDD11_S3_P0_PWM7VSENSE_PVDD11_S3_P0_RNC_PVDD11_S3_P0_PWM4PVDD11_S3_P0_PMSDA_RPVDD11_S3_P0_EN_RPVDD11_S3_P0_PMALERT_R
NC_PVDD11_S3_P0_PG1NC_PVDD11_S3_P0_IMON4NC_PVDD11_S3_P0_IMON3PVDD11_S3_P0_RESET_N_R
NC_PVDD11_S3_P0_SVTOPVDD11_S3_P0_IMON2PVDD11_S3_P0_PMSCL_RPVDD11_S3_P0_IMON1ICRAA229621GNP#HA0SMLF
PVDD11_S3_P0_OCP_N40.2KCHIP
1/16W5%0402LF5%05%1/16WPVDD11_S3_P0_ENPVDD11_S3_P0_PMALERTSMB_SCM_2_R6_SDASMB_SCM_2_R6_SCL1/16W0402LF5%0402LF0 1/16W
PVDD11_S3_P0_TEMP0
04021000PF50VEMPTY04020402LFCHIP
EMPTY01K1/16W0402LF0402LF1/16W5%
5%CHIPPVDD11_S3_P0_VCCS0PWRGD_PVDD11_S3_P01/16WX7R
1/16W0
5%CHIP0402LF1%1C0402X6S10%1UF16VC04026.3V10UFX6S0402X7R10%0.1UF25VX7R10%0.1UF25V04020402LF05%CHIP 1/16W0402LF1%EMPTY 1/16W0402LF5%1/16W05%CHIP 1/16W0402LF05%CHIP 1/16W05%CHIP 1/16W 0402LF0402LF05%CHIP 1/16W0402LF05%EMPTY1/16W0402LF5%CHIP0402LF05%CHIP 1/16WX7R10%470PF50V0402
50VCHIP00402LFCHIP1%1KCHIP1%0402LFCHIP040250V10%1/16W0402LFEMPTY1%CHIP0402LFX7R10%0.1UF25V04020402LF4.99K1%EMPTY1/16W0402LFCHIP
1%49.91/16W00402LF10KCHIP0402X7R10%0402LF1%1/16W
PVDD11_S3_P0_VCC
PVDD11_S3_P0_RESET_NVSENSE_PVDD11_S3_P0_DP1000PF01K1%X7R49.91000PFX7R1/16W0402LF1/16W5%04021/16W0402LF5%5%50VCHIP331/16W5%0EMPTY
CHIP20820820882
8282 83151151
208
20881
812720027 20%
25V
21
PR130
2
1 PC199
2
1 PC4
21
PR37
21
PR33
21
PR34
21
PR35
21
PR419
2
1
PR127
21
PR36
21
PR412
2
1 PC198
21
C197
21
R122
21 R123
21
R118
21
R119
21
R120
21
R117
2
1
PR114
2
1 PC194
21
PR121
2
1
R124
32
21
37
38
15
40
39
TH
35
36
19
20
17
18
31
22
14
8
7
6
5
4
3
2
1
9
10
16
12
33
11
34
13
23
24
25
26
27
28
29
30
PU21
2
1 PR126
2
1 PC5PR601
21
PR125
2
1
PR115
21
R8458
2
1
PR3
2
1 PC193
21
PR113
2
1 PC200
2
1 PC9
21
PR128
21
PR129
21
C196
21
R8116
C5009
CS0
PWM0
TEMP1
EN1||ADDR_CFG
TH_GND
OCP_L
CS2
PWM2
CS3
PWM3
PWM7
CS1
RGND1
VSEN1
VDDIO
TEMP0
VINSEN
VMON||IINSEN
VCCS
PWM6
PG0
PWM1
VSEN0
PWM5
PWM4
PMSDA
RGND0
EN0
nPMALERT
SVD
PG1
CS4
CS5
RESET_L
SVTO
CS6
SVC
PMSCL
SVTI
VCC
CS7
2
1
SHEETDATE
DEPARTMENT
SIZE
PROJECT DOCUMENT NUMBER REV
REVIEWER
DESIGNER
123
7 3 2 1 6 5 4
E
A
B
C
E
D
C
B
A
7 6 5 4
D
OUT
OUT
IN
IN
OUT
IN
IN
OUT
OUT
OUT
OUT
OUT
IN
IN
IN
C



IRIPPLE:5.08A2ND=CH747LM8822ISAT:13A@100C4.5*4.7*4.5DCR:0.105M OHM2ND=CV+10G0MZ04
DCR=0.103M OHM10.0*7.7*12.0ISAT:132A@100CPG2323.900HLT3RD=CVA90^0KZ082ND=CVA90^0KZ04ESR=9M OHM7.3*4.3*1.92ND=CC7390JMZ115.0*5.8ESR=10M OHMPR137,PR138 = EMPTYPU22,PU23 = AL099390004/ISL99390FRZ-TR5935PC201_1,PC202_2 = EMPTYPR411,PR137,PR138 = EMPTYBOM NOTE
ESR=10M OHM3RD=CV+10G0MZ08PG2289.101HLT6.3*82ND=CC72703MD39PVDD11_S3_P0_PHASE2PU22,PU23 = AL021590000/TDA21590PC201_1,PC202_2 = EMPTY3RD SOURCE:MPS BOMPR413,PR135,PR136=CS00002JB13PR133,PR134,PR135,PR136 = CS00002JB132ND SOURCE:INFENEON BOMMAIN SOURCE:RENESAS BOMPU22,PU23 = AL087000A03/MP87000GMJTH-C11D-Z
3RD=CVA90^0KZ082ND=CVA90^0KZ04DCR=0.103M OHM10.0*7.7*12.0ISAT:132A@100CPG2323.900HLTPVDD11_S3_P0_PHASE1
Thu Sep 14 16:12:20 2023<NAME_2><NAME_1>MB FABCGT AMDV02208 OF 365
PVDD11_S3_P0_PVCCPVDD11_S3_P0_IMON1SMLFISL99390FRZ-TR5935IC5.6X7RSW_P12V_AUX_PVDD11_S3_P0_FLTP12V_AUXP5V_AUX P3V3_AUX PVDD11_S3_P0_PVCCPVDD11_S3_P0PVDD11_S3_P0PVDD11_S3_P0PVDD11_S3_P0SW_P12V_AUX_PVDD11_S3_P0_FLT
PVDD11_S3_P0 VR PHASE 1&21/16WPVDD11_S3_P0_VCCSNC_PVDD11_S3_P0_GL1_1SW_PVDD11_S3_P0_SW1SW_PVDD11_S3_P0_PH1
207208207208207207207208207207207208SMLF100NH/16A22UF 270UFINDC080520%22UF16V20%C0805X6S0402040220%22UFX6S0.1UF
X6S0402X6S20%560PF22UF22UF25VX7R25V0.1UFEMPTYC080550V10%SW_PVDD11_S3_P0_SW1_RC16V0CHIPPVDD11_S3_P0_PWM2NC_PVDD11_S3_P0_DNC2PVDD11_S3_P0_LSET2PVDD11_S3_P0_TEMP0PVDD11_S3_P0_IMON2PVDD11_S3_P0_VCC2PVDD11_S3_P0_PWM1PVDD11_S3_P0_TEMP0NC_PVDD11_S3_P0_GL2_2NC_PVDD11_S3_P0_GL1_2SW_PVDD11_S3_P0_SW2SW_PVDD11_S3_P0_SW2_RC
PVDD11_S3_P0_VCCSPVDD11_S3_P0_VCC1NC_PVDD11_S3_P0_DNC1PVDD11_S3_P0_LSET1PVDD11_S3_P0_VOS2SW_PVDD11_S3_P0_PH2X7R10%0.1UF25V0402X6S10%2.2UF10VC04024.87K1%EMPTY0402LFIC0402LF2.2CHIP1/16W1%X6S10%2.2UF10VC04021/8W1%1.50402LFEMPTY560PFC0402EMPTY10%50VC0402 C0805EMPTY1%1.51/8WX7R10%0.1UF25V0402X6S10%10VC04022.2UF1/16WEMPTY1%4.87K0402LF0402LF2.21%CHIP1/16WX6S10%2.2UF10VC0402X6SC0402C0402C080520%X7R10%0.22UF16V040290NH/155ASMLFIND1/16W5%SPCAP20%2.5VSMLFSPCAP470UFSMLF20%2.5V4V22UF20%X6SC0805390UF20%SMLF2.5VALUMSMLF390UF20%ALUM2.5V 2.5V390UF20%ALUMSMLF SMLF2.5V390UF20%ALUM0.22UF040290NH/155AIND25VX7R10%0.1UF04020.1UFX7R10%25V4V22UF20%X6SC08054V22UF20%X6SC08050402LF1K1%CHIP1/16W0402LF05%CHIP1/16W0402LF5%EMPTY1/16W0
SMLF2.5V470UF20%SPCAP4V22UF20%X6SC080505%CHIP1/16W0402LF
X7R10%25V10%25V0402LF10%1UFC0805PVDD11_S3_P0_VOS1NC_PVDD11_S3_P0_GL2_11UF10% 10%16V 16V22UF470UF16V20%C0805 C080522UFX6S20%0402LFSMLF16V20%16V22UFX6SX6SX6SCHIP1/16W0402LF1%SW_PVDD11_S3_P0_BOOT2 SW_PVDD11_S3_P0_BOOT2_RC5.61/16W1%0402LFSW_PVDD11_S3_P0_BOOT1_RCSW_PVDD11_S3_P0_BOOT1CHIPISL99390FRZ-TR5935SMLF20%THLF16VOSCON16VX6S20%C080522UFX6SC080522UFX6S20%22UFC0805X6S20%16V16V16V16V
PC8005
PC8004
1
30
25_29
3
36
10_19
39
34
4
32
40
7_9-20_24
5
37
38
41
6
35
31
33
2
PU22
21
PR138
2
1 PC221_2
2
1 PC800
2
1 PC219_1
2
1 PC215_1
PR413PR411
PR414
2
1 PC227_1
21
PL24
2
1 PC222
2
1 PC220
21
PL232
1
PC217
2
1 PC228
2
1 PC225_2
2
1 PC226
2
1 PC223
21
PR137
2
1 PC218_2
2
1
PC218
2
1 PC216_2
2
1 PC213_1
2
1 PC207_1
21
PR135
2
1 PC169
2
1 PC205_11P0_1
2
1
PR131
2
1 PC203
2
1
PR482
2
1 PC214_2
2
1 PC212_2
2
1 PC206_11P0_2
2
1
PR132
1
30
25_29
3
36
10_19
39
34
4
32
40
7_9-20_24
5
37
38
41
6
35
31
33
2
PU23
21
PR134
2
1 PC204
2
1 PC202_2
2
1 PC224_1
PC6003
2
1 PC801
2
1 PC230
2
1 PC229
21
PL22
2
1 PC211_1
2
1 PC209_1
21
PR133
2
1 PC201_1
2
1 PC208_2
2
1 PC210_2
2
1 PC168
21
PR136
2
1
PR389
PGND2
GL2
GL1
DNC
EN
PGND3
VOS
VIN2
PGND1
SW
LSET
IOUT
TOUT_FLT
PVCC
PHASE
VIN1
BOOT
AGND
VCC
REFIN
PWM
1 2
1 2
1 2
PGND2
GL2
GL1
DNC
EN
PGND3
VOS
VIN2
PGND1
SW
LSET
IOUT
TOUT_FLT
PVCC
PHASE
VIN1
BOOT
AGND
VCC
REFIN
PWM
2
1PC7002
2
1
2
1
2
1
SHEETDATE
DEPARTMENT
SIZE
PROJECT DOCUMENT NUMBER REV
REVIEWER
DESIGNER
123
7 3 2 1 6 5 4
E
A
B
C
E
D
C
B
A
7 6 5 4
D
OUT
IN
OUT
IN
OUT
IN
OUT
IN
C



2ND=CV-10I0MZ00PCMC104T-1R0MNISAT:25A@100CDCR=3.3M OHM10*10*4IRATED=5A@125C2ND=CX220Z06Z003RD=CX000220000
2ND NABOM CHANGE R&C TABLEPC259 CHANGE TO CH13306JB143RD PC212 CHANGE TO CH5222KEB011ST AL008633005/MPQ8633BGLE-C838-Z/MPS2ND AL053319002/RS53319LR/REEDSEMI3RD AL000548007/TPS548B28RWWR/TIBOM NOTE1ST
DCR=5M OHMNEAR CPU SIDERATRACE SPACING = 5MIL
PVDD18_S5_P0 SPECFICATIONTDC=10ADC =1.76-1.84V
ESR=10M OHM2ND=CC7390JMZ115.0*5.8TRACE WIDTH = 10MILDIFFERENTIAL PAIRVOUT=0.6(1+RA/RB)=1.8VFCCMRB
OCP=15A (EDC*1.2)OUTPUT VOLTAGE=1.8VEDC=12AAC =+/-30MVMAX LOAD RELEASE=2.5AIRM REV1.09WORK FREQUENCY=600KHZMAX LOAD STEP=2.5APVDD18_S5_P0EFFICIENCY > 85% @TDCFSW=600KHZThu Sep 14 16:12:41 2023<NAME_2><NAME_1>MB FABCGT AMDV02209 OF 365
C080520%22UFP3V3_AUXP12V_AUXP3V3_AUXPVDD18_S5_P027812781 3310%25V1UFC0402X6S10%16V0.22UFX7R040225V0.1UF040210%EMPTYX6S1UFC040225V10%5%X7R50V1.0UH/18ASMLFPWRGD_PVDD18_S5_P0CHIP0402LF2.21000PFINDCHIPSW_PVDD18_S5_P0_BST_RSW_PVDD18_S5_P0_BST1%0402LFSW_PVDD18_S5_P0_SW25V0.1UFPVDD18_S5_P0_RGNDPVDD18_S5_P0_FBX6S20%22UF16V 16V20% 20%C0805SW_P12V_AUX_PVDD18_S5_P0_FLT20%16V
PVDD18_S5_P0
22UFC080520%4V0402LF1K1%CHIP1/16WX7R10%0.1UF25V0402SMLF2.5V390UF20%ALUM4V22UF20%EMPTYC0805CHIP1/16W1%49.90402LFEMPTYC080520%4V22UFC08054V22UF4V22UF20%C0805X6S20KCHIPC040210%EMPTY0402X7R220PF 50V10%1/16WCHIP0402LF49.91%5%10K1/16W0402LF1/16W1%CHIP10KX7R10%040210%25V0402X7RSMLF0402LF8.66K1%CHIP1/16W05%CHIP 1/16W0402LF0402LF05%CHIP1/16WINDX6S25V0.1UF10%C0402PVDD18_S5_P0_FB_RCVSENSE_PVDD18_S5_P0_DNPVDD18_S5_P0_MODEPVDD18_S5_P0_CS0402FM_PWRGD_PVDD18_S5_P020%X6SX6SCHIPVSENSE_PVDD18_S5_P0_DP5%0402LFPVDD18_S5_P0_REF0.022UF25V00.01UF 1/16W0402LFCHIP1%101/16W0402LFPVDD18_S5_P0_VCCMPQ8633BGLE-C838-ZICSMLFBLM18SN220TN1D/8000MAPVDD18_S5_P0_EN16V22UFX6SC0805X6SC0805X6SC080522UF16VX6S22UF
PC8002
2
1 PC285
21 R177
2
1
PR439
2
1 PC215
2
1 PC115
2
1 PC261
21
PR438
2
1 PC260
2
1 PC288
2
1 PC114
21
PR434
PR435
21
PL78
21
PR471
PC6005
21
PC259
PR418
2
1
R8465
2
1 PC237
2
1 PC81
2
1 PC254
2
1 PC227
2
1
PC209
2
1
PR470
PC113
2
1 PC258
21
10
19
5
20
6
9
11_18
4
7
8
3
1
2
PU57
2
1
PR448
21
PR417
2
1
PR477
2
1
PC212
2
1 PC111
21
PL77
PC6001
2
1C674
212121
PR8001
C5001
1 2
1 2
VIN2
CS
MODE
TRK_REF
SW
RGND
VCC
AGND
FB
BST
EN
PGND
PGOODVIN1
21
2
1
2
1
2
1
2
1
SHEETDATE
DEPARTMENT
SIZE
PROJECT DOCUMENT NUMBER REV
REVIEWER
DESIGNER
123
7 3 2 1 6 5 4
E
A
B
C
E
D
C
B
A
7 6 5 4
D
OUT
IN
IN
IN
C



IRM REV1.09SVI3 ADDRESS=PORT0 (0X2)EFFICIENCY > 90% @TDCWORK FREQUENCY=600KHZMAX LOAD RELEASE=95AMAX LOAD STEP=45AOCP=156A (EDC*1.2)PVDDCR_SOC_P1 SPECFICATIONDEFAULT POWER-ON VID=0.9VIRM REV1.09SVI3 ADDRESS=PORT0 (0X1)EFFICIENCY > 90% @TDCWORK FREQUENCY=600KHZVID=0.75-1.2VMAX LOAD RELEASE=200ALOAD-LINE=0.4MOHM2ND SOURCE:INFENEON BOMPR159 = CS21472FB02PR530,PR436,PR437 = EMPTYPR4 = CS21002FB06PR157 = CS25362FB02PU25 = TBD/XDPE192C3BRENESASINFINEON/52.3K
OCP=276A (EDC*1.2)EDC=230ATDC=175AMAX LOAD STEP=200ATRACE WIDTH = 10MILDIFFERENTIAL PAIRPVDDCR_CPU0_P1 SPECFICATIONDC=+/-20MVVID=0.55-1.5VDEFAULT POWER-ON VID=0.9VMAX AC=VID+200MVMIN AC=VID-EDC*LL-110MVMIN AC=VID-150MVMAX AC=VID+150MVTDC=105AEDC=130ADC=+/-20MVTRACE SPACING = 5MILVRMPSTRACE SPACING = 5MIL0/5.23K/1.47KPC243 = CH3104J1B00PC251 = CH5103KEB01PR173,PR174 = CS01002FB073RD SOURCE:MPS BOMPC6 = CH21006JB10PR4 = CS00002JB13PC251=CH5103KEB01PC250,PC253 = CH31004KB17PR602 = CS24992FB07PR181 = CS37502FB05PR159 = CS35232FB02PR530,PR436,PR437=EMPTYPC244,PC245,PR157,PC243 = EMPTYPU25 = TBD/MP2857GQKT-001C-ZPC244,PC245 = CH12206KB14PC253,PC250 = CH11006JB00TRACE WIDTH = 10MILDIFFERENTIAL PAIRPU25 = TBD/RAA229620GNP#HA0MAIN SOURCE:RENESAS BOMBOM NOTE0X4D0X4D0X72ADDRESS(7-BIT) CONFIG/RPMBUS ADDRESS AND CONFIGThu Sep 14 16:12:20 2023<NAME_2><NAME_1>MB FABCGT AMDV02210 OF 365
1/16WPVDDCR_CPU0_P1_IMON6212PVDDCR_CPU0_P1_IMON4VSENSE_VSS_SENSE_A_P1I16PVDD18_S5_P1
PVDD18_S5_P1
P12V_AUXP3V3_AUX
P3V3_AUX
P3V3_AUXPVDD18_S5_P1PVDDCR_SOC_P1P5V_AUX
PVDDCR_CPU0_P1P3V3_AUX1K0402LF
49.91%0402LF1/16WPVDDCR_CPU0_P1_RESET_NCHIPPVDDCR_CPU0_P1/PVDDCR_SOC_P1 VR CONTROLLERX7R5%PVDDCR_SOC_P1_EN_GD
PVDDCR_CPU0_P1_VCC16V1/16W
0402LF5%0402CHIPPVDDCR_CPU0_P1_PMALERTSMB_VR_3V3STBY_SDACHIP1/16W
50V10%PVDDCR_CPU0_P1_TEMP0
5%1000PF50V1000PF
VSENSE_VSS_SENSE_A_P1
50V
0402LF1/16W05%1K0402LF1%1UFCHIPCHIPPWRGD_PVDDCR_SOC_P1_R0402LF5%0402LF0402
0402LFEMPTYVSENSE_PVDDCR_SOC_P1_DPPVDDCR_CPU0_P1_OCP_N_R
PVDDCR_CPU0_P1_VCCSEMPTY1K1%1K
1/16WCHIP1/16WCHIP1%1K0402LFIC0.1UF25V10%04021%49.91%CHIP0402LF49.9CHIP 1/16W1K1/16WCHIP49.9
1/16W5%00402LF1/16WEMPTY1%4.99K0402LF 040225V0.1UF10%X7R50V1000PF1/16WCHIP10%3300PF50VX7R0402040210%3300PF50VX7R50V5%10PF040250V5%10PF040250V5%EMPTY10PF1%1K1K1%0402LF1KCHIP1%0402LF1/16W1/16W1%04025%0402
0402470PFX7R040250V470PF10%X7R1/16WCHIP5%01/16WCHIP001/16WCHIP25V0.1UF10%X7R0.1UF040225V10%X7RX6S20%10UF6.3VC0402X6SC04021UF10%CHIP1%10402LF
10%X7R6.3V0402
1%01/16W1%0402LF1/16WEMPTY EMPTY1/16WEMPTY
0402LFPVDDCR_CPU0_P1_OCP_NCHIP1/16WBSS138K0402LF1/16WEMPTY1%1/16W0402LF
0402EMPTY
CHIP1/16W1%10K5%04021000PF1%1000PF
X7R5%50V49.90402X7R5% 50V1000PF5%1/16W5%004020402LF1/16WCHIP0402LF0402LF1%1/16WCHIP 0402LF0CHIP1/16W5%0VSENSE_PVDDCR_CPU0_P1_DP5%1%0402LF1%040250V33CHIP1/16W0402LFPWRGD_PVDDCR_SOC_P1
5%0402LF5%33CHIPCHIP330SMB_VR_3V3STBY_SCL
10K5%0CHIPPVDDCR_SOC_P1_EN1K5.23K1%1/16WCHIP0402LFX7R
1000PF5%CHIPX7R0402LF40.2K5%EMPTY0402LF1/16WICPVDDCR_SOC_P1_EN_RC50VPJA3415AE0402LF0402LF
CHIP5%1/16W0402LF5%1/16W0402LF5%1/16W0402LF0SVID_PVDDCR_CPU0_P1_SVTICHIP0EMPTYX7R0SVID_PVDDCR_CPU0_P1_SVC_RCHIP1/16W0402LF0402LF0402LFCHIPPVDDCR_CPU0_P1_ENPWRGD_PVDDCR_CPU0_P11/16W0402LF5%SVID_PVDDCR_CPU0_P1_SVD_R0402LF5%CHIP1/16W01/16W0402LF1/16WCHIPSVID_PVDDCR_CPU0_P1_SVTO49.91%RAA229620GNP#HA0SMLFICPVDDCR_CPU0_P1_IMON1SVID_PVDDCR_CPU0_P1_SVTI_RPVDDCR_CPU0_P1_PMSCL_RSVID_PVDDCR_CPU0_P1_SVC_R1SVID_PVDDCR_CPU0_P1_SVTO_R
PVDDCR_CPU0_P1_RESET_N_RNC_PVDDCR_CPU0_P1_IMON7NC_PVDDCR_CPU0_P1_IMON8SVID_PVDDCR_CPU0_P1_SVD_R1PVDDCR_CPU0_P1_PMALERT_RPVDDCR_CPU0_P1_EN_RPVDDCR_CPU0_P1_PMSDA_RNC_PVDDCR_CPU0_P1_PWM8NC_PVDDCR_CPU0_P1_PWM7VSENSE_PVDDCR_CPU0_P1_VSEN0PVDDCR_SOC_P1_PWM2
PWRGD_PVDDCR_CPU0_P1_RPVDDCR_CPU0_P1_PWM6PVDDCR_CPU0_P1_VMONPVDDCR_CPU0_P1_VINSENVSENSE_PVDDCR_SOC_P1_VSEN1PVDDCR_SOC_P1_IMON2
PVDDCR_CPU0_P1_PWM1NC_PVDDCR_CPU0_P1_PWM9NC_PVDDCR_CPU0_P1_IMON9PVDDCR_SOC_P1_PWM3PVDDCR_SOC_P1_IMON3PVDDCR_SOC_P1_EN//ADDR_CFGPVDDCR_SOC_P1_TEMP1PVDDCR_SOC_P1_PWM1PVDDCR_SOC_P1_IMON1PVDDCR_CPU0_P1_PWM5PVDDCR_CPU0_P1_IMON5PVDDCR_CPU0_P1_PWM4PVDDCR_CPU0_P1_PWM3PVDDCR_CPU0_P1_IMON3PVDDCR_CPU0_P1_PWM27882 83151
2132122112105454 216215213
8254
80
151
80210545481815454 211213215213215
2112162162162152152152132132122122122111/16WEMPTYPVDDCR_CPU0_P1_IMON2211212211
R6087
PR8010
PR8009
21C5003
21C5019
40
25
45
46
19
48
47
TH
43
44
23
24
21
22
39
26
18
12
11
10
9
8
7
6
5
4
3
2
1
13
14
20
16
41
15
42
17
27
28
29
30
31
32
33
34
35
36
37
38
PU25
21
PC247
21
PR183
2
1 PC252
2
1 PC251
2
1 PC10
21
PR530
21
PR436
PR437
2
1 PC253
2
1 PC250
21
R8178
21 R8179
21
R8171
21
R8176
21
R8177
21
R8167
2
1
PR161
2
1
R8160
2
1 C297
2
1 C296
2
1 PC244
21
PR173
21
R8180
21
C8246
2
1 PC6PR602
2
1
PR162
21R8184
2
1
PR163
21
R8165
21
R8166
2
1 PC243
2
1
PR4
G
PQ11
2
1 PR152
G
PQ15
21
PR157
2
1
PR151
2
1
R8153
21
R149
2
1 PC11
21
C248
21
C249
21
PR172
21
R175
2
1
R8156
2
1
R154
2
1 C295
2
1 PC245
21
PR174
21
PR181
21
R8168
21
R8182
2
1
PR164
2
1 C242
2
1
PR150
SDS D
PR159
C5012
S
G
D
G
CS10
PWM10
CS9
PWM9
CS8
PWM8
CS7
PWM7
CS0
PWM0
TEMP1
EN1||ADDR_CFG
TH_GND
OCP_L
CS2
PWM2
CS3
PWM3
PWM11
CS1
RGND1
VSEN1
VDDIO
TEMP0
VINSEN
VMON||IINSEN
VCCS
PWM6
PG0
PWM1
VSEN0
PWM5
PWM4
PMSDA
RGND0
EN0
nPMALERT
SVD
PG1
CS4
CS5
RESET_L
SVTO
CS6
SVC
PMSCL
SVTI
VCC
CS11
SD
21
21
2
1
2
1
2
1
SHEETDATE
DEPARTMENT
SIZE
PROJECT DOCUMENT NUMBER REV
REVIEWER
DESIGNER
123
7 3 2 1 6 5 4
E
A
B
C
E
D
C
B
A
7 6 5 4
D
OUT
IN
IN
OUT
IN
IN
IN
IN
IN
OUT
IN
OUT
BI
OUT
OUT
IN
IN
IN
IN
IN
OUT
OUT
OUT
IN
OUT
IN
IN
OUT
OUT
IN
IN
OUT
OUT
IN
OUT
IN
IN
C



BOM NOTE
ESR=10M OHMIRIPPLE:5.08A2ND=CC72703MD39PGL6303.151HLTISAT:70A@100CDCR=1-4,0.105M OHMDCR=2-3,0.27M OHM6.0*6.1*7.0ISAT:70A@100C
ISAT:70A@100C2ND=CV+15^0TZ0111.0*7.5*12.5PGL6303.151HLTMAIN=CH122KM88017.3*4.3*1.9ESR=9M OHMDCR=2-3,0.27M OHMDCR=1-4,0.105M OHM
6.3*811.0*7.5*12.52ND=CV+15^0TZ013RD=CVA50^0MZ082ND=CVA50^0MZ07DCR=0.09M OHMPG2292.500HLTPVDDCR_CPU0_P1_PHASE1PVDDCR_CPU0_P1_PHASE2
PR335,PR191,PR192,PR199,PR200,PR204,PR425=EMPTYPC254_1,PC255_2,PC284_3,PC285_4,PC306_5,PC124_6=EMPTYPR191,PR192,PR199,PR200,PR204,PR425 = EMPTYPC254_1,PC255_2,PC284_3,PC285_4,PC306_5,PC124_6 = EMPTY3RD SOURCE:MPS BOMPR336,PR189,PR190,PR197,PR198,PR203,PR424=CS00002JB13PU4,PU26,PU27,PU28,PU29,PU24 = AL087000A03/MP87000GMJTH-C11D-Z2ND SOURCE:INFENEON BOMPR187,PR188,PR195,PR196,PR202,PR423 = CS00002JB13PR189,PR190,PR197,PR198,PR203,PR424 = CS00002JB13PU4,PU26,PU27,PU28,PU29,PU24 = AL021590000/TDA21590PU4,PU26,PU27,PU28,PU29,PU24 = AL099390004/ISL99390FRZ-TR5935MAIN SOURCE:RENESAS BOMThu Sep 14 16:12:20 2023<NAME_2><NAME_1>MB FABCGT AMDV02211 OF 365215 213SW_P12V_AUX_PVDDCR_CPU0_P1_FLTSW_P12V_AUX_PVDDCR_CPU0_P1_FLTPVDDCR_CPU0_P1P12V_AUXPVDDCR_CPU0_P1PVDDCR_CPU0_P1
PVDDCR_CPU0_P1_PVCCP3V3_AUXPVDDCR_CPU0_P1_PVCCP5V_AUX
PVDDCR_CPU0_P1 VR PHASE 1&2210211
21021121221121321021121221321521621021121221321021021221321021021121221625VC0402CHIP5.6CHIPSW_PVDDCR_CPU0_P1_BOOT15.6SW_PVDDCR_CPU0_P1_BOOT2_RCSW_PVDDCR_CPU0_P1_BOOT20402LF1%1/16WSW_PVDDCR_CPU0_P1_BOOT1_RC1/16W0402LF1%C04020.1UFISL99390FRZ-TR5935ICIND150NH0402X7R10%SMLFISL99390FRZ-TR5935IC 040225V0.1UF10%X7RSMLFSPCAP220UF20%4V0402LF8.87K1%EMPTY 1/16W1/16WCHIP1%1K0402LFC08054V22UFX6S20%20%C0805X6S22UF4V10%X7R0.1UF25VSMLFIND50NH/86AOSCON16VTHLF20%270UF270UF20%THLF16VOSCONSPCAPSMLF4V20%220UFC0805X6S20%22UF4VC0805X6S20%22UF4V20%220UFSMLFSPCAP4VSPCAPSMLF4V20%220UF20%SMLFSPCAP4V220UF150NHINDSMLF16V10%X7R04020.22UF
16V20%X6S20%16V22UFX6SC080520%16V22UFX6S560PF50VEMPTY10%C0402X6S25VC040210%1UF25V10%0.1UF0402C040210V2.2UFX6S10%1/16WCHIP1%2.20402LF1/16WEMPTY0402LF05%8.87KEMPTY 1/16W1%0402LFC040210V2.2UF10%X6S0402LFCHIP5%01/16W1.51%1/8W0402LFEMPTY20%22UFX6S16V20%C0805X6S16V22UF16V22UFC0805X6S20%25V1UF10%X6S10%X7R0402C040250V560PF10%EMPTY1/16WCHIP5%00402LF0402LF1.51%EMPTY1/8W040225V0.1UF10%X7R10%C040210V2.2UFX6S1/16WCHIP1%0402LF10V2.2UF10%X6S0.1UF040225V10%X7R
1/16W00402LF5%CHIP
SW_PVDDCR_CPU0_P1_SW2SW_PVDDCR_CPU0_P1_SW1SW_PVDDCR_CPU0_P1_PH2PVDDCR_CPU0_P1_IMON1SW_PVDDCR_CPU0_P1_PH1PVDDCR_CPU0_P1_VCC2IND_CPU0_P1_CPL1IND_CPU0_P1_CPL2IND_CPU0_P1_CPL1IND_CPU0_P1_CPL5NC_PVDDCR_CPU0_P1_GL1_1NC_PVDDCR_CPU0_P1_GL2_1PVDDCR_CPU0_P1_LSET1PVDDCR_CPU0_P1_VCCSPVDDCR_CPU0_P1_VOS2NC_PVDDCR_CPU0_P1_GL2_2NC_PVDDCR_CPU0_P1_GL1_2PVDDCR_CPU0_P1_PWM1PVDDCR_CPU0_P1_TEMP0NC_PVDDCR_CPU0_P1_DNC2PVDDCR_CPU0_P1_LSET2PVDDCR_CPU0_P1_IMON2PVDDCR_CPU0_P1_TEMP0PVDDCR_CPU0_P1_PWM2PVDDCR_CPU0_P1_VCCSSMLF2.222UFPVDDCR_CPU0_P1_VOS10402PVDDCR_CPU0_P1_VCC1C0805SW_PVDDCR_CPU0_P1_SW2_RCNC_PVDDCR_CPU0_P1_DNC1SW_PVDDCR_CPU0_P1_SW1_RCC0805C0805SMLF16V0.22UFX7R
1
30
25_29
3
36
10_19
39
34
4
32
40
7_9-20_24
5
37
38
41
6
35
31
33
2
PU26
4
32
1
PL282
1
PC270
1
30
25_29
3
36
10_19
39
34
4
32
40
7_9-20_24
5
37
38
41
6
35
31
33
2
PU4
2
1 PC278
2
1 PC105
21
PR190
21
PR188
PR337
2
1 PC283_1
2
1 PC281_1
PC6004
21
PL30
2
1 PC272
2
1 PC280_2
2
1 PC277
2
1 PC276
2
1 PC275
4
32
1
PL292
1
PC271
2
1 PC268_1
2
1 PC266_1
2
1 PC264_1
21
PR189
2
1 PC262_1
2
1 PC258_C0P1_1
2
1
PR185
PR336
21
PR187
2
1 PC256
2
1
PR485
2
1 PC267_2
2
1 PC265_2
2
1 PC261_2
21
PR192
2
1
PR486
2
1 PC257
2
1 PC255_2
2
1 PC273
2
1 PC279
2
1 PC282_2
2
1 PC170
2
1 PC260_1
21
PR191
2
1 PC269_2
2
1 PC263_2
2
1 PC173
2
1 PC254_1
2
1 PC259_C0P1_2
2
1
PR186
PR335
PGND2
GL2
GL1
DNC
EN
PGND3
VOS
VIN2
PGND1
SW
LSET
IOUT
TOUT_FLT
PVCC
PHASE
VIN1
BOOT
AGND
VCC
REFIN
PWM
1 4
32
PGND2
GL2
GL1
DNC
EN
PGND3
VOS
VIN2
PGND1
SW
LSET
IOUT
TOUT_FLT
PVCC
PHASE
VIN1
BOOT
AGND
VCC
REFIN
PWM
1 2
1 4
32
2
1
SHEETDATE
DEPARTMENT
SIZE
PROJECT DOCUMENT NUMBER REV
REVIEWER
DESIGNER
123
7 3 2 1 6 5 4
E
A
B
C
E
D
C
B
A
7 6 5 4
D
OUT
BI
IN
OUT
BIBI
BI
OUT
IN
OUT
IN
IN
C



PVDDCR_CPU0_P1_PHASE3
11.0*7.5*12.52ND=CV+15^0TZ01DCR=2-3,0.27M OHMDCR=1-4,0.105M OHMISAT:70A@100CPGL6303.151HLT
PGL6303.151HLT11.0*7.5*12.5DCR=2-3,0.27M OHMDCR=1-4,0.105M OHMISAT:70A@100C2ND=CV+15^0TZ01PVDDCR_CPU0_P1_PHASE4Thu Sep 14 16:12:41 2023<NAME_2><NAME_1>MB FABCGT AMDV02212 OF 365
PVDDCR_CPU0_P1SW_P12V_AUX_PVDDCR_CPU0_P1_FLT
PVDDCR_CPU0_P1SW_P12V_AUX_PVDDCR_CPU0_P1_FLT
PVDDCR_CPU0_P1_PVCC
PVDDCR_CPU0_P1_PVCC212211
212
210210210211212213215216
211212213210210210210211212213215216211212213210C0402X6S0402LF1/16WSW_PVDDCR_CPU0_P1_BOOT3SW_PVDDCR_CPU0_P1_PH35.6PVDDCR_CPU0_P1_VCC3C0402SW_PVDDCR_CPU0_P1_BOOT3_RC1%CHIP
5.6SW_PVDDCR_CPU0_P1_BOOT4_RCSW_PVDDCR_CPU0_P1_BOOT41/16WCHIP 0402LF1%1UF20%C0805PVDDCR_CPU0_P1 VR PHASE 3&4
4V22UF20%X6SC08054V22UF20%X6SC0805IND150NHSMLFC0805X6S22UF16V20%0.22UF16V10%X7R0402
4V22UF20%X6SC08054V22UF20%X6SC0805X6S22UF16V20%SMLFIND150NHX7R10%0.22UF16V0402
C0805X6S16V20%X6S22UF16V20%C0402X6S10%1UF25VEMPTY10%560PF50VC04021/8WEMPTY1%1.50402LFX7R10%0.1UF25V04022.2UFC040210VX6S10%SMLFICISL99390FRZ-TR59352.21/16W0402LF1%CHIPX6S10%2.2UF10V8.87K1%1/16W0402LF0402X7R10%0.1UF25V0402LF05%CHIP1/16WC080522UF16V16VX6SX7R10%EMPTY10%560PF50VC04021/8WEMPTY1%1.50402LF0402LF05%CHIP1/16W10%X6S2.2UF10VC04021/16WCHIP1%2.20402LF8.87K1%1/16WEMPTY0402LFSMLFISL99390FRZ-TR5935X6S10%2.2UF10VC0402X7R10%0.1UF25V0402
IND_CPU0_P1_CPL3IND_CPU0_P1_CPL2
IND_CPU0_P1_CPL3SW_PVDDCR_CPU0_P1_PH4SW_PVDDCR_CPU0_P1_SW3_RCNC_PVDDCR_CPU0_P1_GL1_3NC_PVDDCR_CPU0_P1_GL2_3PVDDCR_CPU0_P1_IMON3PVDDCR_CPU0_P1_PWM3NC_PVDDCR_CPU0_P1_DNC3PVDDCR_CPU0_P1_LSET3PVDDCR_CPU0_P1_VCCSPVDDCR_CPU0_P1_VOS3
SW_PVDDCR_CPU0_P1_SW4_RCPVDDCR_CPU0_P1_VOS4NC_PVDDCR_CPU0_P1_GL2_4SW_PVDDCR_CPU0_P1_SW4NC_PVDDCR_CPU0_P1_GL1_4PVDDCR_CPU0_P1_VCC4PVDDCR_CPU0_P1_TEMP0PVDDCR_CPU0_P1_LSET4NC_PVDDCR_CPU0_P1_DNC4PVDDCR_CPU0_P1_IMON4PVDDCR_CPU0_P1_PWM4PVDDCR_CPU0_P1_VCCS
22UFSW_PVDDCR_CPU0_P1_SW3C0805
20%22UF0.1UF25V25VICC0805X6S10%0402EMPTYPVDDCR_CPU0_P1_TEMP0
2
1 PC304_3
2
1 PC302_3
4
32
1
PL31
2
1 PC298_3
2
1
PC300
2
1 PC305_4
2
1 PC303_4
2
1 PC299_4
4
32
1
PL322
1
PC301
2
1 PC296_3
2
1 PC294_3
2
1 PC292_3
21
PR197
2
1 PC316
2
1
PR522
2
1 PC290_3
2
1 PC288_C0P1_3
1
30
25_29
3
36
10_19
39
34
4
32
40
7_9-20_24
5
37
38
41
6
35
31
33
2
PU27
2
1
PR193
2
1 PC286
21
PR195
2
1 PC284_3
21
PR199
2
1 PC297_4
2
1 PC295_4
2
1 PC291_4
2
1 PC293_4
21
PR198
2
1 PC317
2
1
PR523
21
PR200
2
1 PC289_C0P1_4
2
1
PR194
21
PR196 1
30
25_29
3
36
10_19
39
34
4
32
40
7_9-20_24
5
37
38
41
6
35
31
33
2
PU28
2
1 PC287
2
1 PC285_4
PGND2
GL2
GL1
DNC
EN
PGND3
VOS
VIN2
PGND1
SW
LSET
IOUT
TOUT_FLT
PVCC
PHASE
VIN1
BOOT
AGND
VCC
REFIN
PWM
1 4
32
1 4
32
PGND2
GL2
GL1
DNC
EN
PGND3
VOS
VIN2
PGND1
SW
LSET
IOUT
TOUT_FLT
PVCC
PHASE
VIN1
BOOT
AGND
VCC
REFIN
PWM
SHEETDATE
DEPARTMENT
SIZE
PROJECT DOCUMENT NUMBER REV
REVIEWER
DESIGNER
123
7 3 2 1 6 5 4
E
A
B
C
E
D
C
B
A
7 6 5 4
D
IN
OUT
BIBI
BI
OUT
OUT
IN
IN
OUT
IN
C



6.5*6.5*10.02ND=CV+12^0EZ04ISAT:60A@100CDCR=0.17M OHMPGL6312.121AHLTPVDDCR_CPU0_P1_PHASE6DCR=1-4,0.105M OHM11.0*7.5*12.5ISAT:70A@100CPGL6303.151HLT2ND=CV+15^0TZ01DCR=2-3,0.27M OHM
ISAT:70A@100CPGL6303.151HLT11.0*7.5*12.52ND=CV+15^0TZ01DCR=1-4,0.105M OHMDCR=2-3,0.27M OHMPVDDCR_CPU0_P1_PHASE5
Thu Sep 14 16:12:41 2023<NAME_2><NAME_1>MB FABCGT AMDV02213 OF 365
PVDDCR_CPU0_P1_PVCCPVDDCR_CPU0_P1_PVCC
SW_P12V_AUX_PVDDCR_CPU0_P1_FLTPVDDCR_CPU0_P1
SW_P12V_AUX_PVDDCR_CPU0_P1_FLTPVDDCR_CPU0_P1
210211212213215216210210211212213210210210210211212213215216211212213210213213211X6SC0805PVDDCR_CPU0_P1_VOS5NC_PVDDCR_CPU0_P1_GL2_5PVDDCR_CPU0_P1_LSET58.87K0.1UFSW_PVDDCR_CPU0_P1_SW5SW_PVDDCR_CPU0_P1_SW5_RC1/16WPVDDCR_CPU0_P1_VCCSPVDDCR_CPU0_P1_IMON6PVDDCR_CPU0_P1_PWM6PVDDCR_CPU0_P1_TEMP0NC_PVDDCR_CPU0_P1_DNC6PVDDCR_CPU0_P1_LSET6PVDDCR_CPU0_P1_VCC6PVDDCR_CPU0_P1_PWM5NC_PVDDCR_CPU0_P1_GL2_6NC_PVDDCR_CPU0_P1_GL1_6SW_PVDDCR_CPU0_P1_SW6PVDDCR_CPU0_P1_VOS6SW_PVDDCR_CPU0_P1_SW6_RC
PVDDCR_CPU0_P1_IMON5PVDDCR_CPU0_P1_VCCSPVDDCR_CPU0_P1_TEMP0NC_PVDDCR_CPU0_P1_DNC5PVDDCR_CPU0_P1_VCC5NC_PVDDCR_CPU0_P1_GL1_5SW_PVDDCR_CPU0_P1_PH5SW_PVDDCR_CPU0_P1_PH6IND_CPU0_P1_CPL6IND_CPU0_P1_CPL6 IND_CPU0_P1_CPL5
040225V0.1UF10%X7R0402LF8.87K1%EMPTY 1/16WC040210V2.2UF10%X6SCHIP1/16W1%2.20402LFX6S10%10VC04022.2UFISL99390FRZ-TR5935ICSMLF
1%0402LF1.5EMPTY1/8W5%1/16WCHIP00402LFC040210%560PF0.1UF10%X7R20%16V22UFX6S20%16V22UFX6SC08050402LF1.51%EMPTY1/8W5%1/16W0402LFCHIP025V10%X7R04021%EMPTYC040210V2.2UF10%X6S1/16WCHIP1%2.20402LF C040210V2.2UF10%X6S040225V0.1UF10%X7RC0402560PF50V10%EMPTY25V1UF10%X6S20%16V22UFC080520%16V22UFX6S
040216V0.22UF10%X7R150NHINDSMLF20%16V22UFX6SC0805C0805X6S20%22UF4V22UFC0805X6S20%4V
X7R10%16V0.22UF0402IND150NHSMLF20%16V22UFC0805X6S20%22UF4VC0805X6S20%22UF4VISL99390FRZ-TR5935ICSMLFPVDDCR_CPU0_P1 VR PHASE 5&6
C0805C080525VINDSMLF120NH/69A50VEMPTYIND_CPU0_P1_CPL0CHIP1%0402LF1/16WSW_PVDDCR_CPU0_P1_BOOT6 SW_PVDDCR_CPU0_P1_BOOT6_RC5.6CHIP1%1/16W0402LFSW_PVDDCR_CPU0_P1_BOOT5 SW_PVDDCR_CPU0_P1_BOOT5_RC5.60402LFC0402X6S1UF25V10%X6SC04020402
1
30
25_29
3
36
10_19
39
34
4
32
40
7_9-20_24
5
37
38
41
6
35
31
33
2
PU24
2
1 PC316_5
2
1 PC315_5
2
1 PC313_5
4
32
1
PL332
1
PC314
2
1 PC135_6
2
1 PC134_6
2
1 PC132_6
4
32
1
PL82
1
PC133
21
PL27
2
1 PC312_5
2
1 PC311_5
2
1 PC310_5
21
PR203
2
1 PC318
2
1 PC309_5
2
1 PC308_C0P1_5
2
1
PR201
2
1 PC307
21
PR202
2
1 PC306_5
21
PR204
2
1
PR46
2
1 PC130_6
2
1 PC129_6
21
PR424
2
1 PC128_6
2
1 PC127_6
2
1 PC321
21
PR425
2
1
PR524
1
30
25_29
3
36
10_19
39
34
4
32
40
7_9-20_24
5
37
38
41
6
35
31
33
2
PU29
2
1 PC126_C0P1_6
2
1
PR422
2
1 PC125
21
PR423
2
1 PC124_6
PGND2
GL2
GL1
DNC
EN
PGND3
VOS
VIN2
PGND1
SW
LSET
IOUT
TOUT_FLT
PVCC
PHASE
VIN1
BOOT
AGND
VCC
REFIN
PWM
1 4
32
1 4
321 2
PGND2
GL2
GL1
DNC
EN
PGND3
VOS
VIN2
PGND1
SW
LSET
IOUT
TOUT_FLT
PVCC
PHASE
VIN1
BOOT
AGND
VCC
REFIN
PWM
SHEETDATE
DEPARTMENT
SIZE
PROJECT DOCUMENT NUMBER REV
REVIEWER
DESIGNER
123
7 3 2 1 6 5 4
E
A
B
C
E
D
C
B
A
7 6 5 4
D
IN
BIBI
OUT
BI
OUT
OUT
IN
IN
OUT
IN
C



Thu Aug 24 10:15:19 2023<NAME_2><NAME_1>MB FABCGT AMDV02214 OF 365Blank
SHEETDATE
DEPARTMENT
SIZE
PROJECT DOCUMENT NUMBER REV
REVIEWER
DESIGNER
123
7 3 2 1 6 5 4
E
A
B
C
E
D
C
B
A
7 6 5 4
D
C



PVDDCR_SOC_P1_PHASE2IRIPPLE:5.08A6.3*82ND=CC72703MD392ND=CVA50^0MZ07DCR=0.09M OHMISAT:70A@100C6.0*6.1*7.0PG2292.500HLTPGL6303.151HLT3RD=CVA50^0MZ08ESR=10M OHMISAT:70A@100C11.0*7.5*12.5DCR=1-4,0.105M OHM2ND=CV+15^0TZ01DCR=2-3,0.27M OHM2ND=CV+15^0TZ0111.0*7.5*12.5ISAT:70A@100CPGL6303.151HLTDCR=1-4,0.105M OHMDCR=2-3,0.27M OHM7.3*4.3*1.92ND=CH747LM8822ESR=4.5M OHM
PVDDCR_SOC_P1_PHASE1
PC317_7,PC318_8,PC345_9=EMPTYPR211,PR212,PR216=EMPTYPR211,PR212,PR216 = EMPTYPC317_7,PC318_8,PC345_9 = EMPTYPR209,PR210,PR215=CS00002JB13PU30,PU31,PU32 = AL021590000/TDA21590PR209,PR210,PR215 = CS00002JB13PR207,PR208,PR214 = CS00002JB133RD SOURCE:MPS BOMPU30,PU31,PU32 = AL087000A03/MP87000GMJTH-C11D-Z2ND SOURCE:INFENEON BOMPU30,PU31,PU32 = AL099390004/ISL99390FRZ-TR5935MAIN SOURCE:RENESAS BOMBOM NOTEThu Sep 14 16:12:21 2023<NAME_2><NAME_1>MB FABCGT AMDV02215 OF 3652160402X7R10%25VSW_P12V_AUX_PVDDCR_SOC_P1_FLTSW_P12V_AUX_PVDDCR_SOC_P1_FLT P12V_AUXPVDDCR_SOC_P1PVDDCR_SOC_P1PVDDCR_SOC_P1
PVDDCR_CPU0_P1_PVCCPVDDCR_CPU0_P1_PVCC210NC_PVDDCR_SOC_P1_DNC2ICISL99390FRZ-TR5935210211212213215 215216210215216210210211212213215216
215216210210215210X7R0402LFEMPTYSW_PVDDCR_SOC_P1_SW1_RC560PF5.6SW_PVDDCR_SOC_P1_BOOT1_RCSW_PVDDCR_SOC_P1_BOOT11%CHIP 0402LF1/16W5.6SW_PVDDCR_SOC_P1_BOOT2_RCSW_PVDDCR_SOC_P1_BOOT21%CHIP 0402LF1/16W22UF20%16VX6SC080522UFC0805X6SC0805C080520%16VCHIP150NHSMLF0.22UF16V10%C0805THLFC0805X6S20%16V 16VSMLFX6SX6S OSCONIND22UFX6SC080516V20%20%X6S25V1UF25V16V 20%16V50NH/86A22UF4V10%22UF0.1UF1/16W20%C0805X6S20%4V1KX6S10%040222UF16VPVDDCR_SOC_P1_VOS1NC_PVDDCR_SOC_P1_GL1_110%25VISL99390FRZ-TR5935IC0.1UF25V10%22UFX6S20%PVDDCR_SOC_P1 VR PHASE 1&2
SMLF0402LF5%1/16WCHIP0
1%CHIP0402LF22UFX6SC0805X7R10%25V040210%04020.1UFX7RINDX7R0402SMLFSPCAP2.5V20%470UFEMPTY20%470UF2.5VSMLF4V22UF20%X6SC08054V22UF20%X6SC0805SMLFSPCAP20%470UF2.5VX6S22UF16V20%X7R16V0402150NHSMLFIND
C0805C080510%50VC0402X6SC04020402X6S2.2UFC04020402LF1%2.2CHIP1/16WX6S10%2.2UFC040210VEMPTY1%8.87K0402LF1/16W0.1UF0402LF5%1/16W01.51/8W1%16VC080520%X6S1UFC04021/8WEMPTY1%1.50402LFEMPTY10%560PF50VC0402
SMLFX6S10%2.2UF10VC04022.21%CHIP1/16W0402LF10%10VC04022.2UFEMPTY1%8.87K1/16W0402LFX7R10%0.1UF25V0402PVDDCR_CPU0_P1_VCCSPVDDCR_SOC_P1_PWM2PVDDCR_SOC_P1_VOS2IND_SOC_P1_CPL2IND_SOC_P1_CPL3SW_PVDDCR_SOC_P1_PH2NC_PVDDCR_SOC_P1_GL2_1SW_PVDDCR_SOC_P1_SW1PVDDCR_SOC_P1_PWM1PVDDCR_SOC_P1_TEMP1PVDDCR_SOC_P1_LSET1NC_PVDDCR_SOC_P1_DNC1PVDDCR_CPU0_P1_VCCS
SW_PVDDCR_SOC_P1_SW2_RCNC_PVDDCR_SOC_P1_GL1_2NC_PVDDCR_SOC_P1_GL2_2SW_PVDDCR_SOC_P1_SW2PVDDCR_SOC_P1_VCC2PVDDCR_SOC_P1_LSET2PVDDCR_SOC_P1_TEMP1PVDDCR_SOC_P1_IMON2
10V10%
0.22UFEMPTYIND_SOC_P1_CPL2PVDDCR_SOC_P1_VCC1PVDDCR_SOC_P1_IMON1SW_PVDDCR_SOC_P1_PH110%X6S25V0.1UFX7R22UF20%270UF22UF22UF16V20%
PC8012
PC8011
1
30
25_29
3
36
10_19
39
34
4
32
40
7_9-20_24
5
37
38
41
6
35
31
33
2
PU31
21
PR212
2
1 PC341_1
PC6007
21
PL37
2
1 PC336PC334_1
2
1 PC342_2
2
1 PC339_2
2
1 PC337
PC335_2
2
1 PC332_2
2
1
PC334
2
1 PC331_1
2
1 PC329_1
21
PR209
2
1 PC141
2
1 PC321_SOP1_1
2
1 PC319
21
PR207
2
1 PC317_7
21
PR211
2
1 PC330_2
2
1
PR526
2
1 PC149
1
30
25_29
3
36
10_19
39
34
4
32
40
7_9-20_24
5
37
38
41
6
35
31
33
2
PU30
2
1 PC322_SOP1_2
2
1
PR206
2
1 PC320
21
PR208
PR339
2
1 PC344_1
2
1
PC338
4
32
1
PL352
1
PC333
2
1 PC343
2
1 PC340
4
32
1
PL36
2
1 PC327_1
2
1 PC323_1
2
1 PC325_1
2
1
PR205
2
1
PR525
2
1 PC328_2
2
1 PC324_2
21
PR210
2
1 PC326_2
2
1 PC318_8
PGND2
GL2
GL1
DNC
EN
PGND3
VOS
VIN2
PGND1
SW
LSET
IOUT
TOUT_FLT
PVCC
PHASE
VIN1
BOOT
AGND
VCC
REFIN
PWM
1 2
1 4
32
1 4
32
PGND2
GL2
GL1
DNC
EN
PGND3
VOS
VIN2
PGND1
SW
LSET
IOUT
TOUT_FLT
PVCC
PHASE
VIN1
BOOT
AGND
VCC
REFIN
PWM
2
1
2
1
2
1
SHEETDATE
DEPARTMENT
SIZE
PROJECT DOCUMENT NUMBER REV
REVIEWER
DESIGNER
123
7 3 2 1 6 5 4
E
A
B
C
E
D
C
B
A
7 6 5 4
D
OUT
IN
OUT
BIBI
BI
OUT
OUT
IN
IN
IN
C



PGL6303.151HLTISAT:70A@100CDCR=1-4,0.105M OHMDCR=2-3,0.27M OHM11.0*7.5*12.52ND=CV+15^0TZ012ND=CV+22Y0EZ016.5*6.5*10.0ISAT:30A@100CHCME656510Q-221QLDCR=0.17M OHMPVDDCR_SOC_P1_PHASE3
Thu Sep 14 16:12:21 2023<NAME_2><NAME_1>MB FABCGT AMDV02216 OF 365
PVDDCR_CPU0_P1_PVCCSW_P12V_AUX_PVDDCR_SOC_P1_FLTPVDDCR_SOC_P12102112122132152152102102102150402SW_PVDDCR_SOC_P1_BOOT3SW_PVDDCR_SOC_P1_PH3SW_PVDDCR_SOC_P1_SW3PVDDCR_SOC_P1_VOS35.6SW_PVDDCR_SOC_P1_BOOT3_RCCHIP1/16W1%0402LF10%NC_PVDDCR_SOC_P1_GL2_3NC_PVDDCR_SOC_P1_GL1_3PVDDCR_CPU0_P1_VCCSPVDDCR_SOC_P1_TEMP1PVDDCR_SOC_P1_LSET3PVDDCR_SOC_P1_PWM3NC_PVDDCR_SOC_P1_DNC3PVDDCR_SOC_P1_VCC3PVDDCR_SOC_P1_IMON3IND_SOC_P1_CPL0IND_SOC_P1_CPL3SW_PVDDCR_SOC_P1_SW3_RC040225V0.1UF10%X7R1/16W0402LF8.87K1%EMPTY1.50402LF1%1/8WEMPTYC040250V560PFEMPTY10%C040210V2.2UFX6SCHIP0402LF2.21%1/16WC040210V2.2UF10%X6S25V10%0.1UFX7R25V10%C04021UFX6S20%16V22UFX6SC08051/16W5%00402LFCHIP0.22UH/33AINDSMLF150NHINDSMLFC0805X6S20%22UF4VC0805X6S20%22UF4V20%16VX6S22UFC080520%16V22UFX6SC0805040216V0.22UF10%X7R16V22UFC080520%X6SICISL99390FRZ-TR5935SMLF
PVDDCR_SOC_P1 VR PHASE 3
2
1
PC353
2
1 PC355_3
2
1 PC354_3
21
PR216
2
1 PC348_3
2
1
PR213
2
1 PC346
2
1 PC195
2
1
PR511
2
1 PC345_9
1
30
25_29
3
36
10_19
39
34
4
32
40
7_9-20_24
5
37
38
41
6
35
31
33
2
PU32
PC353_3
2
1 PC352_3
2
1 PC351_3
4
32
1
PL38
2
1 PC350_3
21
PR215
2
1 PC349_3
2
1 PC347_SOP1_3
21
PR214
PL34
21
PGND2
GL2
GL1
DNC
EN
PGND3
VOS
VIN2
PGND1
SW
LSET
IOUT
TOUT_FLT
PVCC
PHASE
VIN1
BOOT
AGND
VCC
REFIN
PWM
1 4
321 2
SHEETDATE
DEPARTMENT
SIZE
PROJECT DOCUMENT NUMBER REV
REVIEWER
DESIGNER
123
7 3 2 1 6 5 4
E
A
B
C
E
D
C
B
A
7 6 5 4
D
OUT
IN
BI
OUT
IN
C



BOM NOTEMAIN SOURCE:RENESAS BOMPU34 = TBD/RAA229620GNP#HA0PMBUS ADDRESS AND CONFIG
IRM REV1.09DEFAULT POWER-ON VID=1.1VDC & AC=+/-80MVOCP=168A (EDC*1.2)MAX LOAD STEP=44AMAX LOAD RELEASE=37AIRM REV1.09SVI3 ADDRESS=PORT1 (0X2)EFFICIENCY > 90% @TDCWORK FREQUENCY=600KHZEDC=140ASVI3 ADDRESS=PORT1 (0X1)PVDDIO_P1 SPECFICATIONVID=0.9-1.2VNOTE: 0 OHM CHECKPR12,PR533 = EMPTYPR231 = CS21002FB06PR230 = CS25362FB02PU34 = TBD/XDPE192C3B2ND SOURCE:INFENEON BOMPR245,PR246 = CS01002FB07INFINEON 0X4C /2KTRACE SPACING = 5MILTRACE WIDTH = 10MILDIFFERENTIAL PAIRMPSVRRENESAS 0X74
DIFFERENTIAL PAIRTRACE WIDTH = 10MILTRACE SPACING = 5MILTDC=120ALOAD-LINE=0.4MOHMEDC=230AOCP=276A (EDC*1.2)MAX LOAD STEP=200ATDC=175AMAX AC=VID+200MVDC=+/-20MVVID=0.55-1.5VEFFICIENCY > 90% @TDCWORK FREQUENCY=600KHZMIN AC=VID-EDC*LL-110MVMAX LOAD RELEASE=200ADEFAULT POWER-ON VID=0.9VPVDDCR_CPU1_P1 SPECFICATION
PC367,PC368 = CH11006JB00PR533,PR12=EMPTYPR231 = CS00002JB13PR244 = CS34222FB06PR251 = CS37502FB05PR603 = CS24992FB07PC367,PC368 = CH31004KB17PC364 = CH21006JB10PC358,PC361,PR230,PC357=EMPTYPU34 = TBD/MP2857GQKT-001B-Z3RD SOURCE:MPS BOMPC357 = CH3104J1B00PC358,PC361 = CH12206KB14PC366 = CH5103KEB01PR244 = CS22002FB07PC366=CH5103KEB010X4C /42.2K1/9.53KCONFIGADDRESS(7-BIT)Thu Sep 14 16:12:42 2023<NAME_2><NAME_1>MB FABCGT AMDV02217 OF 365
VSENSE_PVDDCR_CPU1_P1_DPNC_PVDDCR_CPU1_P1_PWM76.3VI6PVDDIO_P1P3V3_AUXPVDD18_S5_P1P5V_AUXP3V3_AUX
PVDD18_S5_P1
P12V_AUX
P3V3_AUXP3V3_AUX
PVDD18_S5_P1PVDDCR_CPU1_P1219PVDDCR_CPU1_P1_PWM48281
8154542245454 222 223
218 219 220 222 223
218 219 2208182781511518382545454 218220222220222
2182232232232232222222202202192192192182181/16WCHIPCHIP5%1/16W0402LF1/16W1K0402LF1000PFCHIPX7R04020402LF50V331/16W1/16W5%0402LF5%5%0FM_PVDDCR_CPU1_P1_ENPWRGD_PVDDCR_CPU1_P110PF1%1/16W1K0EMPTY EMPTYCHIP 1/16W0402LF5%01/16W1KEMPTY5%1%1000PF1%10PF10PF50VEMPTY5%EMPTYCHIP1/16W0402LF1/16W3300PF1/16W5%0402LF330402LFCHIP
CHIP 1/16W5%0402LF33
0402LF50V1/16W0402LF05%1/16W05%CHIPX7R1/16W50VCHIP1000PF5%X7R1000PF50V0402LF0402PWRGD_PVDDIO_P15%0X7R
X7R5%04020402X7R50V1/16W1UFPVDDCR_CPU1_P1_RESET_N_R0402LF1000PF1/16WCHIP0402LF CHIP
1%1K
VSENSE_VSS_SENSE_B_P1VSENSE_VSS_SENSE_C_P1VSENSE_PVDDIO_P1_DPPVDDIO_P1_EN_GPVDDCR_CPU1_P1_VINSENPVDDIO_P1_TEMP1
PVDDCR_CPU1_P1_VCCS
PVDDCR_CPU1_P1_TEMP0ICBSS138KCHIP1/16W1%0402LF10K1%CHIP1%9.53K1/16W0402LFICPJA3415AE0402LF1K1%CHIP1/16W49.91%0402LFCHIP1/16W1%0402LF49.91%CHIP49.9 1/16W5%04025%040250V5%50V1%49.9CHIPEMPTY0402LF1%0402LFEMPTY1/16W0402LF1%1/16W
25V10%X7R04020.1UF05%0402LFCHIP1/16W1%0402LF1KEMPTY50V04020402LF4.99K1%EMPTY1/16WX7R10%0.1UF25V0402X7R5%CHIP 1/16W01/16W0402LF CHIP1KX7R10%04023300PF50V0402LF1%50VX7R10%470PF0402X7R10%470PF50V0CHIP5%0402LFEMPTY1000PF50V0402X7R10%0.1UF25V040210%0.1UF25VX7R0402X6S10%16VC04021UF0402LF11%CHIP1/16W
CHIP 1/16W
1K005%
0402CHIP 1/16W0402LF5%1/16W1%EMPTYPVDDIO_P1_EN_R10KPVDDIO_P1_EN
5%0402LF5%0402LF05%1/16WCHIPCHIP04021000PF0402LF10%05%1/16W
0402CHIP1K
0VSENSE_PVDDCR_CPU1_P1_VSEN00402VSENSE_PVDDIO_P1_VSEN11/16W10%5%04020402LF0402LFC0402X6S20%6.3V10UFCHIP0402LFPVDDCR_CPU1_P1_OCP_N40.2K50VPVDDCR_CPU1_P1/PVDDIO_P1 VR CONTROLLERCHIP 1/16WPVDDCR_CPU1_P1_RESET_N0402LF1%1001%0402LFCHIPSMB_SCM_2_R1_SCLCHIPSMB_SCM_2_R1_SDAPVDDCR_CPU1_P1_SMB_ALERTEMPTY1/16W1KSVID_PVDDCR_CPU1_P1_SVTI1%49.91/16WCHIP0402LFSVID_PVDDCR_CPU1_P1_SVC_RSVID_PVDDCR_CPU1_P1_SVD_RSVID_PVDDCR_CPU1_P1_SVTORAA229620GNP#HA0ICSMLFPVDDCR_CPU1_P1_IMON1PVDDCR_CPU1_P1_VCCSVID_PVDDCR_CPU1_P1_SVTI_RSMB_CLK_PVDDCR_CPU1_P1_RSVID_PVDDCR_CPU1_P1_SVC_R1PVDDCR_CPU1_P1_IMON6SVID_PVDDCR_CPU1_P1_SVTO_RNC_PVDDCR_CPU1_P1_IMON7NC_PVDDCR_CPU1_P1_IMON8PWRGD_PVDDIO_P1_R
SVID_PVDDCR_CPU1_P1_SVD_R1PVDDCR_CPU1_P1_SMB_ALERT_RPVDDCR_CPU1_P1_EN_RSMB_DIO_PVDDCR_CPU1_P1_RNC_PVDDCR_CPU1_P1_PWM8PVDDIO_P1_PWM2
PWRGD_PVDDCR_CPU1_P1_RPVDDCR_CPU1_P1_PWM6PVDDCR_CPU1_P1_VMONPVDDIO_P1_IMON2
PVDDCR_CPU1_P1_PWM1PVDDIO_P1_PWM4PVDDIO_P1_IMON4PVDDIO_P1_PWM3PVDDIO_P1_IMON3PVDDCR_CPU1_P1_OCP_N_RPVDDCR_CPU1_P1_EN1_ADDR_CFGPVDDIO_P1_PWM1PVDDIO_P1_IMON1PVDDCR_CPU1_P1_PWM5PVDDCR_CPU1_P1_IMON5PVDDCR_CPU1_P1_IMON4PVDDCR_CPU1_P1_PWM3PVDDCR_CPU1_P1_IMON3PVDDCR_CPU1_P1_PWM2PVDDCR_CPU1_P1_IMON2
R6088
PR8012
PR8011
21C5006
21
C5020
21
C5022
21
PR12
21PR253
2
1
PC365
2
1
PC366
2
1 PC29
2
1 PC93
21C836021R8233
21R8234
21R8235
21C8359
21R8248
21
PR239
21
R8238
21R8249
21R8250
2
1
PC358
21
PR245
PR533
2
1 PC367
2
1 PC368
21
R8252
21
PR246
2
1
PC361
21R8247
21
R240
21
R8241
21
PC363
2
1
PC364PR603
21C836221R8242
21R8243
21
PR251
2
1 PC357
2
1
R8225
2
1
R8222
2
1
R8220
2
1
PR218
21
PR228
2
1 C310
2
1 C309
2
1 C308
2
1
R8219
2
1
PR217
21
PR226
21
PR227
21
PR460
2
1
PR232
G
PQ12
2
1 PR244
21PR230
2
1
PR231
G
PQ16
2
1 C8356
21
R8224
SDS D
40
25
45
46
19
48
47
TH
43
44
23
24
21
22
39
26
18
12
11
10
9
8
7
6
5
4
3
2
1
13
14
20
16
41
15
42
17
27
28
29
30
31
32
33
34
35
36
37
38
PU34
S
G
D
G
CS10
PWM10
CS9
PWM9
CS8
PWM8
CS7
PWM7
CS0
PWM0
TEMP1
EN1||ADDR_CFG
TH_GND
OCP_L
CS2
PWM2
CS3
PWM3
PWM11
CS1
RGND1
VSEN1
VDDIO
TEMP0
VINSEN
VMON||IINSEN
VCCS
PWM6
PG0
PWM1
VSEN0
PWM5
PWM4
PMSDA
RGND0
EN0
nPMALERT
SVD
PG1
CS4
CS5
RESET_L
SVTO
CS6
SVC
PMSCL
SVTI
VCC
CS11
SD
21
21
2
1
SHEETDATE
DEPARTMENT
SIZE
PROJECT DOCUMENT NUMBER REV
REVIEWER
DESIGNER
123
7 3 2 1 6 5 4
E
A
B
C
E
D
C
B
A
7 6 5 4
D
OUT
IN
OUT
IN
BI
OUT
IN
IN
IN
OUT
IN
OUT
IN
IN
IN IN
OUT
OUT
IN
OUT
IN
OUT
IN
OUT
IN
OUT
IN
OUT
IN
OUT
OUT
IN
OUT
IN
IN
OUT
IN
IN
IN
C



2ND=CV+15^0TZ01DCR=2-3,0.27M OHMDCR=1-4,0.105M OHM11.0*7.5*12.5ISAT:70A@100CPGL6303.151HLT6.0*6.1*7.0DCR=0.09M OHM2ND=CVA50^0MZ073RD=CVA50^0MZ08PG2292.500HLTISAT:70A@100C
MAIN=CH122KM8801ESR=4.5M OHM7.3*4.3*1.9ISAT:70A@100CPGL6303.151HLT11.0*7.5*12.52ND=CV+15^0TZ01DCR=2-3,0.27M OHMDCR=1-4,0.105M OHM2ND=CC72703MD39
2ND SOURCE:INFENEON BOM
PVDDCR_CPU1_P1_PHASE1PVDDCR_CPU1_P1_PHASE26.3*8IRIPPLE:5.08AESR=10M OHM
PU35,PU5,PU37,PU36,PU38,PU33 = AL021590000/TDA21590PR255,PR254,PR263,PR262,PR270,PR426 = CS00002JB13PR273,PR268,PR269,PR260,PR261,PR429 = EMPTYPC374_1,PC373_2,PC404_3,PC403_4,PC422_5,PC136_6 = EMPTYPR340,PR260,PR261,PR268,PR269,PR273,PR429 = EMPTYPU35,PU5,PU37,PU36,PU38,PU33 = AL087000A03/MP87000GMJTH-C11D-ZPR341,PR258,PR259,PR266,PR267,PR272,PR428 = CS00002JB133RD SOURCE:MPS BOMPC374_1,PC373_2,PC404_3,PC403_4,PC422_5,PC136_6 = EMPTYPR272,PR266,PR267,PR259,PR258,PR428 = CS00002JB13BOM NOTEMAIN SOURCE:RENESAS BOMPU35,PU5,PU37,PU36,PU38,PU33 = AL099390004/ISL99390FRZ-TR5935Thu Sep 14 16:12:21 2023<NAME_2><NAME_1>MB FABCGT AMDV02218 OF 36525V0402LF217220PVDDCR_CPU1_P1_PWM2
SW_P12V_AUX_PVDDCR_CPU1_P1_FLTPVDDCR_CPU1_P1_PVCCP5V_AUX P3V3_AUX PVDDCR_CPU1_P1_PVCC
PVDDCR_CPU1_P1PVDDCR_CPU1_P1PVDDCR_CPU1_P1SW_P12V_AUX_PVDDCR_CPU1_P1_FLTP12V_AUX
PVDDCR_CPU1_P1 VR PHASE 1&2NC_PVDDCR_CPU1_P1_GL2_2NC_PVDDCR_CPU1_P1_DNC2SW_PVDDCR_CPU1_P1_BOOT2_R20%0217217218219220222223218219220217217217218219220222223218219217217220218 219218270UF20%OSCONSMLF16VIND50NH/86AX6SOSCONSMLF16V20%270UFSW_PVDDCR_CPU1_P1_BOOTR1PVDDCR_CPU1_P1_VCC10.22UF16V10%SW_PVDDCR_CPU1_P1_SW1_RCC080516V22UF1UFPVDDCR_CPU1_P1_IMON1PVDDCR_CPU1_P1_VCCSPVDDCR_CPU1_P1_TEMP0PVDDCR_CPU1_P1_PWM1PVDDCR_CPU1_P1_VCCSPVDDCR_CPU1_P1_LSET2PVDDCR_CPU1_P1_TEMP0PVDDCR_CPU1_P1_IMON2PVDDCR_CPU1_P1_VCC2SW_PVDDCR_CPU1_P1_BOOTR2PVDDCR_CPU1_P1_VOS2NC_PVDDCR_CPU1_P1_GL1_2SW_PVDDCR_CPU1_P1_SW2_RCNC_PVDDCR_CPU1_P1_DNC1SW_PVDDCR_CPU1_P1_SW1NC_PVDDCR_CPU1_P1_GL1_1NC_PVDDCR_CPU1_P1_GL2_1PVDDCR_CPU1_P1_VOS1IND_CPU1_P1_CPL5IND_CPU1_P1_CPL1 IND_CPU1_P1_CPL2IND_CPU1_P1_CPL1SW_PVDDCR_CPU1_P1_SW20402X7R1%25V0.1UF040210%X7RC040210V2.2UF10%X6S0402LF1/16WCHIP1%2.2C040210V2.2UF10%X6S8.87K0402LF1%EMPTY1/16WC040210V2.2UF10%X6S0402LF1/16W1%2.2C040210V2.2UF10%X6SIC25V0.1UF10%0402LF1.5EMPTY1/8W1%C040250V560PFEMPTY10%1/16WCHIP5%00402LF0.22UF16V10%X7R0402C040225V10%X6S20%X6SC08050402LF1.51%EMPTY1/8W20%16V22UFX6S20%X6SC080516V22UF25V0.1UF10%C040250V560PF10%EMPTYC040225V1UFX6S20%16V22UFX6SC08050402X7R16V22UFC080516VX6S
150NHINDSMLF1/16WCHIP5%0402LF0SMLFSPCAP20%220UF4VSPCAP4V20%220UFSMLFSPCAP4VSMLF20%220UFC0805X6S20%22UF4VC0805X6S20%22UF4V4VSPCAP20%220UFSMLF SMLF4V20%220UFSPCAP150NH040225V0.1UF10%X7R25V0402X7R10%C0805X6S22UF4VC0805X6S20%22UF4V1/16WCHIP1%1K0402LF1/16WCHIP5%0402LF01/16WEMPTY0402LF5%SMLFPVDDCR_CPU1_P1_LSET1INDC080520%20%10%CHIPSMLFSMLFISL99390FRZ-TR593510%EMPTY0.1UF8.87K1/16W1%CHIP1/16W0402LF5.6CHIP1%SW_PVDDCR_CPU1_P1_BOOT15.6X7R0402ISL99390FRZ-TR5935SW_PVDDCR_CPU1_P1_BOOT1_RIC1/16W0402LFSW_PVDDCR_CPU1_P1_BOOT20402X7R0.1UF22UFSMLF
1
30
25_29
3
36
10_19
39
34
4
32
40
7_9-20_24
5
37
38
41
6
35
31
33
2
PU35
PR341PR340
2
1
PC398_1
2
1
PC395_1
PC375
2
1
PC392
21
PL42
4
32
1
PL40
2
1 PC389
2
1
PC397_2
2
1
PC394_2
21 PR261
4
32
1
PL41
2
1
PC384_1
2
1
PC381_1
2
1 PC383
2
1
PC379_1
2
1
PC377_1
2
1 PC201
PR258
2
1
PC375_1
2
1
PC385_2
2
1
PR512
2
1
PC380_2
2
1
PC378_2
2
1 PC386
21 PR260
2
1 PC202
2
1
PR513
2
1
PC376_2
1
30
25_29
3
36
10_19
39
34
4
32
40
7_9-20_24
5
37
38
41
6
35
31
33
2
PU5
2
1 PC371_C1P1_1
2
1
PR256
2
1
PR255
2
1 PC372_C1P1_2
2
1 PC370
2
1 PC374_1
2
1
PR254
PR342
2
1 PC391
2
1 PC388
2
1 PC387
2
1 PC106
2
1
PC382_2
PR259
2
1 PC369
2
1
PR257
2
1 PC373_2
PC390 PC393
PGND2
GL2
GL1
DNC
EN
PGND3
VOS
VIN2
PGND1
SW
LSET
IOUT
TOUT_FLT
PVCC
PHASE
VIN1
BOOT
AGND
VCC
REFIN
PWM
1 2
1 4
32
1 4
32
PGND2
GL2
GL1
DNC
EN
PGND3
VOS
VIN2
PGND1
SW
LSET
IOUT
TOUT_FLT
PVCC
PHASE
VIN1
BOOT
AGND
VCC
REFIN
PWM
2
1
2
1
2
1
SHEETDATE
DEPARTMENT
SIZE
PROJECT DOCUMENT NUMBER REV
REVIEWER
DESIGNER
123
7 3 2 1 6 5 4
E
A
B
C
E
D
C
B
A
7 6 5 4
D BI
OUT
IN
BI
OUT
BI
IN
BI
OUT
IN
OUT
IN
C



PVDDCR_CPU1_P1_PHASE4PVDDCR_CPU1_P1_PHASE3
DCR=1-4,0.105M OHMDCR=2-3,0.27M OHMDCR=1-4,0.105M OHM11.0*7.5*12.5ISAT:70A@100CPGL6303.151HLTISAT:70A@100CPGL6303.151HLTDCR=2-3,0.27M OHM11.0*7.5*12.5Thu Sep 14 16:12:21 2023<NAME_2><NAME_1>MB FABCGT AMDV02219 OF 365
PVDDCR_CPU1_P1_PVCCPVDDCR_CPU1_P1_PVCCSW_P12V_AUX_PVDDCR_CPU1_P1_FLTSW_P12V_AUX_PVDDCR_CPU1_P1_FLT
PVDDCR_CPU1_P1PVDDCR_CPU1_P1217218219220217217217218219220217217218219220222223217217218219220222223219218 2190402CHIP5.6C08050402LFC04025.6SW_PVDDCR_CPU1_P1_BOOT4_RSW_PVDDCR_CPU1_P1_BOOT4CHIP1%0402LF1/16WSW_PVDDCR_CPU1_P1_BOOT3_RSW_PVDDCR_CPU1_P1_BOOT31%1/16WX6SC04020402LFEMPTYSW_PVDDCR_CPU1_P1_SW3_RCC0402EMPTY10%50V560PFSW_PVDDCR_CPU1_P1_BOOTR3SW_PVDDCR_CPU1_P1_SW3PVDDCR_CPU1_P1_VOS3NC_PVDDCR_CPU1_P1_GL1_3NC_PVDDCR_CPU1_P1_GL2_3
PVDDCR_CPU1_P1 VR PHASE 3&410VPVDDCR_CPU1_P1_PWM310%25V1UF10%X6S25V0.1UFSW_PVDDCR_CPU1_P1_BOOTR4SW_PVDDCR_CPU1_P1_SW4PVDDCR_CPU1_P1_VOS4NC_PVDDCR_CPU1_P1_GL1_4NC_PVDDCR_CPU1_P1_GL2_4
04020402LF1/16WPVDDCR_CPU1_P1_TEMP0PVDDCR_CPU1_P1_IMON4PVDDCR_CPU1_P1_PWM4PVDDCR_CPU1_P1_TEMP0PVDDCR_CPU1_P1_LSET4PVDDCR_CPU1_P1_VCCSPVDDCR_CPU1_P1_VCC4NC_PVDDCR_CPU1_P1_DNC4
PVDDCR_CPU1_P1_IMON3PVDDCR_CPU1_P1_VCCSPVDDCR_CPU1_P1_LSET3NC_PVDDCR_CPU1_P1_DNC3PVDDCR_CPU1_P1_VCC3
SW_PVDDCR_CPU1_P1_SW4_RCIND_CPU1_P1_CPL3IND_CPU1_P1_CPL2 IND_CPU1_P1_CPL3
040225V0.1UF10%X7R1/16WEMPTY1%8.87K0402LFC040210V2.2UF10%X6S040225V0.1UF10%X7R1/16WCHIP1%2.20402LFX6SC04022.2UF10%8.87K1%EMPTYISL99390FRZ-TR5935ICSMLF25V10%X7R10V2.2UF10%X6S0402LFCHIP1/16W1%2.2C040210V2.2UF10%X6S0.1UF
EMPTY0402LF1.51%1/8WC040250V560PF10%EMPTY1/16WCHIP5%00402LF16V040210%X7R0.22UF25V1UF10% 20%16V22UFX6SC08051.51%1/8W20%16V22UFC0805X6S20%16V22UFX6SC08055%01/16WCHIP0402LF150NHINDSMLF
C040222UF16VX6S20%10%0.22UFX7R16V22UFX6SC080520%16V22UFC080516V20%X6SIND150NHSMLFC0805X6S20%22UF4VC0805X6S20%22UF4VC0805X6S20%22UF4VC0805X6S20%22UF4VISL99390FRZ-TR5935ICSMLFX7R0402
1
30
25_29
3
36
10_19
39
34
4
32
40
7_9-20_24
5
37
38
41
6
35
31
33
2
PU37
2
1
PC419_3
2
1
PC420_4
2
1
PC418_4
2
1
PC417_3
4
32
1
PL44
2
1
PC416_3
2
1
PC412_3
2
1 PC414
2
1
PC406_3
2
1 PC206
PR267
21 PR269
2
1
PC415_4
2
1
PC411_4
2
1
PR516
2
1
PC407_4
PR266
2
1
PR515
2
1 PC408_3
2
1 PC402_C1P1_3
2
1
PR265
2
1 PC400
2
1 PC405_4
1
30
25_29
3
36
10_19
39
34
4
32
40
7_9-20_24
5
37
38
41
6
35
31
33
2
PU36
2
1
PR263
2
1 PC401_C1P1_4
2
1
PR264
2
1 PC404_3
2
1 PC399
2
1
PR262
2
1
PC410_3
4
32
1
PL43
2
1
PC409_4
2
1 PC413
21 PR268
2
1 PC205
2
1 PC403_4
PGND2
GL2
GL1
DNC
EN
PGND3
VOS
VIN2
PGND1
SW
LSET
IOUT
TOUT_FLT
PVCC
PHASE
VIN1
BOOT
AGND
VCC
REFIN
PWM
1 4
32
1 4
32
PGND2
GL2
GL1
DNC
EN
PGND3
VOS
VIN2
PGND1
SW
LSET
IOUT
TOUT_FLT
PVCC
PHASE
VIN1
BOOT
AGND
VCC
REFIN
PWM
SHEETDATE
DEPARTMENT
SIZE
PROJECT DOCUMENT NUMBER REV
REVIEWER
DESIGNER
123
7 3 2 1 6 5 4
E
A
B
C
E
D
C
B
A
7 6 5 4
D
IN
OUT
BIBI
IN
BI
OUT
IN
OUT
IN
OUT
C



PVDDCR_CPU1_P1_PHASE5
2ND=CV+15^0TZ01DCR=1-4,0.105M OHM11.0*7.5*12.5ISAT:70A@100CPGL6303.151HLTDCR=2-3,0.27M OHM2ND=CV+15^0TZ0111.0*7.5*12.5ISAT:70A@100CPGL6303.151HLTDCR=2-3,0.27M OHMDCR=1-4,0.105M OHMPVDDCR_CPU1_P1_PHASE62ND=CV+12^0EZ04DCR=0.17M OHM6.5*6.5*10.0ISAT:60A@100CPGL6312.121AHLTThu Sep 14 16:12:21 2023<NAME_2><NAME_1>MB FABCGT AMDV02220 OF 365
PVDDCR_CPU1_P1_PVCCPVDDCR_CPU1_P1_PVCCSW_P12V_AUX_PVDDCR_CPU1_P1_FLTSW_P12V_AUX_PVDDCR_CPU1_P1_FLT
PVDDCR_CPU1_P1PVDDCR_CPU1_P1217218219220222223218219220217218219220217217217217
217217218219220222223 220220 218SW_PVDDCR_CPU1_P1_BOOT6SW_PVDDCR_CPU1_P1_BOOTR6SW_PVDDCR_CPU1_P1_SW6NC_PVDDCR_CPU1_P1_GL1_6NC_PVDDCR_CPU1_P1_GL2_65.6SW_PVDDCR_CPU1_P1_BOOT5_RC0402SMLF5.6SW_PVDDCR_CPU1_P1_BOOT50402LFCHIP1%1/16WSW_PVDDCR_CPU1_P1_BOOT6_RCHIP0402LF1/16W1%IND_CPU1_P1_CPL0SMLF560PF120NH/69AINDSMLF04020402X7R0.1UF10%C0805X6S20%16V22UFSW_PVDDCR_CPU1_P1_BOOTR5SW_PVDDCR_CPU1_P1_SW5NC_PVDDCR_CPU1_P1_GL2_5PVDDCR_CPU1_P1_VCCSPVDDCR_CPU1_P1_TEMP0PVDDCR_CPU1_P1_TEMP0PVDDCR_CPU1_P1_PWM5PVDDCR_CPU1_P1_IMON6PVDDCR_CPU1_P1_LSET6PVDDCR_CPU1_P1_PWM6NC_PVDDCR_CPU1_P1_DNC6PVDDCR_CPU1_P1_VCC6PVDDCR_CPU1_P1_IMON5PVDDCR_CPU1_P1_VCCSPVDDCR_CPU1_P1_LSET5PVDDCR_CPU1_P1_VCC5NC_PVDDCR_CPU1_P1_DNC5NC_PVDDCR_CPU1_P1_GL1_5SW_PVDDCR_CPU1_P1_SW6_RCPVDDCR_CPU1_P1_VOS6IND_CPU1_P1_CPL6SW_PVDDCR_CPU1_P1_SW5_RCIND_CPU1_P1_CPL6 IND_CPU1_P1_CPL5040225V0.1UF10%X7R0402LF8.87K1%EMPTY1/16W040225V0.1UF10%X7RC040210V2.2UF10%X6S1/16WCHIP1%2.20402LF0402LF8.87K1%EMPTY1/16WICSMLFC040210V2.2UF10%X6SC040210V2.2UF10%X6S1/16WCHIP1%2.20402LF C040210V2.2UF10%X6S
1.51%1/8WEMPTY0402LFEMPTY10%50VC04021/16WCHIP5%0402LF025VC040225V10%X6S1UF20%16V22UFX6SC08050402LF1.51%EMPTY1/8W20%16V22UFX6SC0805040216V0.22UF10%X7R20%16V22UFX6SC08051/16WCHIP00402LF5%150NHINDC040210%X6S20%16VX6SC08050.22UF10%X7R040222UF20%16V22UFX6SC0805150NHINDSMLFC0805X6S20%22UF4VC0805X6S20%22UF4VC08054V22UF20%X6SC0805X6S20%22UF4VISL99390FRZ-TR5935
PVDDCR_CPU1_P1 VR PHASE 5&6
ISL99390FRZ-TR5935X7R25V25V10%IC0.1UF1UF10%PVDDCR_CPU1_P1_VOS5EMPTY50V560PF16V
1
30
25_29
3
36
10_19
39
34
4
32
40
7_9-20_24
5
37
38
41
6
35
31
33
2
PU38
2
1
PC431_5
2
1
PC430_5
2
1
PC149_6
2
1
PC148_6
4
32
1
PL45
2
1
PC429_5
2
1 PC428
2
1
PC426_5
2
1
PC424_5
2
1
PC425_5
2
1 PC207
PR272
4
32
1
PL69
21 PR273
2
1
PC147_6
2
1 PC146
2
1
PC145_6
2
1
PR517
2
1
PC144_6
2
1
PC141_6
2 1
PL39
21 PR429
2
1 PC208
2
1
PR518
2
1
PR271
2
1 PC421
2
1 PC139_C1P1_6
1
30
25_29
3
36
10_19
39
34
4
32
40
7_9-20_24
5
37
38
41
6
35
31
33
2
PU33
2
1
PR270
2
1
PR427
2
1 PC138
2
1 PC422_5
2
1
PR426
2
1 PC136_6
2
1
PC427_5
2
1
PC140_6
PR428
2
1 PC423_C1P1_5
PGND2
GL2
GL1
DNC
EN
PGND3
VOS
VIN2
PGND1
SW
LSET
IOUT
TOUT_FLT
PVCC
PHASE
VIN1
BOOT
AGND
VCC
REFIN
PWM
1 4
32
1 4
3212
PGND2
GL2
GL1
DNC
EN
PGND3
VOS
VIN2
PGND1
SW
LSET
IOUT
TOUT_FLT
PVCC
PHASE
VIN1
BOOT
AGND
VCC
REFIN
PWM
SHEETDATE
DEPARTMENT
SIZE
PROJECT DOCUMENT NUMBER REV
REVIEWER
DESIGNER
123
7 3 2 1 6 5 4
E
A
B
C
E
D
C
B
A
7 6 5 4
D
IN
OUT
BI
IN
BI
BI
OUT
OUT
IN
IN
OUT
C



Thu Aug 24 10:15:24 2023<NAME_2><NAME_1>MB FABCGT AMDV02221 OF 365Blank
SHEETDATE
DEPARTMENT
SIZE
PROJECT DOCUMENT NUMBER REV
REVIEWER
DESIGNER
123
7 3 2 1 6 5 4
E
A
B
C
E
D
C
B
A
7 6 5 4
D
C



6.0*6.1*7.0PG2292.500HLTISAT:70A@100CDCR=0.09M OHM2ND=CVA50^0MZ073RD=CVA50^0MZ08ESR=10M OHM2ND=CC72703MD39PVDDIO_P1_PHASE1
PR280,PR281,PR374,PR375=EMPTY3RD SOURCE:MPS BOMPVDDIO_P1_PHASE22ND=CV+15^0TZ01DCR=2-3,0.27M OHMPGL6303.151HLTISAT:70A@100C11.0*7.5*12.52ND=CH747LM8822ESR=4.5M OHM7.3*4.3*1.9IRIPPLE:5.08A6.3*811.0*7.5*12.5ISAT:70A@100C2ND=CV+15^0TZ01DCR=2-3,0.27M OHMPGL6303.151HLTDCR=1-4,0.105M OHMDCR=1-4,0.105M OHMPC435_7,PC436_8,PC620_9,PC621_10=EMPTYPR278,PR279,PR372,PR373=CS00002JB13BOM NOTEPU39,PU40,PU52,PU53=AL087000A03/MP87000GMJTH-C11D-ZPC435_7,PC436_8,PC620_9,PC621_10 = EMPTYPR280,PR281,PR374,PR375 = EMPTYPR275,PR274,PR369,PR368 = CS00002JB13PR372,PR373,PR278,PR279 = CS00002JB13PU39,PU40,PU52,PU53 = AL021590000/TDA215902ND SOURCE:INFENEON BOMPU39,PU40,PU52,PU53 = AL099390004/ISL99390FRZ-TR5935MAIN SOURCE:RENESAS BOMThu Sep 14 16:12:42 2023<NAME_2><NAME_1>MB FABCGT AMDV02222 OF 365
C0805222PVDDIO_P1_VOS1SW_P12V_AUX_PVDDIO_P1_FLTP12V_AUXPVDDIO_P1PVDDIO_P1PVDDIO_P1SW_P12V_AUX_PVDDIO_P1_FLTPVDDCR_CPU1_P1_PVCCPVDDCR_CPU1_P1_PVCC
PVDDIO_P1 VR PHASE 1&2222223222223217217217217218219220222223217217218219220222223222223217217X6SC0402 C0805 C0805X6SX6S20%16V22UF20%20%16V22UFC0805270UFIND20%22UF16VX6S22UFC080520%16VX6S10%25V1UF10%X7R0.1UF25V040216VSMLFOSCON10%0.22UF10%0402SW_PVDDIO_P1_BOOT1SMLFICSMLFIND150NH0402LF1K1%CHIP1/16W4V22UF20%X6SC0805X6S20%22UF4VC0805X7R10%100NF50VC04020.1UF25VX7R040250NH/86ASMLFINDSMLF150NHX7R16V0402EMPTY20%470UF2.5VSMLFSPCAP20%470UFSMLF2.5VSPCAP20%470UF2.5VSMLF4V22UF20%X6SC08054V22UF20%X6SC0805X6S20%16V22UFC08050402LFCHIP1/16W05%20%16V22UFC0805X6S20%16V22UFX6SX7R10%0.22UF16V04020402LF05%CHIP1/16W
EMPTYSMLFICX6S10%2.2UF10VC04020402LF2.21%CHIP1/16WX6S10%2.2UF10VC04020402LF1/16WEMPTY1%8.87K1%X6S10%1UF25VC0402X7R10%0.1UF25VC0402EMPTY10%560PF50V1%1.51/8WEMPTY0402LFX6S10%2.2UF10VC04020402LF2.21%CHIP1/16WX6SC040210V2.2UF1/16WEMPTY1%8.87K0402LF10%X7R0.1UF25V040225V10%X7R0402SW_PVDDIO_P1_BOOTR2SW_PVDDIO_P1_SW2IND_PVDDIO_P1_CPL2IND_PVDDIO_P1_CPL2IND_PVDDIO_P1_CPL3NC_PVDDIO_P1_GL1_1NC_PVDDIO_P1_DNC1PVDDIO_P1_VCC1
NC_PVDDIO_P1_GL1_2NC_PVDDIO_P1_GL2_2PVDDIO_P1_VOS2PVDDIO_P1_TEMP1PVDDIO_P1_LSET2PVDDIO_P1_IMON2PVDDIO_P1_PWM2PVDDCR_CPU1_P1_VCCSPVDDIO_P1_IMON1PVDDCR_CPU1_P1_VCCSPVDDIO_P1_TEMP1PVDDIO_P1_PWM1SW_PVDDIO_P1_SW1SW_PVDDIO_P1_BOOTR1ISL99390FRZ-TR5935PVDDIO_P1_LSET1NC_PVDDIO_P1_GL2_1ISL99390FRZ-TR5935560PF50V10%C0402SW_PVDDIO_P1_SW1_RC1.51/8WEMPTY0402LFNC_PVDDIO_P1_DNC2PVDDIO_P1_VCC210%SW_PVDDIO_P1_SW2_RC0.1UF0402LF1%CHIP1/16WSW_PVDDIO_P1_BOOT2SW_PVDDIO_P1_BOOT2_R5.60402LF1%CHIP1/16WSW_PVDDIO_P1_BOOT1_R5.6
1
30
25_29
3
36
10_19
39
34
4
32
40
7_9-20_24
5
37
38
41
6
35
31
33
2
PU40
4
32
1
PL48
PR378
2
1
PC459_1
2
1
PC456_1
2
1
PC451
PC438
21
PL49
4
32
1
PL47
2
1 PC448_1
2
1
PC444_1
2
1 PC447
2
1
PC455
2
1
PC452
2
1
PC450
2
1
PC460_2
2
1
PC458_2
2
1
PC449_2
PR280
2
1
PC446_2
2
1
PC443_2
2
1 PC445
PR281
2
1
PC442_1
21
PR279
2
1
PC440_1
2
1
PC438_1
2
1 PC174
1
30
25_29
3
36
10_19
39
34
4
32
40
7_9-20_24
5
37
38
41
6
35
31
33
2
PU39
2
1 PC437_IOP1_1
2
1
PR277
2
1 PC433
2
1
PR275
2
1
PR488
2
1
PC441_2
PR278
2
1 PC439_2
2
1 PC175
2
1
PR489
2
1 PC434_IOP1_2
2
1
PR276
2
1 PC432
2
1
PR274
2
1 PC435_7
2
1 PC436_8
PC7001 PC454
PGND2
GL2
GL1
DNC
EN
PGND3
VOS
VIN2
PGND1
SW
LSET
IOUT
TOUT_FLT
PVCC
PHASE
VIN1
BOOT
AGND
VCC
REFIN
PWM
1 4
32
1 2
1 4
32
PGND2
GL2
GL1
DNC
EN
PGND3
VOS
VIN2
PGND1
SW
LSET
IOUT
TOUT_FLT
PVCC
PHASE
VIN1
BOOT
AGND
VCC
REFIN
PWM
2
1
2
1
2
1
SHEETDATE
DEPARTMENT
SIZE
PROJECT DOCUMENT NUMBER REV
REVIEWER
DESIGNER
123
7 3 2 1 6 5 4
E
A
B
C
E
D
C
B
A
7 6 5 4
D
IN
OUT
IN
BI
BIBI
IN
OUT
OUT
IN
OUT
C



PVDDIO_P1_PHASE4DCR=2-3,0.27M OHMPGL6303.151HLT11.0*7.5*12.5ISAT:70A@100CDCR=1-4,0.105M OHM2ND=CV+15^0TZ01PGL6303.151HLTDCR=1-4,0.105M OHMDCR=2-3,0.27M OHM2ND=CV+15^0TZ0111.0*7.5*12.5ISAT:70A@100CHCME656510Q-221QLISAT:30A@100C2ND=CV+22Y0EZ01DCR=0.17M OHM6.5*6.5*10.0
PVDDIO_P1_PHASE3
Thu Sep 14 16:12:22 2023<NAME_2><NAME_1>MB FABCGT AMDV02223 OF 365
PVDDIO_P1SW_P12V_AUX_PVDDIO_P1_FLT
PVDDIO_P1SW_P12V_AUX_PVDDIO_P1_FLTPVDDCR_CPU1_P1_PVCCPVDDCR_CPU1_P1_PVCC22222322321721821922022222321722222321721721721821922022222321722222321721725V1UF1%5.6C0402SW_PVDDIO_P1_SW3_RCSW_PVDDIO_P1_BOOT3_RSW_PVDDIO_P1_BOOT30402LFCHIP1/16W5.6SW_PVDDIO_P1_BOOT4_RSW_PVDDIO_P1_BOOT41/16W0402LF1%CHIP
0402
PVDDIO_P1 VR PHASE 3&4
SMLFICISL99390FRZ-TR5935C0805X6S22UF16V20%4V22UF20%X6SC08054V22UF20%X6SC0805C0805X6S22UF16V20%X7R10%16V0402SMLF150NHINDC0805X6S22UF16V20%C0805X6S22UF16V20%EMPTY10%560PF50V0402LF1.51%EMPTY1/8WCHIP0402LF05%1/16W4V22UF20%X6SC08054V22UF20%X6SC0805C0805X6S22UF16V20%C0805X6S22UF16V20%X6S10%C040210%0.22UFX7R16V0402IND0.22UH/33ASMLFSMLFIND150NH0402LF05%CHIP1/16W1/8WEMPTY1%1.50402LF10%560PFC040250VEMPTY
X6S10%1UF25VC0402X7R10%0.1UF25VX6S10%2.2UF10VC04020402LF2.21%CHIP1/16WX6S10%2.2UF10VC04021/16WEMPTY1%8.87K0402LFX7R10%0.1UF25V0402X7R10%0.1UF25V0402SMLFICISL99390FRZ-TR5935X6S10%2.2UF10VC04020402LF2.21%CHIP1/16WX6S10%2.2UF10VC04021/16WEMPTY1%8.87K0402LFX7R10%0.1UF25V0402
IND_PVDDIO_P1_CPL3IND_PVDDIO_P1_CPL4IND_PVDDIO_P1_CPL4IND_PVDDIO_P1_CPL0SW_PVDDIO_P1_SW4_RC
SW_PVDDIO_P1_BOOTR3SW_PVDDIO_P1_SW4SW_PVDDIO_P1_SW3SW_PVDDIO_P1_BOOTR4NC_PVDDIO_P1_GL1_3NC_PVDDIO_P1_GL2_3PVDDIO_P1_VOS3PVDDIO_P1_VCC3NC_PVDDIO_P1_DNC3PVDDCR_CPU1_P1_VCCSPVDDIO_P1_LSET3PVDDIO_P1_PWM3PVDDIO_P1_TEMP1PVDDIO_P1_IMON3
PVDDIO_P1_VOS4NC_PVDDIO_P1_GL2_4NC_PVDDIO_P1_GL1_4PVDDIO_P1_LSET4PVDDIO_P1_VCC4NC_PVDDIO_P1_DNC4PVDDCR_CPU1_P1_VCCSPVDDIO_P1_PWM4PVDDIO_P1_TEMP1PVDDIO_P1_IMON4
0.22UF
PL46
1
30
25_29
3
36
10_19
39
34
4
32
40
7_9-20_24
5
37
38
41
6
35
31
33
2
PU52
2
1
PC627_4
2
1
PC637_3
2
1 PC631
4
32
1
PL68
2
1
PC628_3
2
1
PC626_3
2
1 PC177
2
1
PC636_4
2
1 PC633_4
2
1
PC625_4
4
32
1
PL67
PR375
2
1
PR491
2
1 PC176
2
1
PC624_3
2
1 PC622_3
PR373
2
1 PC619_IOP1_3
2
1
PR371
2
1
PR369
2
1 PC620_9
2
1 PC623_4
PR372
2
1 PC618_IOP1_4
2
1
PR370
2
1 PC616
2
1
PR368
2
1
PC635_3
2
1 PC632_3
2
1
PR492
PR374
2
1
PC634_4
2
1
PC629_4
2
1 PC630
2
1 PC617
1
30
25_29
3
36
10_19
39
34
4
32
40
7_9-20_24
5
37
38
41
6
35
31
33
2
PU53
2
1 PC621_10
2 1
PGND2
GL2
GL1
DNC
EN
PGND3
VOS
VIN2
PGND1
SW
LSET
IOUT
TOUT_FLT
PVCC
PHASE
VIN1
BOOT
AGND
VCC
REFIN
PWM
1 4
32
12
1 4
32
PGND2
GL2
GL1
DNC
EN
PGND3
VOS
VIN2
PGND1
SW
LSET
IOUT
TOUT_FLT
PVCC
PHASE
VIN1
BOOT
AGND
VCC
REFIN
PWM
SHEETDATE
DEPARTMENT
SIZE
PROJECT DOCUMENT NUMBER REV
REVIEWER
DESIGNER
123
7 3 2 1 6 5 4
E
A
B
C
E
D
C
B
A
7 6 5 4
D
OUT
IN
BI
OUT
BI
BI
IN
OUT
IN
OUT
IN
C



PMBUS ADDRESS AND CONFIGADDRESS(7-BIT)0X750X4A /3.57K/27K0X4A0/13.7KCONFIG/RMPSINFINEONRENESASVR
TDC=65AEDC=80APC639 = CH12206KB14PC638 = CH3104J1B003RD SOURCE:MPS BOMPC643 = CH11006JB00PC644 = CH5103KEB01PR464=CS23572FB05BOM NOTEPU54 = TBD/RAA229621GNP#HA0MAIN SOURCE:RENESAS BOM2ND SOURCE:INFENEON BOMPU54 = TBD/XDPE19283BPR376 = CS25362FB02PR6 = CS21002FB06PR14,PR13,PR406,PR407 = EMPTYPR408,PR409,PR415 = EMPTYPR384 = CS01002FB07PU54 = TBD/MP2856GUT-0021-ZPC639,PR376,PC638=EMPTYPR13,PR14,PR406,PR407,PR408,PR409 = EMPTYPR388 = CS37502FB05PR604 = CS24992FB07PC8 = CH21006JB10PC644=CH5103KEB01PC643 = CH31004KB17PR464 = CS32702FB03PR6 = CS00002JB13IRM REV1.09PVDD11_S3_P1 SPECFICATIONOUTPUT VOLTAGE=1.1VDC & AC=1.045-1.155VOCP=96A (EDC*1.2)MAX LOAD STEP=25AMAX LOAD RELEASE=35AWORK FREQUENCY=600KHZEFFICIENCY > 90% @TDCDIFFERENTIAL PAIRTRACE WIDTH = 10MILTRACE SPACING = 5MIL
Thu Sep 14 16:12:42 2023<NAME_2><NAME_1>MB FABCGT AMDV02224 OF 365PVDD11_S3_P1 VR CONTROLLER
0402X7R1000PFPVDD11_S3_P11/16W0402LF0402LF33CHIPPVDD11_S3_P1_PMALERT_RPVDD11_S3_P1_PMSCL_RNC_PVDD11_S3_P1_SVTO0 PVDD11_S3_P1_PWM2NC_PVDD11_S3_P1_IMON4PVDD18_S5_P1P3V3_AUXP12V_AUXP5V_AUX
P3V3_AUX
PVDD18_S5_P1
P3V3_AUX15122522522522582
81545421722581
225818382151NC_PVDD11_S3_P1_IMON8NC_PVDD11_S3_P1_PWM8PVDD11_S3_P1_TEMP1PVDD11_S3_P1_ADDR_CFGPVDD11_S3_P1_OCP_N_RNC_PVDD11_S3_P1_IMON6NC_PVDD11_S3_P1_PWM6NC_PVDD11_S3_P1_IMON5NC_PVDD11_S3_P1_PWM5PVDD11_S3_P1_PWM1NC_PVDD11_S3_P1_IMON7PVDD11_S3_P1_VDDIOPVDD11_S3_P1_VINSENPVDD11_S3_P1_VMON
PWRGD_PVDD11_S3_P1_R
NC_PVDD11_S3_P1_PWM7VSENSE_PVDD11_S3_P1_RNC_PVDD11_S3_P1_PWM3NC_PVDD11_S3_P1_PWM4PVDD11_S3_P1_PMSDA_RPVDD11_S3_P1_EN_R
NC_PVDD11_S3_P1_PG1
NC_PVDD11_S3_P1_IMON3PVDD11_S3_P1_RESET_N_RPVDD11_S3_P1_IMON2PVDD11_S3_P1_IMON1SMLFICRAA229621GNP#HA0
EMPTY 0402LF0402LF5%1%1KPVDD11_S3_P1_OCP_N0402LF1/16W1%0.1UF5%
1/16WPWRGD_PVDD11_S3_P1
0402LF10%VSENSE_PVDD11_S3_P1_DPVSENSE_VSS_SENSE_C_P1PVDD11_S3_P1_TEMP0PVDD11_S3_P1_RESET_N
PVDD11_S3_P1_VCCSPVDD11_S3_P1_VCC
0402LF40.2KX7R25V040210%0402LF10K1%CHIP1/16W0402LF1/16W49.91%CHIP
0402LFEMPTY1/16W4.99K1%0402LF0CHIP1/16WX7R10%0.1UF25V0402EMPTY1/16W50V3300PFX7R0402CHIP1/16W1%0402LF1%1/16WCHIP1K0402LF0402LF5%1/16W00402LF1/16W05%CHIP001/16W5%04025%X7R50V5%1000PF040250VEMPTY
X7R10%470PF50V040205%1/16WCHIP 0402LFCHIP05%1/16W 0402LF0402LF05%1/16WEMPTY0402LF05%CHIP 1/16W05%CHIP 1/16W0402LF05%1/16WCHIP5%0402LFCHIP 1/16W00402LF05%EMPTY1/16W1K 1%EMPTY 1/16W0402LF0402LF5%1/16WCHIPX7R10%0.1UF25V0402X7R10%0.1UF25V04026.3V10UF20%X6SX6S10%1UF16VC04020402LF11%1/16WCHIPCHIPPVDD11_S3_P1_EN5%0402LFPVDD11_S3_P1_PMALERT05%49.950VCHIP5%CHIP1/16W5%1/16W00402LFEMPTY1/16W5%CHIP
1000PF0402LFSMB_SCM_2_R2_SCL0SMB_SCM_2_R2_SDACHIPC0402
CHIP1%1/16W13.7K
32
21
37
38
15
40
39
TH
35
36
19
20
17
18
31
22
14
8
7
6
5
4
3
2
1
9
10
16
12
33
11
34
13
23
24
25
26
27
28
29
30
PU54
21
PR393
2
1 PC645
2
1 PC644
2
1 PC95
2
1 PC96
21
PR406
21
PR391
21
PR392
21
PR407
21
PR13
21
PR14
21
PR408
2
1
PR390
21
PR409
21
PR415
2
1 PC643
21
C8641
21
C642
21
R8385
21 R8386
21
R8381
21
R8382
21
R8383
21
R8380
2
1
PR229
2
1 PC639
21
PR384
2
1
R8011
2
1 PC8
21
PR388
PR604
2
1
PR288
21
R8010
21
R8146
2
1
PR6
2
1 PC638
21
PR376
C5010
PR464
CS0
PWM0
TEMP1
EN1||ADDR_CFG
TH_GND
OCP_L
CS2
PWM2
CS3
PWM3
PWM7
CS1
RGND1
VSEN1
VDDIO
TEMP0
VINSEN
VMON||IINSEN
VCCS
PWM6
PG0
PWM1
VSEN0
PWM5
PWM4
PMSDA
RGND0
EN0
nPMALERT
SVD
PG1
CS4
CS5
RESET_L
SVTO
CS6
SVC
PMSCL
SVTI
VCC
CS7
21
2
1
SHEETDATE
DEPARTMENT
SIZE
PROJECT DOCUMENT NUMBER REV
REVIEWER
DESIGNER
123
7 3 2 1 6 5 4
E
A
B
C
E
D
C
B
A
7 6 5 4
D
OUT
OUT
IN
OUT
IN
IN
IN
OUT
OUT
OUT
OUT
OUT
IN
IN
IN
C



ESR=9M OHMPVDD11_S3_P1_PHASE2PVDD11_S3_P1_PHASE1
ISAT:132A@100C10.0*7.7*12.0DCR=0.103M OHM2ND=CVA90^0KZ043RD=CVA90^0KZ08PG2323.900HLT3RD=CVA90^0KZ082ND=CVA90^0KZ04DCR=0.103M OHM7.3*4.3*1.9ESR=10M OHM2ND=CC7390JMZ115.0*5.82ND=CH747LM8822PR332,PR333 = EMPTYPC503_1,PC504_2 = EMPTYPR330,PR331 = CS00002JB13PC503_1,PC504_2 = EMPTYPR387,PR332,PR333 = EMPTY3RD SOURCE:MPS BOMPR328,PR329 = CS00002JB13BOM NOTE
ESR=10M OHMIRIPPLE:5.08A2ND=CC72703MD396.3*8PG2289.101HLT3RD=CV+10G0MZ08ISAT:13A@100C4.5*4.7*4.5DCR:0.105M OHM2ND=CV+10G0MZ04
PR394,PR330,PR331=CS00002JB13PU44,PU45 =AL087000A03/MP87000GMJTH-C11D-ZPU44,PU45 = AL021590000/TDA215902ND SOURCE:INFENEON BOMPU44,PU45 =AL099390004/ISL99390FRZ-TR5935
PG2323.900HLTISAT:132A@100C10.0*7.7*12.0
MAIN SOURCE:RENESAS BOMThu Sep 14 16:12:17 2023<NAME_2><NAME_1>MB FABCGT AMDV02225 OF 365225 224SMLFSMLFX7RPVDD11_S3_P1_PVCCSW_P12V_AUX_PVDD11_S3_P1_FLTPVDD11_S3_P1PVDD11_S3_P1PVDD11_S3_P1
PVDD11_S3_P1_PVCCP3V3_AUXP5V_AUX
PVDD11_S3_P1SW_P12V_AUX_PVDD11_S3_P1_FLTP12V_AUX
PVDD11_S3_P1 VR PHASE 1&2PVDD11_S3_P1_PWM2NC_PVDD11_S3_P1_DNC2PVDD11_S3_P1_VCCS1/16W225224224224225224224225224224
16V20%C080522UFX6S100NH/16A560PFPVDD11_S3_P1_TEMP0ICX6S1/16WCHIP1%1K0402LFC0805X6S20%22UF4VC0805X6S20%22UF4V25V0.1UFX7RC040250V100NF10%X7R90NH/155AIND0.22UFALUM20%390UF2.5VSMLFALUM20%390UF2.5VSMLFALUM20%390UF2.5VSMLFALUM20%390UF2.5VSMLFC0805X6S20%22UF4VSPCAP20%470UFSMLF2.5V2.5V20%SPCAPSMLF470UFSMLF2.5V470UF20%0C0805X6S20%22UF4V90NH/155AINDSMLF0.22UF040216V10%X7R1/16WCHIP5%00402LF
C040250V10%EMPTYC040210V2.2UF10%X6S1/16WEMPTY5%00402LF1/16WCHIP1%2.20402LF0402LF4.87K1%EMPTY 1/16WC040210V2.2UF10%X6S040225V0.1UF10%X7R0402LF1.522UF22UFC040250V560PF10%EMPTY0402LF1.51%EMPTY1/8W
ISL99390FRZ-TR5935ICSMLF
C040210V2.2UF10%X6SCHIP1%2.20402LF0402LF4.87K1%EMPTY 1/16WC040210V2.2UF10%X6S040225V0.1UF10%X7R
1/16WCHIP5%00402LFPVDD11_S3_P1_VOS1SW_PVDD11_S3_P1_PH1
PVDD11_S3_P1_VOS2
SW_PVDD11_S3_P1_SW1NC_PVDD11_S3_P1_GL1_1NC_PVDD11_S3_P1_GL2_1NC_PVDD11_S3_P1_DNC1PVDD11_S3_P1_LSET1PVDD11_S3_P1_IMON1PVDD11_S3_P1_VCCS
SW_PVDD11_S3_P1_SW2_RCNC_PVDD11_S3_P1_GL2_2NC_PVDD11_S3_P1_GL1_2SW_PVDD11_S3_P1_SW2PVDD11_S3_P1_PWM1PVDD11_S3_P1_VCC2PVDD11_S3_P1_IMON2PVDD11_S3_P1_LSET25%1/16W0402LFEMPTYSW_PVDD11_S3_P1_SW1_RC0402X7R16V
SW_PVDD11_S3_P1_PH2C040210%25V1/8W1%X6SC0805ISL99390FRZ-TR5935PVDD11_S3_P1_TEMP0
IND10%SMLF
C0805X7R10%1UF0.1UF25V 16V20%16VSPCAP20%0402X6SX6SC0805X6S22UF16V20%C080520%16V22UFX6SC080516V22UF20%1/16W0402LF1%CHIPSW_PVDD11_S3_P1_BOOT2 SW_PVDD11_S3_P1_BOOT2_RC5.61/16W0402LFCHIP1%SW_PVDD11_S3_P1_BOOT1 SW_PVDD11_S3_P1_BOOT1_RC5.6PVDD11_S3_P1_VCC1040210%THLFCHIP20%270UF1UFC040210%X6S25V10%0.1UF040225VX6SC080520%22UF16VX6SC080522UF20%X6S22UF20%22UFC0805X6S20%22UFOSCON16V16V16V16VC0805 C0805X6S20%16V
PC8007
PC8006
1
30
25_29
3
36
10_19
39
34
4
32
40
7_9-20_24
5
37
38
41
6
35
31
33
2
PU45
2
1 PC512_2
PR395
2
1 PC529_1
2
1 PC526_1
PC511
2
1 PC524
2
1 PC521_1
21
PL542
1
PC519
2
1 PC803
2
1 PC532
2
1 PC531
2
1 PC802
2
1 PC525
21
PR332
2
1 PC27
2
1 PC523_2
21
PL552
1
PC520
21
PR333
2
1 PC517_1
2
1 PC515_1
2
1 PC513_1
21
PR330
2
1 PC315
2
1 PC511_1
PR394
2
1
PR326
2
1 PC505
2
1
PR520
2
1 PC516_2
2
1 PC514_2
2
1 PC255
1
30
25_29
3
36
10_19
39
34
4
32
40
7_9-20_24
5
37
38
41
6
35
31
33
2
PU44
2
1 PC508_11P1_2
2
1
PR327
21
PR329
2
1 PC506
2
1 PC504_2
PR387
21
PL56
2
1 PC522
2
1 PC530
2
1 PC527_2
2
1 PC528
2
1 PC518_2
2
1 PC509_1
2
1 PC507_11P1_1
21
PR328
2
1 PC503_1
2
1 PC510_2
21
PR331
2
1
PR519
PC7003
PGND2
GL2
GL1
DNC
EN
PGND3
VOS
VIN2
PGND1
SW
LSET
IOUT
TOUT_FLT
PVCC
PHASE
VIN1
BOOT
AGND
VCC
REFIN
PWM
1 2
1 2
1 2
PGND2
GL2
GL1
DNC
EN
PGND3
VOS
VIN2
PGND1
SW
LSET
IOUT
TOUT_FLT
PVCC
PHASE
VIN1
BOOT
AGND
VCC
REFIN
PWM
2
1
2
1
2
1
2
1
SHEETDATE
DEPARTMENT
SIZE
PROJECT DOCUMENT NUMBER REV
REVIEWER
DESIGNER
123
7 3 2 1 6 5 4
E
A
B
C
E
D
C
B
A
7 6 5 4
D
OUT
IN
OUT
IN
OUT
IN
OUT
IN
C



IRATED=5A@125C2ND=CX220Z06Z003RD=CX0002200002ND AL053319002/RS53319LR/REEDSEMI3RD AL000548007/TPS548B28RWWR/TIBOM CHANGE R&C TABLE3RD PC20 CHANGE TO CH5222KEB01PC64 CHANGE TO CH13306JB142ND NA1ST
TDC=10AEDC=12A
VOUT=0.6(1+RA/RB)=1.8V
PVDD18_S5_P1 SPECFICATION
2ND=CC7390JMZ11ESR= 10 MOHM5.0*5.8DIFFERENTIAL PAIRTRACE WIDTH = 10MILTRACE SPACING = 5MILNEAR CPU SIDERBPVDD18_S5_P1DCR=5M OHMRA10*10*4DCR=3.3M OHMISAT:25A@100CPCMC104T-1R0MN2ND=CV-10I0MZ00OCP=15A (EDC*1.2)OUTPUT VOLTAGE=1.8VDC =1.76-1.84VAC =+/-30MVMAX LOAD RELEASE=2.5AEFFICIENCY > 85% @TDCIRM REV1.09WORK FREQUENCY=600KHZMAX LOAD STEP=2.5AFCCMBOM NOTE1ST AL008633005/MPQ8633BGLE-C838-Z/MPSFSW=600KHZThu Sep 14 16:12:17 2023<NAME_2><NAME_1>MB FABCGT AMDV02226 OF 365PVDD18_S5_P1_FBPVDD18_S5_P1P3V3_AUXP3V3_AUXP12V_AUX8181 545433C04021UFX6S10%25VX7R04020.1UF25V10%16VX7R04020.22UF10%X6S10%1UF25VC040210%0.1UFEMPTY25V0402PWRGD_PVDD18_S5_R_P150V1000PFCHIPSW_PVDD18_S5_P1_BST_RINDSMLFSW_PVDD18_S5_P1_BST0402LFMPQ8633BGLE-C838-ZSMLF16VPVDD18_S5_P1_EN22UFC080520%X6S22UFX6S16VC080520%20% 20%SW_P12V_AUX_PVDD18_S5_P1_FLTC0805X6S22UF16V 16V22UFX6SC0805 C0805X6S22UF16V20%BLM18SN220TN1D/8000MA0402LF1/16W49.9EMPTY 0.01UF1%100402LFCHIP1/16W1/16W00402LFCHIPVSENSE_PVDD18_S5_P1_DN10K1/16WC04020402CHIP1%5%5%10KCHIP1/16WPVDD18_S5_P1_CSPVDD18_S5_P1_VCCPVDD18_S5_P1_MODEPVDD18_S5_P1_REFPVDD18_SS_P1_RGNDPVDD18_S5_P1_FB_RCVSENSE_PVDD18_S5_P1_DPINDSMLF8.66K1%CHIP1/16W0402LF05%CHIP1/16W0402LF05%0402LF1/16WCHIPIC040225VX7R10%0.022UF25V0.1UF10%X7R04020402LF1%CHIP50VX7R040210%0402LFCHIP10%25V5%22UFC08054VX6SC08054V22UF20%49.9CHIP1%1/16W0402LF20%C0805X6S4V22UF 22UFC0805EMPTY20%4V22UF20%EMPTY4VC0805ALUMSMLF2.5V20%390UF25V0.1UF0402X7R10%0402LF1K1%CHIP1/16W
PVDD18_S5_P1
0402LFPWRGD_PVDD18_S5_P1SW_PVDD18_S5_P1_SW2.220K1.0UH/18A220PF1%X7R20%X6S
PC8003
2
1 PC60
2
1
PC21
2
1 PC87
2
1 PC84
21
PR400
21
PR401
PC6006
21
PR148
21
PC64
2
1 PR147
2
1
PR399
2
1
PC19
21
PR398
21
PL26
2
1 PC20
2
1
PR403
21 R259
2
1
PC89
2
1 PC88
2 1PR402
2
1 PC83
2
1 PC65
2
1
R8009
2
1 PC22
2
1 PC152
2
1 PC150
2
1 PC61
21
PC62
2
1 PC153
21
10
19
5
20
6
9
11_18
4
7
8
3
1
2
PU3
2
1
PR397
2
1
PR8
2
1C675
PC6002
PR8002
PL57
C5016
21
1 2
1 2
VIN2
CS
MODE
TRK_REF
SW
RGND
VCC
AGND
FB
BST
EN
PGND
PGOODVIN1
21
2
1
2
1
2
1
2
1
SHEETDATE
DEPARTMENT
SIZE
PROJECT DOCUMENT NUMBER REV
REVIEWER
DESIGNER
123
7 3 2 1 6 5 4
E
A
B
C
E
D
C
B
A
7 6 5 4
D
OUT
IN
IN
IN
C



Thu Aug 24 10:15:28 2023<NAME_2><NAME_1>MB FABCGT AMDV02227 OF 365Blank
SHEETDATE
DEPARTMENT
SIZE
PROJECT DOCUMENT NUMBER REV
REVIEWER
DESIGNER
123
7 3 2 1 6 5 4
E
A
B
C
E
D
C
B
A
7 6 5 4
D
C



Thu Aug 24 10:15:29 2023<NAME_2><NAME_1>MB FABCGT AMDV02228 OF 365Blank
SHEETDATE
DEPARTMENT
SIZE
PROJECT DOCUMENT NUMBER REV
REVIEWER
DESIGNER
123
7 3 2 1 6 5 4
E
A
B
C
E
D
C
B
A
7 6 5 4
D
C



10 INCH5 INCH
Thu Sep 14 16:13:12 2023<NAME_2><NAME_1>MB FABCGT AMDV02229 OF 365DELTA_L_GND_1DELTA_L_GND_1DELTA_L_GND_1DELTA_L_GND_1DELTA_L_GND_1DELTA_L_GND_1DELTA_L_GND_1DELTA_L_GND_1DELTA_L_GND_1DELTA_L_GND_1DELTA_L_GND_1DELTA_L_GND_1DELTA_L_GND_1DELTA_L_GND_1
DELTA_L_GND_1DELTA_L_GND_1DELTA_L_GND_1DELTA_L_GND_1DELTA_L_GND_1DELTA_L_GND_1DELTA_L_GND_1DELTA_L_GND_1DELTA_L_GND_1DELTA_L_GND_1DELTA_L_GND_1
DELTA_L_GND_1DELTA_L_GND_1DELTA_L_GND_1DELTA_L_GND_1DELTA_L_GND_1DELTA_L_GND_1DELTA_L_GND_1EMPTYDELTA_L_85_10INCH_IN4_DNDELTA_L_85_10INCH_IN5_DNDELTA_L_85_10INCH_IN5_DPDELTA_L_85_10INCH_IN4_DPSMLFSMLFSMLFDELTA_L_85_5INCH_IN3_DPDELTA_L_85_5INCH_IN3_DNDELTA-L 4.0DELTA_L_85_10INCH_IN6_DNDELTA_L_85_10INCH_IN6_DPDELTA-L 4.0EMPTYSMLFDELTA-L 4.0EMPTYSMLFDELTA-L 4.0EMPTYEMPTYSMLFEMPTYDELTA-L 4.0SMLFSMLFDELTA-L 4.0EMPTYSMLFDELTA-L 4.0EMPTYDELTA-L 4.0SMLFDELTA_L_85_10INCH_IN2_DNDELTA_L_85_10INCH_IN2_DPSMLFDELTA-L 4.0EMPTYSMLFEMPTYDELTA-L 4.0SMLFDELTA_L_85_10INCH_IN1_DPDELTA_L_85_10INCH_IN1_DNSMLFDELTA-L 4.0EMPTYEMPTYDELTA-L 4.0SMLFDELTA_L_85_10INCH_TOP_DPDELTA_L_85_10INCH_TOP_DN
EMPTYDELTA_L_85_5INCH_IN6_DNDELTA_L_85_5INCH_IN6_DPDELTA-L 4.0EMPTYSMLFEMPTYSMLFEMPTYDELTA_L_85_5INCH_IN2_DPDELTA_L_85_5INCH_IN2_DNDELTA_L_85_5INCH_IN1_DPDELTA_L_85_5INCH_IN1_DNDELTA_L_85_5INCH_BOT_DPDELTA_L_85_5INCH_BOT_DNSMLFEMPTYDELTA_L_85_5INCH_TOP_DP
DELTA-L
DELTA-L 4.0SMLFDELTA-L 4.0EMPTYEMPTYSMLFDELTA-L 4.0SMLFDELTA-L 4.0EMPTYDELTA-L 4.0EMPTYEMPTYDELTA-L 4.0SMLFSMLFDELTA-L 4.0EMPTYEMPTYSMLFSMLFDELTA-L 4.0DELTA-L 4.0DELTA_L_85_5INCH_IN4_DNDELTA_L_85_5INCH_IN4_DPDELTA_L_85_5INCH_IN5_DPDELTA_L_85_5INCH_IN5_DNDELTA-L 4.0SMLFDELTA-L 4.0EMPTYDELTA-L 4.0DELTA-L 4.0EMPTYSMLF
DELTA_L_85_5INCH_TOP_DNSMLFDELTA-L 4.0EMPTYSMLFDELTA-L 4.0EMPTYEMPTYDELTA-L 4.0SMLFSMLFDELTA-L 4.0EMPTYDELTA_L_85_10INCH_BOT_DPDELTA_L_85_10INCH_BOT_DNEMPTYDELTA-L 4.0SMLFDELTA-L 4.0EMPTYDELTA_L_85_10INCH_IN3_DPDELTA_L_85_10INCH_IN3_DN
32
13 2
1
32
13 2
1
32
13 2
1
32
13 2
1
32
13 2
1
32
13 2
1
32
13 2
1
32
13 2
1
32
13 2
1
32
13 2
1
32
13 2
1
32
13 2
1
32
13 2
1
32
13 2
1
32
13 2
1
32
13 2
1
J119
J118
J80
J79
J78
J77
J76
J75
J115
J114
J8068
J8067
J66
J65
J64
J63
1_P
3_G2_N1_P
3_G 2_N
1_P
3_G2_N1_P
3_G 2_N
1_P
3_G2_N1_P
3_G 2_N
1_P
3_G2_N1_P
3_G 2_N
1_P
3_G2_N1_P
3_G 2_N
1_P
3_G2_N1_P
3_G 2_N
1_P
3_G2_N1_P
3_G 2_N
1_P
3_G2_N1_P
3_G 2_N
1_P
3_G2_N1_P
3_G 2_N
1_P
3_G2_N1_P
3_G 2_N
1_P
3_G2_N1_P
3_G 2_N
1_P
3_G2_N1_P
3_G 2_N
1_P
3_G2_N1_P
3_G 2_N
1_P
3_G2_N1_P
3_G 2_N
1_P
3_G2_N1_P
3_G 2_N
1_P
3_G2_N1_P
3_G 2_N
J121J120J86J85J84J83J82J81
J117J116J74J73J72J71J70J8069
SHEETDATE
DEPARTMENT
SIZE
PROJECT DOCUMENT NUMBER REV
REVIEWER
DESIGNER
123
7 3 2 1 6 5 4
E
A
B
C
E
D
C
B
A
7 6 5 4
D
C



GND_C8D4B8
HOLE_C10D5-6B10_NPBHOLE1247(M.2)TOOLING HOLEHOLE_DUMMY50HOLE372(GUIDE PIN)HOLE 596HOLE_R4-2X5D2B4_IX0-1T_NPM_RB
GND_HOLE514(STD)P3V3_AUX HS HOLEVR HS HOLEHOLE1187 (E1S SCREW HOLE)HOLE_OB6-4X8OBD3-2X4-8B6-4X8N_RO6X7-6_NPMHSC MODULE CONN HOLEHOLE1248 (M.2 LATCH HOLE)HOLE_C4-5D3-8B8I5-6_RO6-6_NPT_RBRETIMER HS HOLERT HS HOLE WILL DEFINE IN DXF/EMNHOLE_D10NHOLE300 (CPU HS HOLE)GND_HOLE140 (HANDLE)ADD FOR RETIMER VRThu Sep 14 16:12:43 2023<NAME_2><NAME_1>MB FABCGT AMDV02230 OF 365THEMPTYTHEMPTYEMPTYTHTHEMPTYTH
THTHTHEMPTYEMPTYEMPTYTHEMPTYTHEMPTYTHEMPTYTHEMPTYTHTHTHEMPTYTHEMPTY EMPTYTHEMPTYTHEMPTYTHEMPTYTHEMPTYTHEMPTYEMPTYTHTHTH THEMPTYTH THTHEMPTYTHEMPTYTHEMPTYTHEMPTYTHTHEMPTY EMPTYTHEMPTYEMPTYTHTHEMPTYEMPTYTH IOTHLFCONN1_10165288-101LFIOTHEMPTYTHTHEMPTYEMPTYEMPTYEMPTYEMPTYTHEMPTYTHEMPTYEMPTYTH THEMPTYTHTH
HOLEEMPTYTHTHEMPTYTHEMPTYEMPTY
THTHTHEMPTY
EMPTYTHTHTHEMPTYEMPTYTHTHLFCONN1_10165288-101LFEMPTYEMPTY
THEMPTYTHEMPTYTHTHEMPTYTHEMPTYEMPTYTHEMPTYTHEMPTYEMPTYEMPTYTHEMPTYEMPTYEMPTYEMPTYTHEMPTYTHEMPTY
GND5
GND6 GND2
GND3
GND5
GND6 GND2
GND3
GND5
GND6 GND2
GND3
GND5
GND6 GND2
GND3
GND5
GND6 GND2
GND3
GND7GND8GND9GND4GND7GND8GND9GND4GND7GND8GND9GND4GND7GND8GND9GND4GND7GND8GND9GND4
H3 H5 H12H10H8
H2
H6001H6000
1
H11
1
H13
1
H54
1
H50
1
H49
1
H44
1
H43
1
H37
1
H33
1
H38
1
H34
1
H8028
1
H22
1
H8027
1
H21
1
H53
1 1 111
1
1
11
1
1
1
1
1
1
1
1
1
1
1
1
1
1
1
1
1
1
1
1
6
5 3
26
5 3
2
11
1
SCR_H1SCR_H1
1
11
11
1
1
6
5 3
26
5 3
26
5 3
2
11
98749874987498749874
H6002
H90H128
H106
H105
H104
H103
H102
H101
H100
H99
H98
H97
H96
H95
H94
H93
H92
H91
H89
H88
H87
H86
H112H111
H126
J123J122
H127
H32H31
H75H74
H125
H124
H30H29H28
H115
H27
H114H113
H77H76
1
11
11
1
1
1
1
1
1
1
11
1 1 1
1
1
1
1
11
1111
1 1 111
1
1
11
1
1
1
1
1
1
1
1
1
1
1
1
1
1
1
1
1
1
1
1
1
11
1
NC1NC1
1 1111
SHEETDATE
DEPARTMENT
SIZE
PROJECT DOCUMENT NUMBER REV
REVIEWER
DESIGNER
123
7 3 2 1 6 5 4
E
A
B
C
E
D
C
B
A
7 6 5 4
D
C



Thu Aug 24 10:15:31 2023<NAME_2><NAME_1>MB FABCGT AMDV02231 OF 365Blank
SHEETDATE
DEPARTMENT
SIZE
PROJECT DOCUMENT NUMBER REV
REVIEWER
DESIGNER
123
7 3 2 1 6 5 4
E
A
B
C
E
D
C
B
A
7 6 5 4
D
C



Thu Aug 24 10:15:32 2023<NAME_2><NAME_1>MB FABCGT AMDV02232 OF 365Blank
SHEETDATE
DEPARTMENT
SIZE
PROJECT DOCUMENT NUMBER REV
REVIEWER
DESIGNER
123
7 3 2 1 6 5 4
E
A
B
C
E
D
C
B
A
7 6 5 4
D
C



ADDRESS: 0XD4(8-BIT) / 0X6A(7-BIT)20 MATO GPU FPGATO BMC13 MA
Thu Sep 14 16:12:33 2023<NAME_2><NAME_1>MB FABCGT AMDV02233 OF 36574LVC1G32GW0402LFEMPTY1/16W0402LFGPU_FPGA_READY_N
VFG_3P3A_CLK_GENP3V3_AUXP3V3_AUXP3V3_AUX
VFG3P3_CLK_GENP3V3_AUX
P3V3_AUXP3V3_AUXVFG3P3_CLK_GENP3V3_AUXVFG_3P3A_CLK_GEN
234122111 11223480127 23423415080111234112 1501222342341511512349FGL0251DKILFTICSMLF0402 0402X6S10%0.1UFX7R0402C08050.1PNPOC04021K1KCHIP1/16W0402LF1%
PLACE CLOSE TO U247 ALL VDD PINSFCM2012KF-601T/0.5ASMLFIND
ICP3V3_PWRGD_CLKGENCLK_100M_GPU_FPGA_DPCLK_GEN2_GPU_FPGA_OE_OR_NGPU_FPGA_READY_R_NCLK_GEN2_GPU_FPGA_OE_N CLK_GEN2_GPU_FPGA_OE_R2_NCLK-GEN(NON SSC)
10%25VX7R0402LFCHIP1/16W1%10KCHIP0402LF10K1%0402LF1%1/16WEMPTY005%CHIP00402LF1/16W10K1%EMPTYCHIP1/16W0402LF1%
11%10%X7R10%X7R10%25V25V0.1UFX7R10%040225V10%X6S10UF5%01/16WCHIP040210%X7R0.1UF25VCHIP05%1/16W4.7K1%05%CHIP0CHIPCLK_GEN2_SMB_SADRCHIPCHIP0.1UF
SMLF10K1/16WFG_SS_EN10KCLK_100M_BMC_RC_DNCHIP1/16W50V0.1PNPO4.7PF50V4.7PFCLK_GEN2_BMC_RC_OE_NCLK_GEN2_GPU_FPGA_OE_OR_NC04021%1/16WCHIP0402LFCLK_GEN2_XTAL_IN_RMISCSMLF0402LF25MHZCLK_100M_BMC_RC_DPCHIP00402LF0CHIP25V0.1UFCLK_100M_GPU_FPGA_DN25V25VC04021/16W 0402LF1UF0402LF1/16W0.1UF0402FG_SS_ENP3V3_PWRGD_CLKGENCLK_GEN2_GPU_OE_NCLK_100M_GPU_FPGA_DN_RCLK_100M_GPU_FPGA_DP_RCLK_100M_BMC_RC_DN_RCLK_100M_BMC_RC_DP_RCLK_GEN2_BMC_RC_OE_R3_NSMB_HOST_CLK_GEN2_3V3AUX_SDASMB_HOST_CLK_GEN2_3V3AUX_SCLCLK_GEN2_SMB_SADRCLK_GEN2_XTAL_OUTCLK_GEN2_XTAL_IN
C94C71
C1884
R4080
R4081
R4082
R3335
R3336
R3337
R3338
R4078
R4079
R4077
C95C1889C1886
R4501
C1882
R4075
R4076
R3326
R3327
1
2
4
19
12
3
7
16
20
11
25
9
8
24
5
6
15
21
10
18
17
14
13
23
22
21
5
4
2
1
3
31
42
U247
L17
U248
Y8003
TH_GND
GNDXTAL
^vSS_EN_tri
^CKPWRGD_PD#
GND_21
VDD3.3_20
vOE1#
DIF1#
DIF1
VDDA3.3
GNDA
DIF0#
DIF0
vOE0#
VDD3.3_11
GND_10
SDATA_3.3
SCLK_3.3
VDDDIG3.3
GNDDIG
GNDREF
vSADR||REF3.3
VDDXTAL3.3
X2
XIN||CLKIN_25
1 2
GND
O
I1
VCC
I0
X2
G2G1
X1
2
1
2
1
2
1
R3322
2
1
2
1C97
2
1
2
1
2
1
2
1
21 21
21 21
2
1
2
1
21
2
1
2
1
2
1
2
1C2257
2
1C1883
21
2
1
21 21
2
1
21
21
DESIGN NOTE:
SHEETDATE
DEPARTMENT
SIZE
PROJECT DOCUMENT NUMBER REV
REVIEWER
DESIGNER
123
7 3 2 1 6 5 4
E
A
B
C
E
D
C
B
A
7 6 5 4
D
IN
OUT
OUTOUT
OUTOUT
OUTOUTOUTIN
IN
OUTBI
IN
IN
IN
IN
R4521
R4514
C



USB_HUB_I2C ONLY FOR EEPROM.HUB ADDRESS : 0X2C
Thu Sep 14 16:12:30 2023<NAME_2><NAME_1>MB FABCGT AMDV02234 OF 365P3V3_AUXP3V3_AUXP3V3_AUXP3V3_AUXP3V3_AUX235246176178
235235235235
122
235150235235235122
1502352352352352350402LFUSB2 BOM1USB_HUB_PSELF25V1/16W1%CHIP1/16WRST_USB_HUB_N10%CHIPC0402
0CHIP1UF25V10%C0402EMPTYEMPTY10%25V0.1UF1/16WUSB2 BOM10402LFEMPTYNC_USB_HUB_DP4NC_USB_HUB_DM3NC_USB_HUB_DP30402LFEMPTY5%USB2 BOM2EMPTY
USB2_HUB_SWB_DNCHIPUSB2_HUB_SWB_DP00402LFCHIP5%0EMPTY49.9USB2 BOM1USB_HUB_OVCUR1USB2 BOM11/16WEMPTY1%10K1%10KC0402680X6SC04020402X6S0.1%USB2 BOM1100K1%1/16WCHIP0402LF1%CHIP0402LFUSB_HUB_OVCUR110%25V0.1UF10UFX6S6.3V20%0.1UF0402X7R25V10%0.1UF25V10%0402X7R25V1UFC040225V10%X7R0402X7R10%USB2 BOM110%25V49.9 49.9EMPTYEMPTYUSB2 BOM115PFNC_USB_HUB_DP2
USB2_HUB_BUF_SWB_DN
NC_USB_HUB_DM2USB_HUB_OVCUR2
USB HUB (BMC TO EXAMAX)0402LFCHIP0402LF10%EMPTYC040225V0402LF5%EMPTYC0402
C0G0402SMLF00402LFSMLFIC12MHZUSB2 BOM15%50VCHIPUSB2_P0_R_DN05%1/16W50V15PF0402MISCC0GUSB2_HOST_BMC_B_DPUSB2 BOM100USB2 BOM10402LFNC_USB_HUB_DM4X6SP3V3_AUX_USB_HUB0CHIP10%X7RGL852G-OHY600.1UF 0.1UF25V04020402LFEMPTY1%1/16WUSB_HUB_OVCUR4USB_HUB_OVCUR310K10KEMPTYUSB_HUB_OVCUR2EMPTY10KUSB2 BOM110KEMPTYUSB2 BOM1049.90402LFUSB2 BOM1USB2 BOM2EMPTY0USB2_HUB_BUF_SWB_DPSHORT THE NET USB2_HUB_SWB_R_DP/DN TO USB2_HUB_BUF_SWB_R_DP/DNTP_USB2_ENA_HS0.1UF3.9K1/16WTP_USB2_CDPD_U5201_RSTN25V10%USB2 BOM20 R2790/R3651,R3652/R2791 CO-LAYOUTUSB2_HOST_BMC_B_DNUSB2_HOST_BMC_B_BUF_DNUSB2_HOST_BMC_B_BUF_DPUSB2 BOM2EMPTYUSB2 BOM2SMLFTUSB211IRWBREMPTYPD_U5201_EQUSB2 BOM2PD_U5201_VREGUSB2 BOM2USB2 BOM20.1UFEMPTYC0402USB2_HUB_BUF_SWB_R_DPUSB2_HUB_BUF_SWB_R_DNUSB2 BOM2TP_USB2_TESTUSB2_HUB_BUF_SWB_R_DNUSB2_HUB_BUF_SWB_R_DP0R2788/R2786,R2789/R2787 CO-LAYOUTUSB2 BOM2USB2 BOM10402LFCHIPUSB2_P0_R_DPUSB_HUB_XTAL_OUTNC_USB_HUB_SDAUSB_HUB_TESTUSB_HUB_XTAL_INCHIP0402LFUSB2 BOM1USB2_HUB_SWB_DPUSB2_HUB_SWB_DN1UFUSB2 BOM1USB2 BOM1USB2 BOM1USB2 BOM1USB2 BOM1USB2 BOM1USB2 BOM10402LFUSB2 BOM1USB2 BOM147KEMPTYUSB_HUB_PGANGUSB_HUB_PSELF0USB_HUB_DVDD0402LF1/16W0402LFUSB_HUB_RREFUSB_HUB_OVCUR40402LFCHIP10KUSB2 BOM1USB2 BOM11/16WUSB2 BOM1USB_HUB_OVCUR30402LF1/16W1UFCHIP33.21%RST_USB_HUB_R_N
235235235235
R4419
R3665
C2038 C2031 C2032 C2033
R3653
R2789
R2791R2790
C2029 C2030
R4482 R4483
R4420
R3661
R3666
R3659
R3658
R3657
R3656
R3662
C2039 C2040
R3655
R3660
C2035C2034
R2788
31
42
11
10
28
27
TH
18
26
8
17
22
23
19
20
24
25
21
16
13
7
4
2
15
12
6
3
1
14
9
5
Y8004
R3654
21R3651 21R3652
U268
2
1C5234
21R5234 21R5236
2
1C5229
2
1C5236
U5201
R5238
2
1C5232
R2786
R2787
GND
EQ
D2PD1P
D1M
CD
ENA_HS
VCCTEST
VREG
D2M
RSTN
X2
G2G1
X1
DM4
DP4
DM3
DP3
DM2
DP2
DM1
DP1
DM0
DP0
RREF
PSELF
PGANG
RESET#
OVCUR4#
OVCUR3#
OVCUR2#||SMD
OVCUR1#||SMC
TH
DVDD
AVDD
AVDD
AVDD
V33
V5 SDA
TEST||SCL
X2
X1
2
1
2
1
2
1
2
1
2
1
2
1
21
21
21
21
212
1
2
1 2
1
21
2
1
2
1
2
1
21
2
1
2
1
2
1
2
1
2
1
2
1
2
1
2
1
2
1
2
1
2
1
2
1
21 21
CAD NOTE:
CAD NOTE:
CAD NOTE: 21
11123
5 106 9
7821
4
SHEETDATE
DEPARTMENT
SIZE
PROJECT DOCUMENT NUMBER REV
REVIEWER
DESIGNER
123
7 3 2 1 6 5 4
E
A
B
C
E
D
C
B
A
7 6 5 4
D
BIBIBIBI
OUT
OUT
OUT
OUT
OUT
IN
ININININ
IN
BIBI
BIBI
R3664
R3663
C2041
C



ADDRESS : 0X90 (8-BIT) / 0X48 (7-BIT)ADDRESS : 0X90 (8-BIT) / 0X48 (7-BIT)ADDRESS : 0X90 (8-BIT) / 0X48 (7-BIT)ADDRESS : 0X90 (8-BIT) / 0X48 (7-BIT)
Thu Sep 14 16:12:30 2023<NAME_2><NAME_1>MB FABCGT AMDV02235 OF 365
P3V3_AUX
P3V3_AUXP3V3_AUXP3V3_AUX
P3V3_AUXP3V3_AUXP3V3_AUXP3V3_AUXP3V3_AUXP3V3_AUXP3V3_AUXP3V3_AUX
2368525323685253253253272
23685253
253272253
25323685SMLFX7R10%LM75BDICFM_G751_0_ALERT_N10%0402LFSMB_LM75_0_3V3AUX_SCL_R1SMLFU271_1_ADD1U271_1_ADD01/16W1%1K0402LF1/16W1K0.1UF0.1UF1%1/16WEMPTY0402LFEMPTY1/16W1%FM_THERMAL_ALERT_N0402LFU272_2_ADD1U272_2_ADD0
040225V10%X7R33.2CHIP1/16W1%0402LF33.21%CHIP1/16WCHIP0 CHIP0402LF1K1/16W1%1K0402LFCHIP0402LF1/16W1K1%1K1%CHIP0402LFEMPTY1/16W1K0402LF1%EMPTY1%1/16W1KEMPTY0402LFCHIP0402LF1/16W1K1%1%CHIP0402LF1K1/16W1%1/16W1KEMPTY0402LFCHIP0402LF1K1/16W1%0402X7R25V1/16W CHIP1%33.2 0402LF00402LFCHIPCHIP 33.21%1/16W 0402LF1%1/16W CHIP 0402LF33.2CHIP00402LFCHIP 33.21%1/16W 0402LF25V1%1/16W1K0402LFCHIP0402LFEMPTY1K1/16W1%1%1/16W1K0402LFCHIP1%1K1/16W0402LFCHIP0402LFEMPTY1K1/16W1%EMPTY1%0402LF1K1/16WCHIP 0402LF33.21/16W1%CHIP 0402LF033.2 0402LF1%CHIP1/16W25VX7R040210%0.1UFCHIP0402LF1K1/16W1%1/16W1K1%0402LFEMPTYCHIP0402LF1K1/16W1%CHIP0402LF1/16W1K1%1%1/16W1K0402LFEMPTY1/16W1K0402LF1%EMPTY200K1%1/16WEMPTY0402LFEMPTY1/16W0402LF1%200K200K1%0402LF1/16WEMPTY1%1/16WCHIP0402LF200KSMB_LM75_1_3V3AUX_SCL
TEMP SENSOR - LM75FM_THERMAL_ALERT_NSMB_LM75_2_3V3AUX_SCLSMB_LM75_2_3V3AUX_SDASMB_LM75_0_3V3AUX_SDASMB_LM75_1_3V3AUX_SDA_R1
FM_THERMAL_ALERT_NFM_G751_1_ALERT_NSMB_LM75_1_3V3AUX_SCL_R1SMB_LM75_3_3V3AUX_SDA
SMB_LM75_0_3V3AUX_SCLSMB_LM75_1_3V3AUX_SDAFM_LM75_2_ALERT_NSMB_LM75_2_3V3AUX_SDA_R1FM_LM75_3_ALERT_NSMB_LM75_3_3V3AUX_SCL_R1SMB_LM75_3_3V3AUX_SDA_R1SMB_LM75_3_3V3AUX_SCLICU273_3_ADD2SMLFICLM75BDU272_2_ADD2ICFM_THERMAL_ALERT_NLM75BDSMLFSMB_LM75_0_3V3AUX_SDA_R1U270_0_ADD0U270_0_ADD1U270_0_ADD2U271_1_ADD2SMB_LM75_2_3V3AUX_SCL_R1LM75BD0.1UF0402U273_3_ADD0U273_3_ADD1
R4209
R4208
R4210
R4211
R4200R4192
R4201R4193
R4184
R4185
R3554
R4212
R3553
R4202R4194
R4203R4195
R4186
R4187
R4181
R4213
R4178
R4179
R4214
R4182
R4189
R4188
R4197 R4205
R4196 R4204
R4190
R4191
R4206
R4207
R4198
R4199
R4215
R4183
R4180
81
2
3
4 5
6
7
81
2
3
4 5
6
7
81
2
3
4 5
6
7
81
2
3
4 5
6
7
U273
U272
U271
U270
VCC
A0
A1
A2GND
OS
SCL
SDA
VCC
A0
A1
A2GND
OS
SCL
SDA
VCC
A0
A1
A2GND
OS
SCL
SDA
VCC
A0
A1
A2GND
OS
SCL
SDA
2
1
2
1
2
1
2
1
2
1
2
1
2
1
2
1
2
1
2
1
2
1
21
21
21
2
1
2
1
2
1
2
1
2
1
2
1
2
1
21
21
21
21
21
21
2
1
2
1
2
1
2
1
2
1
2
1
2
1
2
1
2
1
2
1
2
1
2
1
2
1
21
21
21
2
1
SHEETDATE
DEPARTMENT
SIZE
PROJECT DOCUMENT NUMBER REV
REVIEWER
DESIGNER
123
7 3 2 1 6 5 4
E
A
B
C
E
D
C
B
A
7 6 5 4
D
BI
IN
OUT
OUT
OUT
OUT
IN
BI
IN
BI
BI
IN
C31
C32
C73
C2010
C



ADDRESS : 0X84 (8-BIT)0X42 (7-BIT)ADDRESS : 0X82 (8-BIT)0X41 (7-BIT)
Thu Sep 14 16:12:30 2023<NAME_2><NAME_1>MB FABCGT AMDV02236 OF 365
0402LFP3V3_AUX0402LFCHIP1/16W0402LFSMB_INA230_1_3V3AUX_SDA_R1EMPTY1/16WPOWER MONITOR WILL CHANGE TO AL000230001VSENSE_P3V3_INA230_1_INPVSENSE_P3V3_INA230_1_INNP3V3_AUX04021%P3V3_OCP_SFF_RP3V3_AUXP3V3_OCP_SFF P3V3_OCP_SFF_RP3V3_AUX
P3V3_E1S_0_RP3V3_E1S_0
P3V3_AUX
P3V3_E1S_0_R35882358822522522522521KCHIP0E1S_0_P3V3_P12V_ADC_R_ALERTNC_INA230_2_NC5NC_INA230_2_NC4NC_INA230_2_NC1E1S_0_P3V3_ADC_ALERT_ROCP_SFF_P3V3_P12V_ADC_R_ALERTOCP_SFF_P3V3_ADC_ALERT_R
POWER MONITOR (1/4)
1KCHIP1/16W1%1%NC_INA230_1_NC5NC_INA230_1_NC4NC_INA230_1_NC3NC_INA230_1_NC20402LFSMB_INA230_1_3V3AUX_SCL_R SMB_INA230_1_3V3AUX_SCL_R1CHIP1/16W0402LF0402EMPTY1/16WCHIPSMLFISL28022FRZ-TSMB_INA230_2_3V3AUX_SDA_R1SMB_INA230_2_3V3AUX_SCL_R1NC_INA230_2_NC01/16W10X7RIC04020402LFX7R10%1%4.7KISL28022FRZ-T
VSENSE_P3V3_INA230_2_INNVSENSE_P3V3_INA230_2_INPINA230_2_A1INA230_1_A1NC_INA230_1_NC0NC_INA230_1_NC1NC_INA230_2_NC205%2W0.0021%CHIP2512LFX7R25V10%04020.1UF0402LF4.7K 1/16W1%CHIP1%0402LFEMPTY1/16W4.7K1%0402LFCHIP25V10%0.1UF04021/16W0402LF1%1010%0.1UF25V2512LFCHIP1%0.0022W1/16WX7R10%X7R040210%25V0.1UF100402LF4.7K0402LF0CHIPX7R25V0.1UFICSMLFINA230_2_A0CHIP1/16W1%1%CHIP4.7K4.7K1/16W1%SMB_INA230_1_3V3AUX_SDA_R25V0.1UF0402LF05%CHIPCHIP5%0
CHIPSMB_INA230_2_3V3AUX_SCL_RSMB_INA230_2_3V3AUX_SDA_R05%CHIP0402LF1/16WCHIP5%0101/16WNC_INA230_2_NC3
0402LF1%CHIP 0402LF1/16W0402LFINA230_1_A0
R3752
R3563
R3767
R3763
R3764
R3760
R3758
R3645
R3603
R3602
R3617
R3616
13
12
9
11
TH
4
5
16
15
14
8
7
6
10
3
1
2
13
12
9
11
TH
4
5
16
15
14
8
7
6
10
3
1
2
U276
U266
TH_GND
GND
NC5
NC4
NC3
NC2
NC1
NC0
EXT_CLK||INT
VINM
VINP
VBUS
SDA||SMBDAT
SCL|||SMBCLK
A0
A1
VCC
TH_GND
GND
NC5
NC4
NC3
NC2
NC1
NC0
EXT_CLK||INT
VINM
VINP
VBUS
SDA||SMBDAT
SCL|||SMBCLK
A0
A1
VCC
21R3754 21R3756
21R3601
21R3600
2
1
2
1
2
1
21
2
1
21
21
21 2
1
21
2
1
21
21
2
1
2
1
2
1
2
1
21
21
21 21
2
1
21
BOM NOTE:
SHEETDATE
DEPARTMENT
SIZE
PROJECT DOCUMENT NUMBER REV
REVIEWER
DESIGNER
123
7 3 2 1 6 5 4
E
A
B
C
E
D
C
B
A
7 6 5 4
D BIIN
OUT
BIIN
OUT
R4094
R4093
R3751
C2069
C2071
C2067
R3627 R3628
C2027
C2024
C2015
C



ADDRESS : 0X86 (8-BIT)0X43 (7-BIT)ADDRESS : 0X88 (8-BIT)0X44 (7-BIT)0X45 (7-BIT)ADDRESS : 0X8A (8-BIT)Thu Sep 14 16:12:31 2023<NAME_2><NAME_1>MB FABCGT AMDV02237 OF 365
P3V3_AUXM2_0_P3V3_ADC_ALERTP3V3P3V3_AUX
P3V3_AUX
P12V_SCM_RP3V3_M2_0P3V3P3V3_AUXP3V3_OCP_V3_2_RP3V3_OCP_V3_2P3V3_AUXP3V3_AUXP12V_SCM_RP12V_SCM
P3V3_OCP_V3_2_R
P3V3_AUXP3V3_AUX3588282252252252252252252
82POWER MONITOR WILL CHANGE TO AL0002300010402LFOCP_V3_2_P3V3_P12V_ADC_R_ALERT0CHIPOCP_V3_2_P3V3_ADC_ALERT_RNC_INA230_3_NC0NC_INA230_3_NC1NC_INA230_3_NC2NC_INA230_3_NC3NC_INA230_3_NC4NC_INA230_3_NC5
POWER MONITOR (2/4)SMB_INA230_5_3V3AUX_SDA_RSMB_INA230_5_3V3AUX_SCL_R
1K1%0402LF1/16WCHIP1K1/16W1%0402LFCHIP1K0402LF1%1/16WCHIP
CHIPSMB_INA230_3_3V3AUX_SCL_R1
0402LFNC_INA230_5_NC2NC_INA230_5_NC1P12V_SCM_ADC_ALERT_RISL28022FRZ-T01/16WEMPTY1/16WVSENSE_P12V_INA230_3_INN10%0402LFVSENSE_P12V_INA230_3_INP
NC_INA230_5_NC5NC_INA230_5_NC4NC_INA230_5_NC3NC_INA230_5_NC004021/16W4.7K0402LFINA230_5_A1M2_0_P3V3_ADC_ALERT_RNC_INA230_4_NC0NC_INA230_4_NC1SMB_INA230_4_3V3AUX_SDA_R1SMB_INA230_4_3V3AUX_SCL_R1ISL28022FRZ-TSMLFVSENSE_P12V_INA230_4_INPVSENSE_P12V_INA230_4_INNICCHIPINA230_4_A1INA230_4_A00402LFCHIP1/16W1%4.7KCHIPCHIPCHIP1/16W
0402LF05%CHIP1/16WSMB_INA230_5_3V3AUX_SCL_R1CHIP5%0SMB_INA230_5_3V3AUX_SDA_R11/16WSMB_INA230_4_3V3AUX_SCL_RSMB_INA230_4_3V3AUX_SDA_R1%00402LFCHIP5%010SMB_INA230_3_3V3AUX_SDA_RSMB_INA230_3_3V3AUX_SCL_RNC_INA230_4_NC3P12V_SCM_ADC_ALERTVSENSE_P12V_INA230_5_INNVSENSE_P12V_INA230_5_INP
2W1%0.002CHIP2512LFX7R040210%25V0.1UF10 1%1/16W10 1%0.1UF25VX7R04021%EMPTY4.7K 1/16W1%4.7K 1/16W CHIP1/16W00402LF5%X7R10%25V0.1UF0402ICSMLF
CHIP2512LF2W0.0021%CHIP2W0.0021%CHIP1%1/16W1%4.7KCHIP0402LF0402LFEMPTY1%
0.1UF25V10%X7R040225V0.1UFSMLF0402LF4.7K1%EMPTYX7R0.1UFCHIP04.7K1%0402LFEMPTY0402LF1%CHIP0402LF101%1/16W10%25VX7R0.1UF0402IC1%4.7K040210%25V00402LFCHIP4.7K CHIPCHIP10 1%CHIP0402X7R10%25V0.1UF0402LF0402LF1/16W1%1/16W1/16W1/16W1/16W0402LF0402LF2512LF0402LF0402LF0402LF5%05%0402X7R10%1/16WINA230_3_A0INA230_3_A15%CHIP1/16W0402LFISL28022FRZ-T0.1UF4.7KX7RNC_INA230_4_NC4NC_INA230_4_NC225V10%INA230_5_A010CHIPNC_INA230_4_NC5SMB_INA230_3_3V3AUX_SDA_R1
R3559
R3561
R3560
R3571
R3570
R3609
R3608
R3620
R3612
R3613
R3578
R3579
R3610
R3611
R3574
R3575
13
12
9
11
TH
4
5
16
15
14
8
7
6
10
3
1
2
13
12
9
11
TH
4
5
16
15
14
8
7
6
10
3
1
2
13
12
9
11
TH
4
5
16
15
14
8
7
6
10
3
1
2
U263
U265
U264
TH_GND
GND
NC5
NC4
NC3
NC2
NC1
NC0
EXT_CLK||INT
VINM
VINP
VBUS
SDA||SMBDAT
SCL|||SMBCLK
A0
A1
VCC
TH_GND
GND
NC5
NC4
NC3
NC2
NC1
NC0
EXT_CLK||INT
VINM
VINP
VBUS
SDA||SMBDAT
SCL|||SMBCLK
A0
A1
VCC
TH_GND
GND
NC5
NC4
NC3
NC2
NC1
NC0
EXT_CLK||INT
VINM
VINP
VBUS
SDA||SMBDAT
SCL|||SMBCLK
A0
A1
VCC
21R3577
21R3576
21R3572 21R3573
21R3568 21R3569
2
1
2
1
2
1
21
2
1
21
21
2
1
21
21
2
1
2
1
21
21
21
2
1
2
1
2
1
2
1
2
1
2
1
21
2
1
2121
21
21
2
1
21
2
1
2121
21
21
2
1
BOM NOTE:
SHEETDATE
DEPARTMENT
SIZE
PROJECT DOCUMENT NUMBER REV
REVIEWER
DESIGNER
123
7 3 2 1 6 5 4
E
A
B
C
E
D
C
B
A
7 6 5 4
D
OUT
OUT
INBI
OUT
INBI
BIIN
R4092
R4090
R4091
R3633
C2017
C2020
C2012
R3635
R3634
R3622 R3624
R3621 R3623
C2022
C2021
C2014
C2019
C2013
C2018
C



TBCFRU EEPROMFRU ADDR: 0XA2 (8-BIT) / 0X51 (7-BIT)CPU FRU EEPROMFRU ADDR: 0XA0 (8-BIT) / 0X50 (7-BIT)Thu Sep 14 16:12:31 2023<NAME_2><NAME_1>MB FABCGT AMDV02238 OF 365
P3V3_AUXP3V3_AUXP3V3_AUXP3V3_AUXP3V3_AUXP3V3_AUX
251239239251239251251239CHIP0402LFCHIP1K0402LFCHIP1/16W1%MB_FRU_ADDR2MB_FRU_ADDR0EMPTY1%M24128-BWMN6TPSMLF10K1%0402LFEMPTY1/16W04020.1UF25VX7R10%0402LF4.7K5%1/16WEMPTY0402LFEMPTY1/16W5%4.7KIC0402LFEMPTY1/16W1%10K1/16W0402LFCHIP1%1K1%0402LF1/16WCHIP1K0402LFEMPTY1/16W1%1K1/16W1%0402LFCHIP10K05%CHIP05%CHIP0CHIP5%5% CHIP01/16WCHIP0402LF1KSMB_CPU_FRU_3V3AUX_SCLSMB_CPU_FRU_3V3AUX_SDACPU_FRU_ADDR01K1%SMB_FRU_3V3AUX_SCLSMB_FRU_3V3AUX_SDAPD_CPU_FRU_WPMB_FRU_ADDR10402LF5%4.7K5%1/16W4.7KX7R10%25V0.1UF04021K1/16W 1/16WCHIP1%0402LF1/16W0402LF10K1%EMPTY0402LFEMPTY1/16W10K1% 1%10K1%1K0402LFEMPTY1/16WICM24128-BWMN6TPSMLF
MB FRUCPU_FRU_ADDR2CPU_FRU_ADDR1EMPTYSMB_FRU_3V3AUX_SDASMB_FRU_3V3AUX_SCL1/16W0402LF 0402LF1/16WSMB_FRU_3V3AUX_R1_SDASMB_FRU_3V3AUX_R1_SCLPD_MB_FRU_WP
7
4
8
5
6 3
2
1
7
4
8
5
6 3
2
1
U1
U64
E0
E1
E2
VSSSDA
SCL
WC#
VCC
E0
E1
E2
VSSSDA
SCL
WC#
VCC
21R86
21R85
21R125
21
2
1
2
1
2
1
2
1
2
1
2
1
2
1
R4
2
1
R24
2
1
2
1
2
1
R26
2
1
R43
2
1
2
1
2
1
2
1
2
1
2
1
2
1
2
1
R121
SHEETDATE
DEPARTMENT
SIZE
PROJECT DOCUMENT NUMBER REV
REVIEWER
DESIGNER
123
7 3 2 1 6 5 4
E
A
B
C
E
D
C
B
A
7 6 5 4
D
INBI
BIIN
R69
R68
R54 R62
R60
R44
C1 R52
R721
R722R710
C629
R714 R718
R713 R717
C



239 OF 365V02GT AMDMB FABC<NAME_1><NAME_2>Thu Aug 24 10:15:37 2023Blank
SHEETDATE
DEPARTMENT
SIZE
PROJECT DOCUMENT NUMBER REV
REVIEWER
DESIGNER
123
7 3 2 1 6 5 4
E
A
B
C
E
D
C
B
A
7 6 5 4
D
C



Thu Sep 14 16:12:31 2023MB FABC240 OF 365V02GT AMD<NAME_1><NAME_2>
FM_GPU_HSC_EN_BUF_R10.1UFEMPTY241FM_AC_PWR_BTN_PDB_N0.1UF EMPTYP12V_PSUP3V3_AUX
P3V3_AUXP3V3_AUXP3V3_AUXP3V3_AUXEMPTY1K1%HPDB_HSC_PWRGDFM_GPU_HSC_EN_BUF20%16VCHIP5%02412422692428024124124124182
15024325880132139246251253
241
241241
150151241150151130242SMB_FAN_3V3AUX_BUF_R_SCL0402LF1/16WCHIPPDB_PRSNT_R_NFM_FAN_PWR_ENSMB_FAN_3V3AUX_BUF_R_SDA5%CHIP0.1UF22UFHPDB_HSC_PWRGD_RFM_GPU_HSC_EN_BUF_R1C08055%FM_FAN_PWR_EN_RCHIP0FM_FAN_PWR_EN_REMPTYCHIP005%PDB_PRSNT_N
4.7K4.7K5%1/16WHPDB_HSC_PWRGD_RFM_PDB_BUF_EN_R1_NCHIP4.7K5%FM_PDB_BUF_EN_R_N
0FM_AC_PWR_BTN_PDB_NTP_J45_A1RST_SMB_SWITCH_R_NFM_AC_PWR_BTN_R_NCHIP5%05%P3V3_PDB_AUX_ADCRST_SMB_SWITCH_N0.1UF0.1UF EMPTYCHIPIOTHLFCONN60_10106263-6003K02LF
SMB_FAN_3V3AUX_BUF_R_SCL1%
RST_SMB_SWITCH_R_NPDB_PRSNT_N
33.2POWER CONNECTOR/ISOLATEDSMB_FAN_3V3AUX_BUF_SDASMB_FAN_3V3AUX_BUF_SCLCHIP1%33.2CHIP1%SMB_FAN_3V3AUX_SDA SMB_FAN_3V3AUX_R_SDA SMB_FAN_3V3AUX_BUF_R_SDA0.1UF EMPTYEMPTY
0402LF 1/16WEMPTY5%00EMPTYCHIP33.21%CHIP33.204020.1UF10%25VX7RLTC4307CMS8IC1/16WSMB_FAN_3V3AUX_SCL05% CHIPSMLF5%0 SMB_FAN_3V3AUX_R_SCLMB_PDB_SMB9_R_EN2N7002KICSMLFCHIP1K1%1/16WCHIP0402LFFM_PDB_BUF_EN_R10402LFPWRGD_P3V3_AUX_PDB_BUF
0402LFEMPTY0402LF5%1/16WEMPTY
241241241241241241
G
S D
C1115
R1526
C8011
R8102
R3114
R3113
C67
C66
C65
C64
C74
R2905
R2906
R2807R2805
R2801
R2800
R2812
R2811
R2796
C1751
R2793
R2803
R2802
P6_8
P6_7
P6_6
P6_5
P6_4
P6_3
P6_2
P6_1
P5_8
P5_7
P5_6
P5_5
P5_4
P5_3
P5_2
P5_1
P4_8
P4_7
P4_6
P4_5
P4_4
P4_3
P4_2
P4_1
P3_8
P3_7
P3_6
P3_5
P3_4
P3_3
P3_2
P3_1
P2_8
P2_7
P2_6
P2_5
P2_4
P2_3
P2_2
P2_1
P1_8
P1_7
P1_6
P1_5
P1_4
P1_3
P1_2
P1_1
D3
D2
D1
C3
C2
C1
B3
B2
B1
A3
A2
A1
8
76
23
54
1
G
S D
J45
U192
U190
POWER
SIGNAL
D3
C3
B3
A3
P6_8
P6_7
P6_6
P6_5
P6_4
P6_3
P6_2
P6_1
P3_8
P3_7
P3_6
P3_5
P3_4
P3_3
P3_2
P3_1
P5_8
P5_7
P5_6
P5_5
P5_4
P5_3
P5_2
P5_1
D1
C1
B1
A1
P4_8
P4_7
P4_6
P4_5
P4_4
P4_3
P4_2
P4_1
P2_8
P2_7
P2_6
P2_5
P2_4
P2_3
P2_2
P2_1
P1_8
P1_7
P1_6
P1_5
P1_4
P1_3
P1_2
P1_1
D2
C2
B2
A2
READY
SDA_OUT
SCL_OUT
VCC
GND
SDA_IN
SCL_IN
ENABLE
S
G
D
2
1
21
2
1
R2950
2
1
R9000
21
21
21
21
21
21
21
21
21
21 21
2
1
2
1
21
21
21
21
21
2
1
2
1
R2794
21
21 21
SHEETDATE
DEPARTMENT
SIZE
PROJECT DOCUMENT NUMBER REV
REVIEWER
DESIGNER
123
7 3 2 1 6 5 4
E
A
B
C
E
D
C
B
A
7 6 5 4
D
OUT
OUT
IN OUT
OUT
OUT
OUT
OUT
OUT
IN
OUT
OUT
IN
BIBI
IN
IN
INBI
INININ
C



OUT PUT IS PUSH PULL MODE
Thu Sep 14 16:12:32 2023<NAME_2><NAME_1>MB FABCGT AMDV02241 OF 365
PWRGD_P3V3_AUX_PDB85P3V3_AUXHPDB_HSC_PWRGD_NP3V3_AUXP3V3_AUX
P3V3_AUXP3V3_AUXP3V3_AUXP3V3_AUXP3V3_AUX
81241
811262412411/16WPJT138KSMLF54.9K0402LFCHIP1/16W74LVC2G07DW-7SMLF0402X7R10%25V0.1UF1%100K0402LFCHIP
10%25VX7R0.1UF04020402LFCHIP33.24.7K5%1/16WEMPTY0402LF4.7K5%0402LFEMPTY1/16W0402LF1%1/16WCHIP100K1/16WEMPTY5%0402LF4.7KSMLF74LVC1G08W5-7IC1/16WCHIP5%00402LFIC0.1UF040225V10%X7R00402LF1/16WCHIP5%4.7K5%EMPTY1/16W0402LF4.7K5%0402LF1/16WCHIPCHIP0402LF33.20402LF100K1%1/16WCHIP1%EMPTY0402LF1/16WICPJT138K5%4.7KICSMLFPOWER CONNECTOR/ISOLATEDHPDB_HSC_PWRGD_ISOHPDB_HSC_PWRGD
FM_GPU_HSC_ENGPU_PRSNT GPU_PRSNT_RFM_GPU_HSC_EN_BUF_RPWRGD_P3V3_AUX_PDB_BUF_RFM_GPU_HSC_EN_BUFPWRGD_P3V3_AUX_PDB_BUFPWRGD_P3V3_AUX_PDB_R
G2
G1
S2 D2D1S1
R4554
R4553
R4264
R3770
R2940
R2946
5
2
52
43
61
4
5
3
2
1
4 31 6
Q145
Q145
21R4266
U308
U278
21R2944
VCCGND
2Y
1Y
2A
1A
VCC
Y
GND
B
A
2
1
2
1
2
1
2
1
2
1
2
1
2
1
21
2
1C69
21
2
1
2
1
2
1
2
12
1C1775
SHEETDATE
DEPARTMENT
SIZE
PROJECT DOCUMENT NUMBER REV
REVIEWER
DESIGNER
123
7 3 2 1 6 5 4
E
A
B
C
E
D
C
B
A
7 6 5 4
D
IN
OUT
IN
OUTIN
IN OUT
C70R4551
R4552
R4265
R4268
R2948
R2941
C



Thu Sep 14 16:12:32 2023<NAME_2><NAME_1>MB FABCGT AMDV02242 OF 365
P3V3_AUXP3V3_AUXP12V_AUXP12V_AUXP3V3_AUXFM_AC_PWR_BTN_PLD_N0402LFEMPTY0.1UFSMLF10%EMPTY25V10%EMPTYC04021/16W0FM_AC_PWR_BTN_PLD_ISO_R_NEMPTY5%0402LFEMPTY04021UF8.45K1%EMPTY25V2N7002KFM_P12V_HSC_EN_RP12V_AUX_BLEEDING0402LF1/16W5%ICSMLFCHIP0402LF1/16W05%1/16WCHIP1%100K0402LF4.7K5%0402LFCHIP1/16WMB0_P12V_STBY_PWRGD
PSU POWER CONNECTORS
IC2N7002KSMLFFM_P12V_HSC_EN_N FM_P12V_HSC_EN_R_NCHIP00402LF74LVC2G07DW-71/16W1/16WFM_AC_PWR_BTN_R_N5%0NC_U8004_2YCHIP0402LFFM_AC_PWR_BTN_PLD_ISO_N1/16W1%1K254189268 263241 15081
G
G
S DS D
52
43
61
G
G
S DS D
U8004
Q54
U158
S
G
D
VCCGND
2Y
1Y
2A
1A
S
G
D
2
1
2
1
2
1
2
1
2121
2
1
2
1
21R2529
21R2531
SHEETDATE
DEPARTMENT
SIZE
PROJECT DOCUMENT NUMBER REV
REVIEWER
DESIGNER
123
7 3 2 1 6 5 4
E
A
B
C
E
D
C
B
A
7 6 5 4
D
OUTIN
IN
R8106
R8103
C8012
C8013
R8105R8104
R2530
R2528
C



Thu Aug 24 10:15:40 2023243 OF 365GT AMDMB FABC<NAME_2><NAME_1>V02Blank
SHEETDATE
DEPARTMENT
SIZE
PROJECT DOCUMENT NUMBER REV
REVIEWER
DESIGNER
123
7 3 2 1 6 5 4
E
A
B
C
E
D
C
B
A
7 6 5 4
D
C



Thu Aug 24 10:15:41 2023<NAME_2><NAME_1>MB FABCGT AMDV02244 OF 365Blank
SHEETDATE
DEPARTMENT
SIZE
PROJECT DOCUMENT NUMBER REV
REVIEWER
DESIGNER
123
7 3 2 1 6 5 4
E
A
B
C
E
D
C
B
A
7 6 5 4
D
C



PCA9539 ADDR: 0XE8 (8-BIT) / 0X74 (7-BIT)
Thu Sep 14 16:12:33 2023<NAME_2><NAME_1>MB FABCGT AMDV02245 OF 365000GPU_PRSNT_N_ISO_R1PRSNT_CABLE_GPU_B3_ISO_R1_NPRSNT_CABLE_GPU_A3_ISO_R_N5%CHIPCHIPCHIPP3V3_AUXP3V3_AUXP3V3_AUXP3V3_AUX176178235246246246246246246246246246246246246130246246246246246246246246246246246246246246121123251121123246251121123121123123126811258012312581123811231258124624624624680132139241251253246246246
BMC - PCA9539
SMLFICPCA9539RPW05%CHIP04020.1UFX7R25V10%5%0CHIP05%CHIP5%5%05%CHIP5%0CHIP5%0CHIP05%CHIP05%CHIP5%CHIP0CHIP05%05%CHIPCHIP5%0
0402LFEMPTY4.7K1/16W5%0402LF1%10KEMPTY1/16W05%CHIP0402LFEMPTY1%1K1/16W0402LF1/16W1%1KCHIP0402LFEMPTY1K1/16W1%0402LF1/16W1%1KCHIPRST_USB_HUB_NRST_SWB_BIC_NTP_TCA9539_0_P0_2TP_TCA9539_0_P0_3PRSNT_CABLE_GPU_A1_ISO_R1_NGPU_PEX_STRAP1_RGPU_PEX_STRAP0_RGPU_BASE_ID1_RGPU_BASE_ID0_RPRSNT_CABLE_SWB_B1_ISO_R_NPRSNT_CABLE_GPU_A2_ISO_R1_NSMB_IOEXP_3V3AUX_SDA_R1SMB_IOEXP_3V3AUX_SCL_R1TCA9539_0_ADD0PRSNT_CABLE_GPU_A3_ISO_R_NRST_SWB_BIC_R_NSMB_IOEXP_3V3AUX_SCL_R1SMB_IOEXP_3V3AUX_SDA_R1GPU_BASE_ID0_RGPU_BASE_ID1_RGPU_PEX_STRAP1_RPRSNT_CABLE_SWB_B2_ISO_R_NPRSNT_CABLE_GPU_A2_ISO_R1_NGPU_PEX_STRAP0_RPRSNT_SWB_ISO_R1_NPRSNT_CABLE_SWB_B1_ISO_R_NPRSNT_CABLE_GPU_A1_ISO_R1_NGPU_BASE_ID1SMB_IOEXP_3V3AUX_SDAGPU_BASE_ID0RST_SWB_BIC_NSMB_IOEXP_3V3AUX_SCLGPU_PEX_STRAP1GPU_PEX_STRAP0PRSNT_CABLE_SWB_B1_ISO_NGPU_PRSNT_N_ISOPRSNT_CABLE_GPU_B3_ISO_NPRSNT_CABLE_GPU_A3_ISO_NPRSNT_CABLE_GPU_A1_ISO_NPRSNT_SWB_ISO_NPRSNT_CABLE_SWB_B2_ISO_NPRSNT_CABLE_GPU_A2_ISO_NPRSNT_CABLE_SWB_B2_ISO_R_NPU_U181_INTTCA9539_0_ADD1GPU_PRSNT_N_ISO_R1PRSNT_SWB_ISO_R1_NPU_RST_SMB_U181_NRST_SMB_SWITCH_NTCA9539_0_ADD0TCA9539_0_ADD1PRSNT_CABLE_GPU_B3_ISO_R1_N
R2982
R2848
R2983
R3499
R3516
R3517
R3518
R9001
R9011
R9018
R9013
R9019
R8004
R9010
R9012
R2922
R2695
R2696
R2693
R2694
12 24
23
22
3
20
19
18
17
16
15
14
13
11
10
9
8
7
6
5
4
1
2
21
U181
VDD
SDA
SCL
A0
IO1_7
IO1_6
IO1_5
IO1_4
IO1_3
IO1_2
IO1_1
IO1_0
VSS
IO0_7
IO0_6
IO0_5
IO0_4
IO0_3
IO0_2
IO0_1
IO0_0
RESET
A1
INT
21
2
1C1713
21
21
21
21
21
21
21
21
21
21
21
21
21
21
2
1
21
2
1
2
1
2
1
2
1
2
1
SHEETDATE
DEPARTMENT
SIZE
PROJECT DOCUMENT NUMBER REV
REVIEWER
DESIGNER
123
7 3 2 1 6 5 4
E
A
B
C
E
D
C
B
A
7 6 5 4
D
OUT
OUT
OUT
OUT
IN
IN
IN
IN
IN
IN
IN
IN
IN
IN
BI
OUT
OUT
OUT
OUT
OUT
OUT
OUT
OUT
OUT
OUT
OUT
OUT
OUT
IN
OUT
OUT
IN
IN
IN
IN
IN
IN
IN
IN
IN
IN
IN
IN
IN
IN
IN
IN
IN
IN
IN
IN
R2923
R2921
C



Thu Aug 24 10:15:42 2023<NAME_2><NAME_1>MB FABCGT AMDV02246 OF 365Blank
SHEETDATE
DEPARTMENT
SIZE
PROJECT DOCUMENT NUMBER REV
REVIEWER
DESIGNER
123
7 3 2 1 6 5 4
E
A
B
C
E
D
C
B
A
7 6 5 4
D
C



FROM OCP HSC ENABLEFROM OCP HSC ENABLEFROM OCP_12V_HSC PWRGDFROM CPLDFROM OCP_12V_HSC PWRGDFROM CPLD
Thu Sep 14 16:12:34 2023<NAME_2><NAME_1>MB FABCGT AMDV02247 OF 365
P3V3_OCP_V3_2P3V3_OCP_V3_2P3V3_OCP_SFFP3V3_AUXP3V3_AUXP3V3_OCP_SFF1371401411428183140 141136 134 135137142 140 14113115015115015115015115015180 83134 135134 135 1361315%0CHIPX7RSMB_OCP_V3_2_3V3AUX_BUF_SCL0402LFCHIP1/16WEMPTYHP_LVC3_OCP_V3_2_P12V_PWRGDP3V3_OCP_V3_2_EN_RP12V_OCP_SFF_BUF_EN_R5%HP_LVC3_OCP_V3_2_R_ENSMB_OCP_V3_2_3V3AUX_BUF_SDA040210%0.1UF25VPCA9617ADPP12V_OCP_V3_2_BUF_EN_R0EMPTY0402LFEMPTYHP_LVC3_OCP_V3_1_R_EN05%SMB_OCP_SFF_3V3AUX_BUF_SCLSMB_OCP_SFF_3V3AUX_SCLSMB_OCP_SFF_3V3AUX_SDASMB_OCP_V3_2_3V3AUX_SDASMB_OCP_V3_2_3V3AUX_SCL
SMBUS - ISOLATED
4.7K5%1/16W0402LFCHIP1/16W5%4.7KCHIPX7R040225V0.1UF10%040225VX7R10%0.1UFICPCA9617ADPSMLFSMLF10%0402X7R25V0.1UF0402LFIC5%P3V3_OCP_SFF_EN_RHP_LVC3_OCP_V3_1_P12V_PWRGD0402LFSMB_OCP_SFF_3V3AUX_BUF_SDA05%4.7KCHIP5%04.7K5%1/16WCHIP0402LF5%0EMPTY
R1180
R1135
R3264
R3263
R3501R3500
81
63
72
4 5
81
63
72
4 5
U236
U235
GND
SCLB
SDABSDAA
SCLA
VCCBVCCA
EN
GND
SCLB
SDABSDAA
SCLA
VCCBVCCA
EN
21
21
R1522
21R1500
21
21
21
2
1
2
1
2
1
2
1
2
1
2
1
2
1
2
1
SHEETDATE
DEPARTMENT
SIZE
PROJECT DOCUMENT NUMBER REV
REVIEWER
DESIGNER
123
7 3 2 1 6 5 4
E
A
B
C
E
D
C
B
A
7 6 5 4
D
IN
IN
IN
IN
IN
OUT
BI
IN
OUT
BI
IN
IN
BI
BI
R3519 R3520
C1862C1860
C1861C1859
C



I3C FROM BMCTBCTBCTBC
Thu Sep 14 16:12:34 2023<NAME_2><NAME_1>MB FABCGT AMDV02248 OF 365
0402LFCHIP1/16WLTC4307CMS8SMB_2_BMC_GPU_BUF_SDASMB_2_BMC_GPU_BUF_SCL0.1UFP3V3_AUX1%LTC4307CMS8CHIP1/16WLTC4307CMS8SMB_BMC_SWB_R_SCLSMB_BMC_SWB_R_SDA1/16WP3V3_AUXP3V3_AUXP3V3_AUXP3V3_AUX
P3V3_AUXP3V3_AUXP3V3_AUX116150151802491161221221191191221228224915015115015182249251802492511501511501511501510402LF 1/16W27 5%CHIPI3C_BMC_SWB_BUF_SDA0402LF1%I3C_BMC_SWB_SCLSMB_BMC_SWB_EN0402LFCHIP5%00CHIP5%1/16W0402LFCHIP5%0EMPTY1/16W0402LF5%0EMPTY010K
CHIP0CHIP0402LF01/16W5%10%25VX7R040200402LF5%CHIP1/16WCHIP05%0402LF54.9K1%1/16W0402LF54.9K1%CHIP0402LF 1/16W1%33.2 CHIP33.21%CHIP0402LFCHIP5%0CHIP5%05%0CHIP0EMPTYEMPTY01/16W0402LF5%5%CHIP00.1UF25V10%X7R04021/16WCHIP5%0402LF2.2K1%33.2 CHIP2.2K5%0402LF1/16WCHIP1/16W1%CHIP0402LF33.2
0.1UF25V10%X7R04025%1/16WEMPTY4.7K5%4.7K1/16WEMPTY0402LF1/16W00402LFEMPTY5%EMPTY033.2 CHIP1%CHIP33.2CHIP33.21%0402LF 1/16W04020.1UFX7R25V10%CHIP0402LF54.9K1%1/16WCHIP1/16W1%54.9K0402LFI3C_BMC_SWB_R_SCL I3C_BMC_SWB_BUF_SCL
SMLFICLTC4307CMS8ICSMLFEMPTYSMLF1%SMLFICSMB_BMC_SWB_BUF_R_SCLSMB_BMC_SWB_BUF_R_SDASMB_BMC_GPU_EN_R1SMB_1_BMC_GPU_R_SDASMB_1_BMC_GPU_R_SCL SMB_1_BMC_GPU_BUF_SCLSMB_1_BMC_GPU_BUF_SDASMB_1_BMC_GPU_BUF_R_SDASMB_1_BMC_GPU_BUF_R_SCLI3C_BMC_SWB_BUF_R_SDAI3C_BMC_SWB_BUF_R_SCL
SMB_BMC_SWB_BUF_SCLSMB_BMC_SWB_BUF_SDASMB_BMC_GPU_ENSMB_BMC_SWB_EN_RSMB_2_BMC_GPU_BUF_R_SCLSMB_2_BMC_GPU_BUF_R_SDASMB_1_BMC_GPU_SCLSMB_1_BMC_GPU_SDASMB_BMC_GPU_EN_R3SMB_2_BMC_GPU_R_SDASMB_2_BMC_GPU_R_SCLSMB_BMC_GPU_ENSMB_BMC_SWB_SCLSMB_BMC_SWB_ENSMB_BMC_SWB_SDASMB_2_BMC_GPU_SDASMBUS - PCIE3 SMBUSSMB_2_BMC_GPU_SCLSMB_BMC_SWB_EN_R2CHIP33.205%CHIP0402LF 1/16W10K1%CHIP1/16WI3C_BMC_SWB_R_SDAI3C_BMC_SWB_SDA05%CHIP0402LF
R2669R2667
R3523
R3105
R3106
R3109
R3110
R3108
R3107
R2674R3111
R2897
R2898
R2675
R2893
R2894
R2670R2668
R2671
R2672
R2899
R2724
R2705
R2707
R2991
R2990
R2725
R2706
R2676
R3112
R2986
R2987
R2992
8
76
23
54
1
8
76
23
54
1
8
76
23
54
1
8
76
23
54
1
U175
U194
U176
U200
READY
SDA_OUT
SCL_OUT
VCC
GND
SDA_IN
SCL_IN
ENABLE
READY
SDA_OUT
SCL_OUT
VCC
GND
SDA_IN
SCL_IN
ENABLE
READY
SDA_OUT
SCL_OUT
VCC
GND
SDA_IN
SCL_IN
ENABLE
READY
SDA_OUT
SCL_OUT
VCC
GND
SDA_IN
SCL_IN
ENABLE
2121
2
1
2
1
2
1
21
21
21
21
21
2
1
2
1
2
1
21
2
1
21
2
1
2
1
21
21
21
21
21
21
21
21
2
1
2
1
21
21
2
1
21
21
21
21
2
1
21
21
21
21
21
2
1
SHEETDATE
DEPARTMENT
SIZE
PROJECT DOCUMENT NUMBER REV
REVIEWER
DESIGNER
123
7 3 2 1 6 5 4
E
A
B
C
E
D
C
B
A
7 6 5 4
D
BI
BI
OUT
BI
OUT
BI
OUT
BI
OUT
IN
BI
IN
BI
IN
IN
BI
IN
IN
IN
IN
R3524C1766
C1708
C1707
R3522R3521C1796
R4603
R2666
C



Thu Aug 24 10:15:45 2023<NAME_2><NAME_1>MB FABCGT AMDV02249 OF 365Blank
SHEETDATE
DEPARTMENT
SIZE
PROJECT DOCUMENT NUMBER REV
REVIEWER
DESIGNER
123
7 3 2 1 6 5 4
E
A
B
C
E
D
C
B
A
7 6 5 4
D
C



PCA9548 ADDR: 0XE0 (8-BIT) / 0X70 (7-BIT)
Thu Sep 14 16:12:35 2023<NAME_2><NAME_1>MB FABCGT AMDV02250 OF 365
P3V3_AUXP3V3_AUXP3V3_AUXP3V3_AUX150 251150 251251252239251251239251251251251251148148251176178179251251251251252
251 148239251249251179 251 176 178176 178 179 251251 148148 251251148148251251246179251176178251246
148 251251249251246251246251252251252150 251150 251251249249251
251239
80132139241246253SMB_BMC_SWB_SCL_R4SMB_BMC_SWB_SDA_R4SMB_PCIE0_3V3AUX_SDASMB_PCIE0_3V3AUX_SCLCHIPCHIP5%0SMB_INA230_3V3AUX_SCL_RSMB_INA230_3V3AUX_SDA_R5%0CHIP05%CHIP5%5%0SMB_INA230_3V3AUX_SCLSMB_FRU_3V3AUX_SDASMB_FRU_3V3AUX_SCLSMB_PCIE0_3V3AUX_SCL_R5SMB_PCIE0_3V3AUX_SDA_R5SMB_PCIE0_3V3AUX_SCL_R3SMB_USB_CPU0_HUB1_SCL_RSMB_USB_CPU0_HUB1_SDA_RPU_RST_SMB_PCIE0_NPCA9548_PCIE3_ADDR2SMB_PCIE0_3V3AUX_SDA_R3ICPCA9548_PCIE3_ADDR0PCA9548_PCIE3_ADDR1PCA9548_PCIE3_ADDR2IO_SLOT1K0402LFCHIP1/16W1%IO_SLOT0402LF1KCHIP1/16W1%IO_SLOT1/16WCHIP1K0402LF1%EMPTY1%0402LF10K1/16WEMPTY1%0402LF1/16W10KEMPTY1/16W0402LF1%10KCHIPCHIPCHIPCHIPCHIPCHIP10%25VSMB_SENSOR_E1S_3V3AUX_SCLSMB_SENSOR_E1S_3V3AUX_SDA5%SMB_IOEXP_3V3AUX_SCL_RSMB_IOEXP_3V3AUX_SDA_RSMB_USB_CPU0_HUB1_SDAPCA9548_PCIE3_ADDR1PCA9548_PCIE3_ADDR00402SMB_INA230_3V3AUX_SDA0402LFSMB_SENSOR_M2_P1_3V3AUX_SCLSMB_FRU_3V3AUX_SDASMB_BMC_SWB_SCLCHIP5%2.2K2.2K1/16W0402LFCHIPCHIP5%0SMB_PCIE0_3V3AUX_SCL_RCHIP
SMB_USB_CPU0_HUB1_SCLSMB_USB_CPU0_HUB1_SDA1/16W0402LF2.2K5%CHIPSMB_SENSOR_E1S_3V3AUX_SCLSMB_SENSOR_E1S_3V3AUX_SDA2.2K5%CHIPCHIP5%2.2K1/16W0402LF5%2.2K2.2K1/16W1/16WSMB_SENSOR_M2_P1_3V3AUX_SCLSMB_SENSOR_M2_P1_3V3AUX_SDA005%SMB_IOEXP_3V3AUX_SCLSMB_USB_CPU0_HUB1_SCLSMB_IOEXP_3V3AUX_SDACHIP010K1%1/16WCHIP0402LF5%0CHIPCHIP05%5%05%5%5%0 1/16W1/16WCHIPSMB_SENSOR_M2_P1_3V3AUX_SDASMB_BMC_SWB_SDASMB_IOEXP_3V3AUX_SDASMB_IOEXP_3V3AUX_SCLSMB_INA230_3V3AUX_SDASMB_INA230_3V3AUX_SCLSMB_PCIE0_3V3AUX_SDASMB_PCIE0_3V3AUX_SCLSMB_PCIE0_3V3AUX_SDA_R
SMBUS - PCIE0 SMBUS
SMB_BMC_SWB_SDASMB_BMC_SWB_SCL
SMB_FRU_3V3AUX_SCL
TCA9548APWRSMLF33.21/16W 0402LF1%CHIP1%33.205%2.2K EMPTY5%2.2K EMPTY2.2K CHIP5%CHIP5%2.2K5%CHIP0402LFCHIPCHIP5%0402LF2.2K5%CHIP2.2K5%0402LFCHIP5%2.2K CHIP2.2K5%1/16W2.2K5%CHIP0402LF
X7R0.1UF05%0RST_SMB_SWITCH_NSMB_FRU_3V3AUX_SCL_RSMB_FRU_3V3AUX_SDA_R
R6212
R6211
R6201
R6200
R65
R55
R2566
R2703
R2704
R3580
R3581
R2565
R2204
R2205
R3396
R3395
R3582
R3583
R3535
R3536
R2985
R2984
R66
R67
R1090
R1089
R3394
R3393
R2968
R2967
R3527
R3526
R2268
24
23
19
17
15
13
10
8
6
4
22
20
18
16
14
11
9
7
5
3
12
21
2
1
U36
SD4
SC4
SD5
SC5
SD6
SC6
SD7
SC7
A2 SCL
SDA
VCC
GND
SC3
SD3
SC2
SD2
SC1
SD1
SC0
SD0
RESET#
A1
A0
21 21
2 12 1
2 12 1
21 21
21 21
21 21
21 21
2
1
21
2 1
2
1
2
1
2
1
2
1
2
1
2
1
2
1
SHEETDATE
DEPARTMENT
SIZE
PROJECT DOCUMENT NUMBER REV
REVIEWER
DESIGNER
123
7 3 2 1 6 5 4
E
A
B
C
E
D
C
B
A
7 6 5 4
D
OUTOUT
BIOUT
BIIN
BIOUTBIOUTBIOUT
OUTOUT
OUTOUT
OUTOUT
OUT
OUTOUT
OUTOUT
OUT
OUTOUT
INININ
OUT
OUT
OUTBI
BI
BI
IN
OUT
OUT
OUT
C106
R1822
R320R318R316
R587R319R317
C



Thu Sep 14 16:12:35 2023<NAME_2><NAME_1>MB FABCGT AMDV02251 OF 3653583583583583583582382382372372382512512372372382382381%1/16WCHIP33.20402LF33.2 CHIP1%0402LF33.21%1/16WCHIP33.21%CHIPCHIP33.21%0402LF 1/16W1%CHIP33.2SMB_INA230_7_3V3AUX_SCL_RSMB_INA230_8_3V3AUX_SCL_RSMB_INA230_8_3V3AUX_SDA_RSMB_INA230_7_3V3AUX_SDA_RSMB_INA230_6_3V3AUX_SCL_RSMB_INA230_6_3V3AUX_SDA_R1/16W33.233.2SMB_INA230_5_3V3AUX_SCL_RSMB_INA230_5_3V3AUX_SDA_R0402LF33.21%CHIPSMB_INA230_2_3V3AUX_SDA_RSMB_INA230_2_3V3AUX_SCL_RSMB_INA230_3_3V3AUX_SCL_R
SMBUS - PCIE1 SMBUS
SMB_INA230_3V3AUX_SDASMB_INA230_3V3AUX_SCL SMB_INA230_1_3V3AUX_SCL_RSMB_INA230_1_3V3AUX_SDA_R0402LFCHIP1%33.2CHIP33.21%0402LF33.21%CHIP33.21%CHIP1%33.2CHIPCHIP1%33.21%0402LF 1/16W1/16W1/16WSMB_INA230_4_3V3AUX_SDA_RSMB_INA230_3_3V3AUX_SDA_RSMB_INA230_4_3V3AUX_SCL_RCHIP0402LFCHIP1%CHIP1%33.21/16W
21 21
21 21
21 21
21 21
21R3588 21R3589
21 21
21R3594 21R3595
21 21
R1349R1348
R1347R1346
R1345R1344
R3586R3587
R3590R3591
R3592R3593
SHEETDATE
DEPARTMENT
SIZE
PROJECT DOCUMENT NUMBER REV
REVIEWER
DESIGNER
123
7 3 2 1 6 5 4
E
A
B
C
E
D
C
B
A
7 6 5 4
D
OUTBI
OUTBI
BIOUT
BIOUT
OUT
IN
BI
OUTBI
BIOUT
BIOUT
BI
C



PCA9548 ADDR: 0XE0 (8-BIT) / 0X70 (7-BIT)
Thu Sep 14 16:12:35 2023<NAME_2><NAME_1>MB FABCGT AMDV02252 OF 365SMB_VR_SENSOR_3V3AUX_SDASMB_VR_SENSOR_3V3AUX_SCL1/16W0402LFSMB_ADC_SCL_RSMB_ADC_SDA_RSMB_VR_3V3AUX_SDASMB_VR_3V3AUX_SCLSMB_LM75_0_3V3AUX_SDA2.2K253253PCA9548_PCIE0_ADDR0PCA9548_PCIE0_ADDR1PCA9548_PCIE0_ADDR2251P3V3_AUXP3V3_AUXP3V3_AUXP3V3_AUX253 259253 259
253 259236 253253 236150253150253253 259236 253268236253253272236236253272253236253236236253268253 23615025380132139241246253151151253253253253253 236236 253253 236236 253 272151253253 272 236253151236 253150253253CHIP5%0CHIP05%
5%CHIP2.2K2.2K CHIP5%2.2K1/16W2.2K5%SMB_ADC_SCL_R5%CHIPSMB_LM75_3_3V3AUX_SCLSMB_LM75_3_3V3AUX_SDA2.2K CHIP5%2.2K1/16WCHIP0402LF2.2K2.2K1/16W1/16W5%2.2K5%2.2K2.2K1/16W1/16W2.2KSMB_VR_SENSOR_3V3AUX_SDA_RSMB_VR_SENSOR_3V3AUX_SCL_RSMB_ADC_SDA_RSMB_ADC_SCL0CHIPSMB_LM75_3_3V3AUX_SCLSMB_P12V_HSC_SDA5%0CHIP0CHIPSMB_LM75_2_3V3AUX_SCL_R5%CHIPSMB_LM75_2_3V3AUX_SCLCHIPCHIPCHIPCHIPCHIP5%0SMB_LM75_0_3V3AUX_SDA_RSMB_LM75_0_3V3AUX_SCL_RSMB_LM75_1_3V3AUX_SDA_RSMB_LM75_1_3V3AUX_SCL_RSMB_VR_3V3AUX_SCL_R605%SMB_LM75_0_3V3AUX_SDASMB_LM75_0_3V3AUX_SCLSMB_LM75_1_3V3AUX_SDASMB_LM75_2_3V3AUX_SDASMB_LM75_1_3V3AUX_SCLTCA9548APWRSMB_LM75_2_3V3AUX_SDA_RSMB_VR_3V3AUX_SDA_R6SMB_P12V_HSC_SCLSMLF33.2SMB_LM75_3_3V3AUX_SDA05%CHIP05%05%005%1%EMPTY0402LF10K1/16W5%CHIP005%CHIP0402LF1/16W5%0CHIP25V0.1UF10%X7R0402
EMPTY5%0402LFEMPTYCHIP5%2.2K0402LF5%CHIP0402LFCHIP5%5%CHIPCHIP0402LFCHIP5%CHIP5%0402LF5%1%CHIP0402LF33.21%CHIP1/16WSMB_VR_SENSOR_3V3AUX_SDARST_SMB_SWITCH_NSMB_VR_3V3AUX_SCLSMB_VR_3V3AUX_SDAPCA9548_PCIE0_ADDR1PCA9548_PCIE0_ADDR2PCA9548_PCIE0_ADDR0PU_RST_SMB_PCIE2_NSMB_LM75_1_3V3AUX_SDASMB_LM75_2_3V3AUX_SCLSMB_LM75_2_3V3AUX_SDASMB_LM75_0_3V3AUX_SCLSMB_LM75_1_3V3AUX_SCLSMB_VR_SENSOR_3V3AUX_SCLIC
SMBUS - PCIE2 SMBUS0402LFEMPTY1%10K1/16W0402LFEMPTY1%1/16W10KEMPTY1%0402LF10K1/16W1/16WCHIP1K1%0402LFIO_SLOT0402LF1KCHIP1/16W1%IO_SLOT1/16W1K0402LFCHIP1%IO_SLOT5%SMB_P12V_HSC_SDA_RSMB_LM75_3_3V3AUX_SCL_RSMB_P12V_HSC_SCL_RSMB_LM75_3_3V3AUX_SDA_RSMB_ADC_SDA
R1341
R1316
R1315
R1312
R6229
R6228
R3711
R3712
R3721
R3722
R3723
R3724
R3725
R3726
R3727
R3728
R3730
R3729
R4269
R4270
R3713
R3714
R3715
R3716
R3718
R3717
R3720
R3719
R3731
R3732
R3710
24
23
19
17
15
13
10
8
6
4
22
20
18
16
14
11
9
7
5
3
12
21
2
1
U39
SD4
SC4
SD5
SC5
SD6
SC6
SD7
SC7
A2 SCL
SDA
VCC
GND
SC3
SD3
SC2
SD2
SC1
SD1
SC0
SD0
RESET#
A1
A0
21 21
21 21 21 21
2 12 1
21 21
21 21
2
1
2 12 1
21
2
1
2
1
2
1
2
1
2
1
2
1
2
1
SHEETDATE
DEPARTMENT
SIZE
PROJECT DOCUMENT NUMBER REV
REVIEWER
DESIGNER
123
7 3 2 1 6 5 4
E
A
B
C
E
D
C
B
A
7 6 5 4
D
OUTOUT
OUTOUT
OUTBI
BIIN
BIOUT
OUTOUT
OUTOUT
OUTOUT
OUTOUT
OUT
OUT
OUT
OUT
INININ
BIOUTBIOUT
IN
OUT
OUT
OUT
BIOUTBIOUT
C2056
R3705
R3708R3706R3703
R3709R3707R3704
C



Thu Sep 14 16:12:37 2023<NAME_2><NAME_1>MB FABCGT AMDV02253 OF 365
P3V3_AUXSMLFP3V3_AUX80150254 255263268189243254255
PWRGD_ISOLATOR
33.21%ICPJT138KCHIP5%005%CHIP0402LF1/16WCHIP4.7KICPWRGD_PS_PWROK_PLD_ISO_RPWRGD_PS_PWROKPWRGD_PS_PWROK_PLDPWRGD_PS_PWROK_PLD_ISOMB0_P12V_STBY_PWRGDPJT138K0402LF1/16WCHIPPWRGD_PS_PWROK_PLD_NSMLFPWRGD_PS_PWROK_PLD5%0402LFCHIP1/16W1K1%
G1
G2
D1S1S2 D2
R3047
R3048
R4605
R4604
5
2
4 31 6
Q144
Q144
21R9446
2
1
21
21
2
1
SHEETDATE
DEPARTMENT
SIZE
PROJECT DOCUMENT NUMBER REV
REVIEWER
DESIGNER
123
7 3 2 1 6 5 4
E
A
B
C
E
D
C
B
A
7 6 5 4
D
IN
OUT
OUT
OUTIN
C



PWRGD_P1V2_AUX 1 = ONRST_CPU0_RSMRST_N 1 = ONPWRGD_PS_PWROK 1 = ON
PWRGD_SYS_PWROK 1 = ONP3V3 1 = ONP5V 1 = ONPWRGD_P1V8_AUX 1 = ON
Thu Sep 14 16:12:37 2023<NAME_2><NAME_1>MB FABCGT AMDV02254 OF 365
P3V3_AUX
P3V3P5VP3V3_AUX
P3V3_AUXP3V3_AUXP3V3_AUX8528812542708114827127181LED_BLUELTST-C281TBKT-5AIC0402LFLTST-C281TBKT-5ALTST-C281TBKT-5ASMLFLED_BLUELED_BLUELTST-C281TBKT-5ASCM_SYS_PWROK_R21%1/16W130CHIP0402LFSMLFLED_PWRGD_PS_PWROK_PLD_D LED_PWRGD_PS_PWROK_PLD1/16WCHIPLED_RST_RSMRST_PLD_R_N1301/16WLED_RST_RSMRST_PLD_R_N_DSMLFICSMLFLED_PWRGD_SYS_PWROK_R_DCHIP0402LF1%ICICRST_CPU0_RSMRST_NPJT138KICSMLFICLED_BLUEPWRGD_PS_PWROK_PLDICPJT138KSMLF1301%
LED_P3V3LED_P5VLED_BLUESMLFICLTST-C281TBKT-5ALED_BLUESMLFICLTST-C281TBKT-5A1/16W1301%CHIP0402LF1%0402LF1/16WCHIP470LED_PWRGD_SYS_PWROK_RPJT138KPOWER GOOD LED'S 1/3
LED_BLUELTST-C281TBKT-5A1/16WCHIP1301%0402LFSMLFPJT138KICLED_PWRGD_P1V8_AUX_DPWRGD_P1V8_AUX_RICSMLFLED_PWRGD_P1V8_AUXSMLFSMLF1/16WCHIP1301%0402LFLED_PWRGD_P1V2_AUXLED_PWRGD_P1V2_AUX_DPJT138KPWRGD_P1V2_AUX_RIC
G1
G1
G2
G1
G2
D1S1
D1S1S2 D2D1S1S2 D2
R3102
Q6000
D6000
D93
Q87
5 Q87
D88
Q78
D91
5 Q78
D98
D96
D99
AC
AC
AC
AC
AC
AC
AC
4 3 4 3
21
21
21
21
21
21
21
2
C A
C A
2
C A
2
C A
C A
C A
C A
1 6
1 61 6
SHEETDATE
DEPARTMENT
SIZE
PROJECT DOCUMENT NUMBER REV
REVIEWER
DESIGNER
123
7 3 2 1 6 5 4
E
A
B
C
E
D
C
B
A
7 6 5 4
D
IN
IN
IN
IN
IN
R6246
R3074
R3069
R3071
R3075
R3100
C



PWRGD_PVDDCR_CPU0_P0 1 = ONPWRGD_PVDD33_S5 1 = ONPWRGD_PVDDCR_SOC_P0 1 = ONPWRGD_PVDDIO_P0 1 = ON
PWRGD_PVDDCR_CPU1_P0 1 = ONPWRGD_PVDD18_S5_P0 1 = ONPWRGD_PVDD11_S3_P0 1 = ON
Thu Sep 14 16:12:43 2023<NAME_2><NAME_1>MB FABCGT AMDV02255 OF 365P3V3_AUX
P3V3_AUXP3V3_AUXP3V3_AUXP3V3_AUXP3V3_AUXP3V3_AUX81828282 818181LED_PWRGD_PVDDCR_CPU0_P0_DSMLFPJT138KICSMLFPJT138KLED_PWRGD_PVDDCR_CPU1_P0_RLTST-C281TBKT-5ALED_BLUENC_Q83_D2NC_Q83_G2NC_Q83_S2LED_PWRGD_PVDD11_S3_P0_RSMLFICLED_BLUELED_PWRGD_PVDDIO_P0_RFM_LED_PWRGD_PVDDIO_P0PJT138KPJT138KLED_PWRGD_PVDDCR_SOC_P0_DPJT138KSMLFLED_BLUELTST-C281TBKT-5ASMLFSMLFSMLFSMLFICLED_BLUESMLFLTST-C281TBKT-5APJT138KICICICICLED_BLUESMLFICICSMLFICSMLFICPJT138KFM_LED_PWRGD_PVDDCR_CPU0_P0SMLFFM_LED_PWRGD_PVDDCR_SOC_P0LED_BLUESMLFLTST-C281TBKT-5AFM_LED_PWRGD_PVDDCR_CPU1_P0LED_PWRGD_PVDDCR_CPU1_P0_D
ICLED_PWRGD_PVDDCR_CPU0_P0_RLED_PWRGD_PVDD33_S5_R LED_PWRGD_PVDDIO_P0_DFM_LED_PWRGD_PVDD11_S3_P0LED_PWRGD_PVDD18_S5_P0_DLED_BLUEICLTST-C281TBKT-5ALED_PWRGD_PVDD18_S5_P0_RLTST-C281TBKT-5ALED_PWRGD_PVDD11_S3_P0_DLTST-C281TBKT-5APOWER GOOD LED'S 2/3
ICPJT138KSMLFLED_PWRGD_PVDDCR_SOC_P0_RFM_LED_PWRGD_PVDD18_S5_P0IC
0402LF1/16WCHIP1%1300402LF1/16WCHIP1%1300402LF1/16WCHIP1%1301301/16W0402LF1%CHIP1301%1/16WCHIP0402LF1/16W0402LF1301%CHIP0402LF1/16WCHIP1%130
LED_PWRGD_PVDD33_S5_DFM_LED_PWRGD_PVDD33_S5
G2
G1
G2
G1
G2
G2
G1
G1
S2 D2D1S1
S2 D2D1S1
S2 D2
S2 D2D1S1
D1S1
5
4 3
Q83
D77
Q81
D78
D79
5 Q81
Q83
D73
Q79
D74
D75
D76
5 Q79
Q80
5 Q80
AC
AC
AC
AC
AC
AC
AC
4 3
4 34 3
21
21
21
21
21
21
21
C A
2
C A
C A
2
C A
2
C A
C A
C A
2
1 61 6
1 61 6
SHEETDATE
DEPARTMENT
SIZE
PROJECT DOCUMENT NUMBER REV
REVIEWER
DESIGNER
123
7 3 2 1 6 5 4
E
A
B
C
E
D
C
B
A
7 6 5 4
D
IN
IN
IN
ININ
IN
IN
R3092
R3090
R3091
R3086
R3087
R3089
R3088
C



PWRGD_PVDDIO_P1 1 = ONPWRGD_PVDD18_S5_P1 1 = ONP12V_AUX 1 = ONPWRGD_PVDD11_S3_P1 1 = ONPWRGD_PVDDCR_CPU0_P1 1 = ONPWRGD_PVDDCR_CPU1_P1 1 = ONPWRGD_PVDDCR_SOC_P1 1 = ONP12V_PSU 1 = ONP12V_SCM FAULT 0 = ONThu Sep 14 16:12:43 2023<NAME_2><NAME_1>MB FABCGT AMDV02256 OF 365
SMLFP12V_PSUP3V3_AUX
P3V3_AUXP3V3_AUXP12V_AUXP3V3_AUXP3V3_AUXP3V3_AUXP3V3_AUX
P3V3_AUX152
808081808080 CHIP5601/16WLED_P12V_PSU_R21%LED_P12V_PSU_R3CHIPLED_P12V_SCM_FAULT_D20402LFSMLFP12V_SCM_FAULT_R_NPJT138KPJT138KSMLFSMLFIC0402LFIC
0402LFLED_PWRGD_PVDD18_S5_P1_DFM_LED_PWRGD_PVDD18_S5_P11/16W0402LF 1/16W5601%1301%0402LFLED_BLUECHIP1/16W5601%0402LFLED_P12V_AUX_R1 LED_P12V_AUX_R3LTST-C281TBKT-5ALED_BLUEICSMLF1%560CHIP 1/16W5600402LFCHIP1%1/16W5601%CHIP 0402LFICSMLFFM_LED_PWRGD_PVDD11_S3_P1SMLFLTST-C281TBKT-5APJT138K
POWER GOOD LED'S 3/3
PJT138KIC1301%CHIP 1/16W0402LF1301%CHIPSMLFLTST-C281TBKT-5APJT138KSMLFICLTST-C281TBKT-5ALED_BLUEICSMLF1301%CHIP 1/16W0402LFCHIPICSMLFLED_BLUEICSMLFPJT138KLTST-C281TBKT-5ALED_BLUESMLFICICPJT138KSMLF
LED_PWRGD_PVDDCR_CPU0_P1_D LED_PWRGD_PVDDCR_CPU0_P1_RLED_PWRGD_PVDDCR_SOC_P1_DLED_PWRGD_PVDDCR_CPU1_P1_D LED_PWRGD_PVDDCR_CPU1_P1_RLED_PWRGD_PVDDIO_P1_R
FM_LED_PWRGD_PVDDCR_CPU0_P1FM_LED_PWRGD_PVDDCR_SOC_P1FM_LED_PWRGD_PVDDCR_CPU1_P1FM_LED_PWRGD_PVDDIO_P1
LED_BLUEIC 1301%CHIP 1/16W0402LF1301%CHIP 1/16W0402LFICLED_BLUESMLFICSMLFICLED_BLUELED_PWRGD_PVDD11_S3_P1_RLED_PWRGD_PVDD11_S3_P1_D1/16WLTST-C281TBKT-5ALED_PWRGD_PVDDCR_SOC_P1_RLTST-C281TBKT-5APJT138KLED_PWRGD_PVDD18_S5_P1_RICLED_P12V_AUX_R20402LFLED_P12V_PSU_R15%LED_PWRGD_PVDDIO_P1_D1/16WCHIP1%CHIPIC0402LF4.7KLTST-C281TBKT-5ASMLF1/16WLTST-C190KSKT-PLED_YELLOW249LED_P12V_SCM_FAULT1/16WLED_P12V_SCM_FAULT_D1
G1
G2
G1
G1
G2
G2
G1
G2
D1S1
S2 D2D1S1 D1S1S2 D2
S2 D2 D1S1S2 D2
5
2
C A
C A
C A
4 31 6
Q8001
Q8001
D8002
D8001
D8000
D84
D85
Q86
5 Q86
D80
D81
D82
D83
Q84
5 Q84
Q85
5 Q85
AC
AC
AC
AC
AC
AC
AC
AC
AC
4 3
4 34 3
2
1 21
21 2 1 2 1
212121
21
21
21
21
21
21
C A
C A
2
C A
C A
C A
C A
2
2
1 6
1 61 6
SHEETDATE
DEPARTMENT
SIZE
PROJECT DOCUMENT NUMBER REV
REVIEWER
DESIGNER
123
7 3 2 1 6 5 4
E
A
B
C
E
D
C
B
A
7 6 5 4
D
IN
IN
IN
IN
IN
IN
IN
R8028
R8029
R8026 R8027
R8024R8023
R3099
R3097
R3093
R3094
R3096
R3095
C
R8025
R8022



VI=1.581VADDR: 0X3A(8-BIT) / 0X1D(7-BIT)IF USE AD128,POP R3668,R3670
VIN 1.599V 1.599V 1.677V 1.581VV SOURCE P3V3_AUX P3V3 P5V P12V_AUXADDR: 0X6A(8-BIT) / 0X35(7-BIT)
NOTE:R4567 NEED CHANGE TO 5.11K OHM ON EVT STATES AND POP R4568Thu Sep 14 16:12:43 2023<NAME_2><NAME_1>MB FABCGT AMDV02257 OF 3650402LF1/16WCHIPP3V3_PDB_AUX_ADC_MAMP3V3_PDB_AUX_ADC_TICVOLTAGE SENSOR (1/2)
ADC_TI_BOM1CO-LAYOUTADC_MAM_BOM205%0402EMPTYADC_TI_BOM1258ADC_TI_BOM1P12V_E1S_0_ISENSE_MAM_TIC5%CHIP1/16WADC_TI_BOM1258P12V_OCP_SFF_ISENSE_MAMP12V_OCP_SFF_ISENSE_TICEMPTYP12V_E1S_0_ISENSE_MAM_MAMADC_TI_BOM1P5VP12V_AUX
P3V3_AUXP3V3_AUXP3V3
P3V3_AUX
P3V3_AUX
ADC_TI_BOM3P12V_E1S_0_ISENSE_TIC5%50V100PFEMPTYEMPTYP12V_E1S_0_ISENSE_MAMP12V_E1S_0_ISENSE_MPS_TIC0402ADC_TI_BOM1ADC_TI_BOM1ADC128_A0P12V_E1S_0_ISENSE_TIC25825825810%CHIP0ADC_TI_BOM3CO-LAYOUTX7R0402P12V_OCP_V3_2_ISENSE_MAMCO-LAYOUTCHIPP12V_OCP_V3_2_ISENSE_TICEMPTY5%0P12V_OCP_V3_2_ISENSE_MPS_TIC05%P12V_OCP_V3_2_ISENSE_MAM_TICADC_TI_BOM1ADC_MAM_BOM20ADC_TI_BOM3CHIP5%P12V_OCP_SFF_ISENSE_MPS_TIC5%CO-LAYOUTADC_TI_BOM1P12V_OCP_SFF_ISENSE_MAM_TIC140134258147141258258258258258258135258258258258258258258258258258258258258151258151258258258258
258146241258258258258
140258147258
258258258258151258151258 258258258
258258
134135146141SMLFMAX11617EEE+T10%X7RMAX11617_VREF_RCHIPX6SX7R0.1UF0402MAX11617_VREF10UFADC_MAM_BOM20.1UFIND25VP3V3_MAX11617_VDDEMPTY0402LFEMPTYEMPTYPOP U269, AND DE-POP U193 WHICH IS 2ND SOLUTION10%10%100PF1%2KADC_MAM_BOM2ADC_MAM_BOM20402EMPTYP12V_E1S_0_ISENSE_MPS_MAM50V0402ADC_MAM_BOM2EMPTYP12V_OCP_V3_2_ISENSE_MPS_MAM5%
CO-LAYOUTADC_MAM_BOM2ADC_MAM_BOM21/16WCHIPADC_TI_BOM110%25V0.1UF100PF5%0ADC_MAM_BOM20402LFP12V_AUX_ADC0402LFCHIPEMPTYP5V_ADC_MAMADC_MAM_BOM20402EMPTY5%50V100PFCO-LAYOUTADC_MAM_BOM2P3V3_AUX_ADC_TIC5%0P3V3_AUX_ADC_MAM0.1UF25V10%X7R0402P3V3_ADC_TIC0.1UF10%0402100PFP5V_ADC_TICADC_MAM_BOM2CO-LAYOUTADC_TI_BOM10402LFP5V_ADC0ADC_MAM_BOM20402CHIPP3V3_ADC05%ADC_TI_BOM1P3V3_AUX_ADCCHIP00 0402P12V_E1S_0_ISENSE_MAMSMB_SEN_MAM_3V3AUX_SCLSMB_SEN_MAM_3V3AUX_SDA0402ADC_MAM_BOM216VC08051/16W10%X6S16V10%C0805P3V3_PDB_AUX_ADC_MAMP3V3_AUX_ADC_MAMADC_TI_BOM14.7KSMB_SEN_TIC_3V3AUX_SCLSMB_SEN_TIC_3V3AUX_SDAADC_TI_BOM1SMLFX7R10%25V
ADC_TI_BOM1100PFX7RADC_TI_BOM125V00402LFP12V_AUX_ADC_TICP12V_AUX_ADC_MAM50V5%EMPTYEMPTYADC_TI_BOM11.21K5%0402X7R10%18K9.09KADC_TI_BOM15%EMPTY4.7K1%5%4.7K1/16W1%5.11K
4.7KADC128_A15.11K
P12V_OCP_V3_2_ISENSE_TICCHIPP3V3_ADC128_VCC0.1UF0402LFEMPTYADC_TI_BOM11%1/16W1/16W 1/16W1%ADC_TI_BOM1SMB_SCM_2_R4_SDAADC_TI_BOM1CHIPCHIP0402LFSMB_SCM_2_R4_SCL1/16WP3V3_AUX_ADC_TICADC128_VREFP3V3_PDB_AUX_ADC_TIC1%0402TP_ADC128_INTADC_TI_BOM125VSMB_SEN_TIC_3V3AUX_SCLSMB_SEN_TIC_3V3AUX_SDA5%05%0100PF5%05% EMPTY1%1/16W5%5%01% 5%01/16W0402LFCHIP1/16W1/16W1%0CHIP1%0402LFCHIP
10%040250V5%0402LF1K1%1/16WCHIP0402LFCHIP5%0EMPTY5%04020402CHIP1%1/16W7.87K1%EMPTY1K0402LF1KBLM18PG300SN1DSMLF4.7K1%0.1UF5%00.1UF0402EMPTY5%5.11K1%05%CHIP
50VP3V3_ADC_MAMP3V3_PDB_AUX_ADCX7REMPTY
EMPTYICX7R25VX7RINDADC_TI_BOM110%EMPTYP12V_AUX_ADC_TICP5V_ADC_TICP3V3_ADC_TICCHIPADC128_A11%1/16WADC_TI_BOM11KADC128_A00402LFEMPTYADC_TI_BOM10402LFADC_TI_BOM1
0402LF05%CHIPX7R040250V25VX7R10%ADC_TI_BOM1P12V_OCP_SFF_ISENSE_TICADC128D818CIMTX/NOPB5%1/16W10UFSMLFBLM18PG300SN1D25V25VP12V_AUX_ADC_MAMP12V_OCP_SFF_ISENSE_MAMP12V_OCP_V3_2_ISENSE_MAMP5V_ADC_MAM0402LFSMB_SCM_2_R4_SCLSMB_SCM_2_R4_SDA01/16WSMB_SEN_MAM_3V3AUX_SDASMB_SEN_MAM_3V3AUX_SCLADC_MAM_BOM20EMPTYCHIPEMPTY0.1UFCO-LAYOUTADC_MAM_BOM2100PF1/16W5%0402LFP3V3_ADC_MAM25V0402LF25V0.1UFADC_TI_BOM1ADC_MAM_BOM21%0.1UFP1V581_PDB_ADC0402EMPTYCO-LAYOUTADC_MAM_BOM2
CO-LAYOUTP12V_OCP_SFF_ISENSE_MAM_MAMP12V_OCP_SFF_ISENSE_MPS_MAM0EMPTYADC_MAM_BOM2P12V_OCP_V3_2_ISENSE_MAM_MAM05% EMPTY50VCO-LAYOUT5%0.1UF
L15
C1768
R3672
R3671
R1793
R1792
C1767
R3863
C2176
R3864
R3865
R3866
R3859
C2042
C59
R3860
R3861
R3862
R3939
R3940
C35
R3941
R3942
C2043
C2044
C1344
C2045
R3681
R2907
R3682
R3683
R3684
R2908
R3685
R3686R1791
R1799
R1800
C1757
R2900
R3689
C1347
C2047
R3669R3667
C2046
R3687
R3688
R3670R3668
C2050
C2048
R1785
R2843
C2049
R3005
R3679
R3680
R4567
R4568
16
14
13
15
1
2
3
4
12
11
10
98
7
6
5
21
1
5
2
3
6
9
10
11
12
13
14
15
16 4
8
7
21
U193
U269
L16
1 2
VDD
GND
SDA
SCL
AIN7
AIN6
AIN5
AIN4AIN3
AIN2
AIN1
AIN0
AIN8
AIN9
AIN10
AIN11||REF
1 2
INT#
GND
SCL
SDA
IN0
IN1
IN2
IN3
IN4
IN5
IN6
IN7
A1
A0
V+
VREF
2
1
2
1
2
1
21
21 21
21 21
2
1
2
1
2
1
2
1
21
2
1
2
1 C37
21
21
21
21
2
1
2
1
2
1
2
1 C33
21
21
21
21
21
2
1
2
1 C2194
21
21
2
1
2
1
2
1
2
1
2
1
2
1
2
1
2
1
21
21
2
1
2
12
1
2
1
2
1
21
2
1
21
2
1
21
21
2
1
2
1
21
2
1
21
2
1
2
1
21
21
2
1
2
1
2
1
CAD NOTE:
R3690
SHEETDATE
DEPARTMENT
SIZE
PROJECT DOCUMENT NUMBER REV
REVIEWER
DESIGNER
123
7 3 2 1 6 5 4
E
A
B
C
E
D
C
B
A
7 6 5 4
D
IN
IN
IN
INOUT
OUT
OUT
IN
IN
IN
IN
IN
IN
IN
OUT
OUT
OUT
OUT
OUT
OUT
OUT
OUT
IN
IN
IN
IN
IN
IN
IN
BIOUT
OUTBI
BIIN
BIIN
INBI
ININ
ININ
ININ
IN
IN
ININ
OUT
OUT
OUT
OUT
OUT
IN
IN
IN
IN
IN
OUT
OUT
C2052C2051
C



1.402VPVDD18_S5_P1ADDR: 0X6A(8-BIT) / 0X35(7-BIT)VINV SOURCEP5V_AUX1.677VP1V8_AUX
ADDR: 0X3A(8-BIT) / 0X1D(7-BIT)IF USE AD128,POP R3668,R3670
P1V2_AUX1.402VP1V8_CPU0_RT_1D1.402V 1.581VPVDD_33_S51.402V 0.934VP1V8_CPU1_RT_1D PVDD18_S5_P01.402V
Thu Sep 14 16:13:11 2023<NAME_2><NAME_1>MB FABCGT AMDV02258 OF 365
P1V8_CPU1_RT_1D
PVDD18_S5_P1PVDD18_S5_P0P1V8_CPU0_RT_1D
P3V3_AUXPVDD_33_S5P1V8_AUXP1V2_AUXP3V3_AUX
P5V_AUX
P3V3_AUX
259259259259259259259253259259
259259259259259259259253259259259259259259259259259253259 259259259259259259259259259259259259259259259253259
259259259
259
259
259
1/16W0402LFMAX11617_2_VREF0.1UF25V10%X7R0402X6S10%MAX11617_2_VREF_RMAX11617EEE+TSMLFBLM18PG300SN1D10%10%16VEMPTYX7R25VADC_MAM_BOM2P1V8_CPU1_RT_1D_ADC_MAMCO-LAYOUTC0805SMLFADC_MAM_BOM2P5V_AUX_ADC_MAM0.1UFP3V3_MAX11617_2_VDD16V10UFEMPTYX7R0402LFP1V2_AUX_ADC_MAMP1V2_AUX_ADC_TIC1%1/16WP1V8_CPU0_RT_1D_ADC_TIC5.11KCHIPCO-LAYOUTADC_MAM_BOM205%EMPTYEMPTY1/16WSMB_SEN_MAM_2_3V3AUX_SDA0402LFSMB_SEN_MAM_2_3V3AUX_SCLPOP U51, AND DE-POP U50 WHICH IS 2ND SOLUTIONADC_MAM_BOM25%0SMB_ADC_SCL_RSMB_SEN_MAM_2_3V3AUX_SDAP3V3_ADC128_2_VCC25VPVDD18_S5_P1_ADC_MAMADC_MAM_BOM2EMPTY0.1UFADC_MAM_BOM21/16WCHIP25VPVDD18_S5_P0_ADC_TICPVDD18_S5_P0_ADC_MAMADC_MAM_BOM225V0402LFADC_MAM_BOM2100PF1/16WPVDD_33_S5_ADCCO-LAYOUTADC_MAM_BOM2CHIPP1V8_CPU1_RT_1D_ADC05%ADC_TI_BOM1CHIP
ADC_MAM_BOM2EMPTY100PFADC_TI_BOM1P1V8_AUX_ADC_TICP1V8_AUX_ADC_MAMCHIP0402LF18KADC_MAM_BOM2ADC_TI_BOM1ADC_MAM_BOM25%1%0402LFP1V8_CPU0_RT_1D_ADCEMPTY0.1UFADC_MAM_BOM2ADC_MAM_BOM2EMPTY04020.1UF25V10%X7R0402ADC_TI_BOM1ADC_MAM_BOM2CO-LAYOUT0402LFP1V2_AUX_ADC5%5%EMPTY0402X7R10%25V0.1UFADC_TI_BOM1P5V_AUX_ADC_TICP5V_AUX_ADC_MAMCO-LAYOUTADC_MAM_BOM2P1V8_AUX_ADC1/16WCHIPEMPTYCO-LAYOUT0402CHIP10UFC0805SMB_ADC_SDA_RADC_TI_BOM104021/16W0402LFPVDD18_S5_P1_ADC1%CHIP04020402
1/16WCHIP
0402LF5%1/16W18K0
0402CHIP040209.09K
ADC_TI_BOM1ADC_TI_BOM10402LFADC_TI_BOM11/16W18KX7R25V0.1UFX7R0402LFADC_TI_BOM1PVDD18_S5_P1_ADC_TICPVDD18_S5_P0_ADC_TICPVDD_33_S5_ADC_TICP1V8_CPU1_RT_1D_ADC_TICP1V8_CPU0_RT_1D_ADC_TIC1%1KADC_TI_BOM1ADC128_2_A0ADC128_2_A10402LFEMPTY1/16W0402LFCHIP1/16W1K1KEMPTY1K1%P1V2_AUX_ADC_TIC1/16WEMPTY04021%1/16WEMPTY1/16WSMB_ADC_SCL_R05% CHIPSMB_SEN_TIC_2_3V3AUX_SCLSMB_SEN_TIC_2_3V3AUX_SDA4.7K1%4.7KSMB_SEN_TIC_2_3V3AUX_SDAADC128_2_VREFADC128_2_A1P1V8_AUX_ADC_TICP5V_AUX_ADC_TICADC_TI_BOM1ADC_TI_BOM1ADC_TI_BOM1ICSMLFP1V8_CPU1_RT_1D_ADC_MAMPVDD_33_S5_ADC_MAM1%
CHIP0402LF1/16W18K0402LF1/16WCHIP18K0402LF5.11K1/16W
5%EMPTY
18K0402LF1%CHIP1%5.11K1%1%CHIP18K1%
05%1/16W
0 2K0402X6SIND
040201/16WCHIP0402040225V0CHIP5.11KCHIP1/16W1%
1%0402LF1/16W5.11KEMPTY50V5%CHIP5% EMPTY001/16W0402LFCHIPCHIP1%0 100PFX7R1%EMPTY05%50V5%04020.1UFX7R10%CHIP1%0402LF1%0.1UFBLM18PG300SN1DINDSMLF10%X7R0.1UF
VOLTAGE SENSOR (2/2)
P1V8_AUX_ADC_MAMP1V2_AUX_ADC_MAMP1V8_CPU0_RT_1D_ADC_MAMPVDD18_S5_P1_ADC_MAMPVDD18_S5_P0_ADC_MAM
0402LF CHIPADC128D818CIMTX/NOPBADC_TI_BOM110%040210%SMB_SEN_TIC_2_3V3AUX_SCLTP_ADC128_2_INTADC128_2_A0CHIPSMB_ADC_SDA_R0402LFADC_TI_BOM10402LFEMPTYADC_TI_BOM1
1%5%5%ADC_TI_BOM10 040210%05%4.7KCHIP5%ADC_TI_BOM1PVDD_33_S5_ADC_MAMPVDD_33_S5_ADC_TICADC_TI_BOM10.1UF10%X7R05%10%0402SMB_SEN_MAM_2_3V3AUX_SCL1%0402LF5%0EMPTYP5V_AUX_ADCCHIPADC_MAM_BOM21/16WCHIP5%100PF50VEMPTY5%ADC_TI_BOM1100PF50V25V5%5.11K1%5%50VADC_TI_BOM11%P1V8_CPU0_RT_1D_ADC_MAM100PF50VADC_TI_BOM1X7R10%1/16WCO-LAYOUT
P1V8_CPU1_RT_1D_ADC_TIC50V100PF5%ADC_TI_BOM10.1UF25VADC_TI_BOM1EMPTYCO-LAYOUT5%0PVDD18_S5_P0_ADC5.11K0402EMPTY50V5%ADC_TI_BOM10402LFADC_MAM_BOM225VADC_TI_BOM105% CHIPPVDD18_S5_P1_ADC_TIC100PFADC_TI_BOM1ADC_MAM_BOM2
L24
R1256
C1081
R1249
R1236
R1233
R1254
R1247
C1080
R1235
R1255
R1248
C1082
R1257
R1250
C1083
R1234
R1231
R1252
R1246
C1079
R1232
R1251
R1245
C1078
C1077C1076
R1243
R1244
R1228
R1227
C1084
C1085
R1258
R1259
R1237
R1260
R1263R1226
R1225
R1222
R1223
R1220
R1221
R1229
C1090
C1088
R1224
C1089
C1091
C1087
C1086
C1075
R1230
R1267
C1074
C1092
R1241R1239
R1242R1240
C1093
R1238
21
16
14
13
15
1
2
3
4
12
11
10
98
7
6
5
1
5
2
3
6
9
10
11
12
13
14
15
16 4
8
7
21
U50
U51
L25
1 2
1 2
VDD
GND
SDA
SCL
AIN7
AIN6
AIN5
AIN4AIN3
AIN2
AIN1
AIN0
AIN8
AIN9
AIN10
AIN11||REF
INT#
GND
SCL
SDA
IN0
IN1
IN2
IN3
IN4
IN5
IN6
IN7
A1
A0
V+
VREF
2
1
2
1
2
1
2
1
2
1
2
1
21
2
1
2
1
21
2
1
2
1
21
21
2
1
2
1
2
1
2
1
21
21
2
1
2
1
21
21
2
1
2
1
2
1
2
1
21
21
2
1
2
1
2
1
21
21
2
1
2
1
2
1
2
1
21
2
1
21 21
21 21
2
1
2
1
2
1
2
1
2
1
2
1
2
1
2
1
2
1
2
1
2
1
2
1
2
1
21
21
2
1
21
21
2
1
2
1
CAD NOTE:
R1268
SHEETDATE
DEPARTMENT
SIZE
PROJECT DOCUMENT NUMBER REV
REVIEWER
DESIGNER
123
7 3 2 1 6 5 4
E
A
B
C
E
D
C
B
A
7 6 5 4
D
OUT
OUT
OUT
OUT
OUT
OUT
OUT
OUT
OUT
OUT
OUT
OUT
OUT
OUT
OUT
OUT
IN
IN
IN
IN
IN
IN
IN
IN
IN
IN
BIOUT
BIOUT
INBI
ININ
INBI
IN
IN
ININ
IN
INININ
BIIN
OUT
OUT
C1095C1094
C



Thu Sep 14 16:12:45 2023<NAME_2><NAME_1>MB FABCGT AMDV02259 OF 3655%50V33P12V_AUXP12V_AUXP12V_MEM_CPU1P12V_MEM_CPU0P12V_MEM_CPU0P1V8_AUXP3V3_AUXP1V8_AUXP3V3_AUXP12V_MEM_CPU1P1V8_AUXP1V8_AUX81260260
260260
TP_P12V_AUX_CPU0_DIMM_ISEN_PTP_P12V_AUX_CPU1_DIMM_ISEN_P TP_P12V_AUX_CPU1_DIMM_ISEN_NTP_P12V_AUX_CPU0_DIMM_ISEN_NSMLF0.0013W1%CHIPSMLF1%0.001CHIP3W
PWRGD_P12V_MEM_CPU0_RSMLFPWRGD_P12V_MEM_R
1/16W1%16.9K0402LFICPWRGD_P12V_MEM_CPU1SMLFBSS138DW-7-F1%0402LFCHIP1/16W
P12V_MEM MOS SWITCH
PWRGD_P12V_MEM_CPU1_EN_NPWRGD_P12V_MEM_CPU0_EN_NPWRGD_P12V_MEM_CPU1_ENICCHIPPWRGD_P12V_MEM_CPU0_EN1%CHIP1/16W100K0402LF1%1/16WCHIP100K0402LF0402LFCHIP1/16W10K5%0402LF10K5%CHIP1/16WPWRGD_P12V_MEM_CPU010K5%0402LFCHIP1/16WCHIP1/16W5%0402LF10K
04021000PFX7R25V10%X7R04020.1UF333316.9KICPWRGD_P12V_MEM10KCHIP1/16W0402LFSN74LVC1G11DCKRSMLFBSS138DW-7-FPU_U38_6PWRGD_P12V_MEM_CPU1_RPWRGD_P12V_MEM_CPU1PWRGD_P12V_MEM_CPU01%
2
1
C347
2
1
R1452
2
1
R1457
2
1
R1450
41
52
36
Q18
41
52
36
Q19
2
1
R1442
2
1
R1443
2
1
R1449
2
1
R1440
2
1
R1441
21 R13634
5
2
6
3
1
U38
21R1458
21R1459
21
21
4343
R6504
21
R1838
21
R1837
4343
GND
Y
VCC
C
B
A
D2D1
S2
G2G1
S1
D2D1
S2
G2G1
S1
2
1
2
1
SHEETDATE
DEPARTMENT
SIZE
PROJECT DOCUMENT NUMBER REV
REVIEWER
DESIGNER
123
7 3 2 1 6 5 4
E
A
B
C
E
D
C
B
A
7 6 5 4
D
OUT
OUT
IN
IN OUT
C5014
C



85 OHM80 OHM50 OHM45 OHM
Thu Sep 14 16:12:46 2023<NAME_2><NAME_1>MB FABCGT AMDV02260 OF 365T1_GNDT1_GNDT1_GNDT1_GNDT1_GNDT1_GNDT1_GNDT1_GND
T1_GNDT1_GNDT1_GNDT1_GNDT1_GND
T1_GNDT1_GNDT1_GNDT1_GNDT1_GNDT1_GNDT1_GNDT1_GNDT1_GNDT1_GNDT1_GND
T1_GNDT1_GNDT1_GNDT1_GNDT1_GNDT1_GNDT1_GNDT1_GNDT1_GNDT1_GNDT1_GND
T1_GNDT1_GNDT1_GNDT1_GNDT1_GNDT1_GNDT1_GNDT1_GNDT1_GNDT1_GNDT1_GNDT1_GND
T1_GNDTDR_SE_45_OHM_IN2
TDR_1
TDR_SE_45_OHM_TOPTDR_SE_45_OHM_IN1TDR_SE_45_OHM_IN3TDR_SE_45_OHM_IN6TDR_SE_45_OHM_BOTTDR_SE_45_OHM_IN5TDR_SE_45_OHM_IN4TDR_SE_50_OHM_IN6TDR_SE_50_OHM_IN4TDR_SE_50_OHM_BOTTDR_SE_50_OHM_IN5TDR_SE_50_OHM_IN3TDR_SE_50_OHM_IN1TDR_SE_50_OHM_IN2TDR_SE_50_OHM_TOP
TDR_DIFF_80_BOT_DPTDR_DIFF_80_BOT_DNTDR_DIFF_80_IN6_DPTDR_DIFF_80_IN6_DNTDR_DIFF_80_IN5_DPTDR_DIFF_80_IN5_DNTDR_DIFF_80_IN4_DPTDR_DIFF_80_IN4_DNTDR_DIFF_80_IN3_DPTDR_DIFF_80_IN3_DNTDR_DIFF_80_IN2_DPTDR_DIFF_80_IN2_DNTDR_DIFF_80_IN1_DPTDR_DIFF_80_IN1_DNTDR_DIFF_80_TOP_DPTDR_DIFF_80_TOP_DN
TDR_DIFF_85_BOT_DPTDR_DIFF_85_BOT_DNTDR_DIFF_85_IN6_DPTDR_DIFF_85_IN6_DNTDR_DIFF_85_IN5_DNTDR_DIFF_85_IN3_DPTDR_DIFF_85_IN3_DNTDR_DIFF_85_IN5_DPTDR_DIFF_85_IN4_DNTDR_DIFF_85_IN4_DPTDR_DIFF_85_IN2_DPTDR_DIFF_85_IN2_DNTDR_DIFF_85_IN1_DPTDR_DIFF_85_IN1_DNTDR_DIFF_85_TOP_DPTDR_DIFF_85_TOP_DN
TH2TH2TH2TH2TH2TH2TH2TH2
TH2TH2TH2TH2THTP_TDR_4P_DIPEMPTYEMPTYTHTP_TDR_4P_DIPTP_TDR_4P_DIPTHEMPTYTP_TDR_4P_DIPEMPTYTHTHTP_TDR_4P_DIPEMPTYTHEMPTYTP_TDR_4P_DIPTH2TH2TH2TH2TP_TDR_4P_DIPTHEMPTYTP_TDR_4P_DIPTHEMPTY
TP_TDR_4P_DIPTHEMPTYTP_TDR_4P_DIPEMPTYTHEMPTYTP_TDR_4P_DIPTHTP_TDR_4P_DIPTHEMPTYTP_TDR_4P_DIPTHEMPTYTHTP_TDR_4P_DIPEMPTYTHTP_TDR_4P_DIPEMPTYTHEMPTYTP_TDR_4P_DIPTHTP_TDR_4P_DIPEMPTYEMPTYTHTP_TDR_4P_DIPEMPTYTP_TDR_4P_DIPTHEMPTYTHTP_TDR_4P_DIPTHEMPTYTP_TDR_4P_DIPEMPTYTHTP_TDR_4P_DIPTP_TDR_4P_DIPTHEMPTYTHEMPTYTP_TDR_4P_DIPEMPTYTHTP_TDR_4P_DIPEMPTYTHTP_TDR_4P_DIPEMPTYTHTP_TDR_4P_DIPTP_TDR_4P_DIPTHEMPTYEMPTYTP_TDR_4P_DIPTHEMPTYTHTP_TDR_4P_DIP
EMPTYTHTP_TDR_4P_DIPTHEMPTYTP_TDR_4P_DIP
4
1
3
2
4
1
3
2
4
1
3
2
4
1
3
2
4
1
3
2
4
1
3
2
4
1
3
2
4
1
3
2
4
1
3
2
4
1
3
2
4
1
3
2
4
1
3
2
4
1
3
2
4
1
3
2
4
1
3
2
4
1
3
2
4
1
3
2
4
1
3
2
4
1
3
2
4
1
3
2
4
1
3
2
4
1
3
2
4
1
3
2
4
1
3
2
4
1
3
2
4
1
3
2
3
2
1
3
2
1
3
2
1
3
2
1
4
1
3
2
4
1
3
2
4
1
3
2
4
1
3
2
4
1
3
2
4
1
3
2
3
2
1
3
2
1
3
2
1
3
2
1
3
2
1
3
2
1
3
2
1
3
2
1
3
2
1
3
2
1
3
2
1
3
2
1
TDR
TDR
TDR
TDR
TDR
TDR
TDR
TDR
TDR
TDR
TDR TDR
TDR
TDR
TDR
TDR
X11
X8012
X8007
X8008
X8001
X8002
X7
X8
X8009
X8010
X8011
X8027
X8028
X8003
X8004
X8005
X9
X10
X8025
X8026
X8006
X27
X28
X12
X1
X2
X3
X4
X5
X25
X26
X6
S1
P2S2
P1
S1
P2S2
P1
S1
P2S2
P1
S1
P2S2
P1
S1
P2 S2
P1
S1
P2 S2
P1
S1
P2S2
P1
S1
P2S2
P1
S1
P2S2
P1
S1
P2S2
P1
S1
P2S2
P1
S1
P2S2
P1
S1
P2S2
P1
S1
P2 S2
P1
S1
P2 S2
P1
S1
P2 S2
P1
S1
P2S2
P1
S1
P2S2
P1
S1
P2 S2
P1
S1
P2 S2
P1
S1
P2 S2
P1
S1
P2S2
P1
S1
P2S2
P1
S1
P2S2
P1
S1
P2 S2
P1
S1
P2 S2
P1
S1
P2 S2
P1
S1
P2 S2
P1
S1
P2 S2
P1
S1
P2 S2
P1
S1
P2 S2
P1
S1
P2 S2
P1
SHEETDATE
DEPARTMENT
SIZE
PROJECT DOCUMENT NUMBER REV
REVIEWER
DESIGNER
DB7
DB8
DB9
DB10
DB11
DB15
DB16
DB12
DB1
DB2
DB3
DB4
DB5
DB13
DB14
DB6
123
7 3 2 1 6 5 4
E
A
B
C
E
D
C
B
A
7 6 5 4
D
C



85 OHM NECK
Thu Sep 14 16:12:46 2023<NAME_2><NAME_1>MB FABCGT AMDV02261 OF 365
T1_GNDT1_GNDT1_GNDT1_GNDT1_GNDT1_GNDT1_GNDT1_GNDT1_GNDT1_GNDT1_GNDT1_GNDTDR_2
TP_TDR_4P_DIPEMPTYTP_TDR_4P_DIPEMPTYTHTHEMPTYTP_TDR_4P_DIPTHTDR_DIFF_85_NECK_IN1_DNTDR_DIFF_85_NECK_IN1_DPTDR_DIFF_85_NECK_IN2_DPTDR_DIFF_85_NECK_IN2_DNTDR_DIFF_85_NECK_IN3_DNTDR_DIFF_85_NECK_IN3_DPTP_TDR_4P_DIPTP_TDR_4P_DIPEMPTYTHEMPTYTHTP_TDR_4P_DIPTHEMPTYTP_TDR_4P_DIPEMPTYEMPTYTHTP_TDR_4P_DIPTP_TDR_4P_DIPEMPTYTHTHTDR_DIFF_85_NECK_IN4_DPTDR_DIFF_85_NECK_IN4_DNTDR_DIFF_85_NECK_IN5_DPTDR_DIFF_85_NECK_IN5_DNTDR_DIFF_85_NECK_IN6_DNTDR_DIFF_85_NECK_IN6_DPTP_TDR_4P_DIPTP_TDR_4P_DIPTHEMPTYTHTP_TDR_4P_DIPEMPTYTHEMPTY
4
1
3
2
4
1
3
2
4
1
3
2
4
1
3
2
4
1
3
2
4
1
3
2
4
1
3
2
4
1
3
2
4
1
3
2
4
1
3
2
4
1
3
2
4
1
3
2
X9008
X9009
X9011
X9010
X9027
X9028
X9002
X9003
X9004
X9005
X9025
X9026
S1
P2 S2
P1
S1
P2 S2
P1
S1
P2 S2
P1
S1
P2S2
P1
S1
P2S2
P1
S1
P2 S2
P1
S1
P2S2
P1
S1
P2S2
P1
S1
P2S2
P1
S1
P2S2
P1
S1
P2 S2
P1
S1
P2 S2
P1
SHEETDATE
DEPARTMENT
SIZE
PROJECT DOCUMENT NUMBER REV
REVIEWER
DESIGNER
123
7 3 2 1 6 5 4
E
A
B
C
E
D
C
B
A
7 6 5 4
D
C



OCP=240AOCW=220AADDRESS 0X20HOT SWAT CIRCUITFPH=220ALATCH OFF MODEUV =10.091VOV =14.333V
SOFT START TIME=6MS.VOUT SLEW RATE: 2V/MSADDRESS: 0X40(8-BIT) / 0X20(7-BIT)EN<0.95V OFFEN>1.2V ON
Thu Sep 14 16:12:44 2023262 OF 365MB FABCV02GT AMD<NAME_2><NAME_1>P12V_AUXAGND_HSCHSC_VDDAGND_HSCAGND_HSCHSC_VDDAGND_HSCHSC_VDDAGND_HSCAGND_HSCAGND_HSCAGND_HSCAGND_HSCAGND_HSCP12V_AUXAGND_HSCP3V3_AUXAGND_HSC
P12V_PSUHSC BOM11UF25V264 265268189243 254264 26526426526926815115126880 26885264 265264 26526880264 265264 265264 265264 265HSC_SSHSC BOM1MB0_P12V_STBY_PWRGD1/16W1%0402CHIP0402LFHSC BOM1HSC BOM10.001UFX7R1%10KHSC_SCREFX7RHSC BOM1120KCHIP1/16WCHIP0402LFHSC BOM10.1%0.047UF25V1/16WHSC BOM11%0402LFHSC BOM1HSC BOM10402LF1K1%1/16W4.7KHSC BOM1C0402ICSS15P3S-M3/86AHSC BOM1HSC BOM1HSC_ADDR1K1%HSC BOM1HSC_VDD181/16WC0402HSC_ONHSC BOM10402LFHSC_EN05%CHIP5%0402LF1/16WCHIP0402LF1%HSC BOM11/16WHSC_VIN_UVW_NHSC_EN_R1/16W0HSC BOM1CHIPAUX_SWIRQ_SML1_PMBUS_ALERTCHIP0402LF5%SMB_SML1_PMBUS_HSC_SDAHSC BOM1CHIPSMB_SML1_PMBUS_HSC_R_SDASMB_SML1_PMBUS_HSC_L_SCLSMB_SML1_PMBUS_HSC_SCLHSC BOM15%0402LF1/16WCHIPHSC BOM1C0402X7R50VHSC BOM10.01UF4.99KHSC BOM1CHIP1/16W0.1%HSC BOM1HSC BOM11UF75K25VX6SX6SCHIP0402LFCHIP1/16W5%1/16W0402LF1/16W1%HSC_VDD_RHSC BOM1HSC_ON_R1K1/16WCHIP10KHSC BOM1HSC BOM10402LF33.20C040225V0402LFIRQ_SML1_PMBUS_ALERT_NC04020402LF1UFX6SICCHIP0402LF16.9K2KX7R50V22222K1%CHIP
HSC MP5990 (1/3)
IRQ_HSC_FAULT_NHSC_MODEHSC_D_OC_RHSC_FAULTHSC_D_OCHSC_VTEMPHSC_OCREF0C0402X6S1/16WCHIP1/16W0402LF1%0EMPTYHSC_IMON0402LF5%025V1UF0.1%HSC_VSENSEHSC BOM1HSC BOM10.01UF75K0.1%1/16WCHIPHSC BOM10402LFSMLF1/16WCHIP0402LF1%CHIP1/16WCHIP1/16WHSC BOM10402LF1%0402LFHSC BOM150VC04020.1%HSC_CS1/16WHSC BOM10402LFHSC_VOSEN1/16WC0402X7R16V0.068UFHSC BOM1CHIPCHIP1/16W1%HSC BOM16.19KHSC_FLT_TYPE0402LF0402LFCHIP1/16W0.1%4.99KMP5990GMA-1111-ZSMLFHSC BOM1
Anode_2CathodeAnode_1
R3909
15
36
35
34
33
32
31
30
29
28
27
249
14
43
42
8
7
6
5
4
3
2
1
45
17
19 16
12
25
11
13
38
22
41
21
39
44
18
40
26
37
2010
23
K21
R2587R3936
PD111
PR1133
PR3937
PC2193
PR3935
R3934
R2588
PC2192
PC2191
PC2190
PR1131
R3933
PC2189
PU289
PR2106
R2586
PR3929
PR3930
PR3928
PC2103
PC2188
PR2149
R1714
R3925
PC2187PC2186
R3924
R1117
ADDR
VDD18
VDD33_2
VDD33_1
VINSEN
VIN10
FLT_TYPE
GND2
VIN1
VOUT4
VOSEN
VOUT10
VIN9
CS
IMON
VOUT6
SS
SCREF_OCWREF
OCREF
VTEMP
VIN6
VIN5
ON
VOUT8
PG||OCW#
VIN8
MODE
VOUT7VIN7
GOK
ALT#
VOUT9
VOUT5
D_OC
SCL
VIN_UVW#
SDA
GND1
VIN4
VIN3
EN
VIN2
VOUT1
VOUT2
VOUT3
2
1
2
1
21
2
1
2
1
21
21
2
1
2
1
2
1
2
1
2
1
21
2
1
2
1
21
21
21
2
1
2
1
2
1
2
1
21
2
1
2
1
21
2
1
21
21212121
SHEETDATE
DEPARTMENT
SIZE
PROJECT DOCUMENT NUMBER REV
REVIEWER
DESIGNER
123
7 3 2 1 6 5 4
E
A
B
C
E
D
C
B
A
7 6 5 4
D
OUT
OUT
IN
IN
OUT
OUT
IN
IN
OUT
OUT
OUTIN
OUT
IN
BI
OUT
PR3931
PR3932
PR3926
PR3927
C



HOT SWAT CIRCUIT
SOFT START TIME=6MS.VOUT SLEW RATE: 2V/MSSOFT START TIME=6MS.VOUT SLEW RATE: 2V/MSThu Sep 14 16:12:22 2023MB FABCGT AMD263 OF 365V02<NAME_2><NAME_1>
AGND_HSCAGND_HSCHSC_VDDAGND_HSCP12V_PSUAGND_HSC
AGND_HSCAGND_HSCAGND_HSC
P12V_PSU
AGND_HSCP12V_AUXP12V_AUXHSC_VDD
2632641/16W0.068UFHSC_VTEMPHSC_FAULTHSC_SCREF_2HSC BOM1HSC BOM11/16WHSC BOM1HSC BOM11%0402LF5%CHIPHSC_SCREF_1HSC_CS_1HSC BOM10402LFHSC BOM1264HSC BOM1
264 265 263264 265 263264 265 263265263
263 264 265264 265 263264 265 263264265263263265
263 264 265
263264265
263264265264 265 263263 264 265263264265264265263264265263 264 265HSC_FAULTHSC_VTEMP16VHSC BOM10.068UF04020402LF1/16WHSC_D_OC_20HSC BOM1HSC_D_OC_RCHIP0402LFHSC BOM1HSC_IMON1/16WCHIPHSC BOM1HSC_CS_2CHIP5%00402LF0402LF50V0.1%2KHSC BOM1HSC BOM1EMPTYHSC BOM11/16W0402LF0CHIP5%MP5991GLU-ZHSC BOM1HSC BOM1CHIPHSC_FLT_TYPECHIP5%HSC BOM1HSC_D_OC_1 HSC_D_OC_RHSC_FLT_TYPE_11/16W5%01/16W00402LF2K2KHSC_IMONMP5991GLU-ZSMLFHSC BOM1HSC_VDD_R_1HSC_OCREF0.1%1/16WEMPTY0.1%1/16W50VCHIPHSC BOM11NFHSC BOM10402LF1UFSMLF04021NF2KIC0402
C040225V00402X7R120K0402CHIP0IC
X7R01UFCHIP5%0402X7R16V
HSC MP5990 (2/3)HSC_NC1_2HSC_SS
HSC_SCREFHSC_MODE_2HSC_OCREFHSC_VDD_R_2HSC_SSHSC_ONHSC_MODE_15%CHIP1/16WX6SCHIP1/16W0402LF50V220PFHSC_NC1_10402LF0402LFHSC BOM125VX6SC0402HSC BOM11%1/16W0402LFCHIP120KHSC BOM1HSC_SCREFHSC_ON1/16W50VEMPTY220PF0.1%HSC_FLT_TYPE_21/16W5%CHIPHSC BOM1HSC_FLT_TYPE0402LF
PC2348
18
32
31
30
29
28
27
26
25
2
1
33
16
15
14
13
12
11
10
9
21
19
17
4
24
7
8
22
5
20
6
3
23
18
32
31
30
29
28
27
26
25
2
1
33
16
15
14
13
12
11
10
9
21
19
17
4
24
7
8
22
5
20
6
3
23
PR3919
PR3920
PC2184
PR3921
PR3922
PC2185
PU287
PR3918
PR3916
PR3914
PC2347
PR1134
PC2182
PR3910
PC1525
PR3917
PU288
PR1101PR3915
PR3912
PR3911
PC2181
PC2183
NC1
FLT_TYPE
SCREF_OCWREF
MODE
VOUT10
VOUT9
VOUT8
VOUT7
VOUT6
VOUT5
VIN9
VIN8
VIN7
VIN6
D_OC
VOUT4
VOUT3
VOUT2
VOUT1
VTEMP
GOK
SS
GND
VDD33
IMON
CS
OCREF
ON
VIN5
VIN4
VIN3
VIN2
VIN1
NC1
FLT_TYPE
SCREF_OCWREF
MODE
VOUT10
VOUT9
VOUT8
VOUT7
VOUT6
VOUT5
VIN9
VIN8
VIN7
VIN6
D_OC
VOUT4
VOUT3
VOUT2
VOUT1
VTEMP
GOK
SS
GND
VDD33
IMON
CS
OCREF
ON
VIN5
VIN4
VIN3
VIN2
VIN1
21
21
2
1
21
21
2
1
2
1
21
2
1
2
1
21
2
1
2
1
21
2
1
2
1
2
1
21
2
1
2
1
2121
SHEETDATE
DEPARTMENT
SIZE
PROJECT DOCUMENT NUMBER REV
REVIEWER
DESIGNER
123
7 3 2 1 6 5 4
E
A
B
C
E
D
C
B
A
7 6 5 4
D
IN
IN
OUT
IN
OUT
OUT
IN
OUT
IN
OUT
OUT
IN
OUT
IN
IN
IN
OUT
IN
C



HOT SWAT CIRCUITSOFT START TIME=6MS.VOUT SLEW RATE: 2V/MSSOFT START TIME=6MS.VOUT SLEW RATE: 2V/MSThu Sep 14 16:12:22 2023MB FABCGT AMD264 OF 365V02<NAME_2><NAME_1>
HSC_VDD
AGND_HSCAGND_HSCAGND_HSCP12V_PSU
AGND_HSCP12V_PSUAGND_HSCAGND_HSCAGND_HSCAGND_HSCP12V_AUXP12V_AUX
HSC_VDD264MP5991GLU-ZMP5991GLU-ZHSC BOM10402LF1/16W0.1%HSC BOM10402LFHSC BOM1
265263263264265
264 265 263263 264 265263264265264265263263 264 265264 265 263263264265263264265263264265264 265 263263 264 265263264265264 265 263264 265 263264 265 263263 264 2650402LFHSC_CS_4HSC_IMONHSC BOM1HSC BOM1HSC BOM150V 50V 1/16W0402LFHSC BOM10.1%2KC0402EMPTY1NF220PFCHIPHSC_ONHSC BOM1HSC BOM1X6S25V1UFCHIP1/16W5%HSC BOM10402X7R16V0.068UF0402LFCHIP5%CHIP5%0HSC BOM10402LFHSC_D_OC_3 HSC_D_OC_RHSC_FLT_TYPEHSC_FLT_TYPE_3SMLFICHSC_VDD_R_31%120K1/16W0402LFCHIPHSC_ONHSC BOM1HSC_IMON1/16WHSC_MODE_3HSC BOM11/16WHSC_SCREF_31/16W CHIP0402CHIP0.1%2K0402LFCHIP1/16W05%1/16WSMLFICEMPTY0402
1UFC040205%CHIPEMPTY1/16W CHIP0402EMPTYCHIP2K2KCHIP0402X7R5%1/16W01/16W0HSC MP5990 (3/3)
HSC_NC1_3HSC_FLT_TYPEHSC_D_OC_RHSC_SCREFHSC_MODE_4HSC_SCREFHSC_OCREFHSC_FAULTHSC_SSHSC_SCREF_4HSC_VDD_R_4
HSC BOM1HSC BOM10402LF0402LF5%0X6S25V50VHSC BOM150VHSC_OCREF220PF04021NF0.1%HSC_CS_3HSC BOM1HSC BOM1HSC BOM1HSC_VTEMP0402LF0402LF1%120KHSC BOM1HSC BOM1HSC_VTEMPHSC_FAULTHSC_NC1_4HSC_FLT_TYPE_40HSC BOM15%01/16WHSC_D_OC_40402LFCHIPCHIP1/16W0402LFHSC BOM1HSC_SSHSC BOM116V0.068UF
18
32
31
30
29
28
27
26
25
2
1
33
16
15
14
13
12
11
10
9
21
19
17
4
24
7
8
22
5
20
6
3
23
18
32
31
30
29
28
27
26
25
2
1
33
16
15
14
13
12
11
10
9
21
19
17
4
24
7
8
22
5
20
6
3
23
PR3992
PR3993
PC2226
PR3994
PR3995
PC2227
PR3990
PR3988
PR3986
PR3982
PC2224
PR3980
PC3272
PR3989
PR3991PR3987
PR3984
PR3981
PC2223
PC2225
NC1
FLT_TYPE
SCREF_OCWREF
MODE
VOUT10
VOUT9
VOUT8
VOUT7
VOUT6
VOUT5
VIN9
VIN8
VIN7
VIN6
D_OC
VOUT4
VOUT3
VOUT2
VOUT1
VTEMP
GOK
SS
GND
VDD33
IMON
CS
OCREF
ON
VIN5
VIN4
VIN3
VIN2
VIN1
NC1
FLT_TYPE
SCREF_OCWREF
MODE
VOUT10
VOUT9
VOUT8
VOUT7
VOUT6
VOUT5
VIN9
VIN8
VIN7
VIN6
D_OC
VOUT4
VOUT3
VOUT2
VOUT1
VTEMP
GOK
SS
GND
VDD33
IMON
CS
OCREF
ON
VIN5
VIN4
VIN3
VIN2
VIN1
21
21
2
1
21
21
2
1
2
1
21
2
1
2
1
21
2
1
2
1
21
2
1
2
1
2
1
21
2
1
2
1
2121
PC2350
PC2349
SHEETDATE
DEPARTMENT
SIZE
PROJECT DOCUMENT NUMBER REV
REVIEWER
DESIGNER
123
7 3 2 1 6 5 4
E
A
B
C
E
D
C
B
A
7 6 5 4
D
IN
OUT
IN
OUT
OUT
IN
IN
OUT
IN
OUT
OUT
IN
OUT
IN
IN
IN
OUT
IN
C
PU296
PU297



Thu Aug 24 10:15:57 2023<NAME_2><NAME_1>MB FABCGT AMDV02265 OF 365Blank
SHEETDATE
DEPARTMENT
SIZE
PROJECT DOCUMENT NUMBER REV
REVIEWER
DESIGNER
123
7 3 2 1 6 5 4
E
A
B
C
E
D
C
B
A
7 6 5 4
D
C



FPH=220AOCW=220ALATCH OFF MODERDS(ON)=0.76M OHMAT 4.5V, ID=300AUV =10.091VOV =14.333VOCP=240AHOT SWAT CIRCUIT
Thu Sep 14 16:12:45 2023<NAME_2><NAME_1>MB FABCGT AMDV02266 OF 3651NFC0402EMPTY10%50VEMPTY101%10MB0_CM_GATE_G0ICP12V_HSC_SENSE2_R1_NP12V_HSC_SENSE2_R3_N0.0003CHIPSMLF4WP12V_HSC_SENSE2_R2_NSMLFP12V_HSC_SENSE1_P2W0.003P12V_HSC_SENSE2_R1_NP12V_HSC_SENSE2_R2_NP12V_HSC_SENSE2_R2_PP12V_HSC_SENSE2_R3_PP12V_HSC_SENSE2_R4_P10HSC BOM2P12V_HSC_SENSE2_R1_NP12V_HSC_SENSE2_N1%CHIPCHIPP12V_HSC_SENSE2_R2_NP12V_HSC_SENSE2_R3_NHSC BOM2HSC BOM2HSC BOM2HSC BOM2P12V_HSC_SENSE2_R3_NP12V_HSC_SENSE2_R4_N1%1%HSC BOM21/16W1%P12V_HSC_GATE_G1P12V_HSC_GATE_G2P12V_HSC_SENSE1_NP12V_HSC_SENSE2_R1_PP12V_HSC_GATE1P12V_HSC_GATE2P12V_HSC_SENSE2_R3_P
P12V HOTSWAP FOR MODULE(1/2)
PR6002 CHANGE TO CS+003DFR03
CHIP10 1%CHIP1%1%CHIPCHIP1%ICCHIPPSMNR58-30YLHSMLF1/16W0402ICEMPTYIC1%100402LFCHIPCHIP1 4WCHIP1%1%0.00031%CHIP1 10CHIP0402LFIC0402LF10ICSMLF0402LF1/16W10CHIP0402LF1%
111%1CHIPCHIPHSC BOM2HSC BOM21%CHIPHSC BOM2HSC BOM2HSC BOM21%1%1%CHIPCHIPCHIPCHIPP12V_HSC_ADC_PP12V_HSC_SENSE2_R1_PP12V_HSC_SENSE2_R2_PP12V_HSC_SENSE2_R3_PP12V_HSC_SENSE2_R4_P0402LF1%CHIPP12V_HSC_SENSE1_PP12V_HSC_ADC_N11%1%10CHIP10101010100HSC BOM211%CHIPHSC BOM211%CHIPHSC BOM21%1010P12V_HSC_SENSE2_R4_NHSC BOM2HSC BOM2HSC BOM2HSC BOM2SMLFSMLF0.0003P12V_HSC_SENSE2_R2_PSMLF4W0.0003P12V_HSC_SENSE2_R4_NP12V_HSC_SENSE2_R4_P4WHSC BOM2SMLFP12V_HSC_SENSE1_NHSC BOM2HSC BOM2HSC BOM2HSC BOM2CHIPP12V_HSC_SENSE2_R1_P1%PSMNR58-30YLHHSC BOM2HSC BOM2101%1/16WCHIP0402LFHSC BOM2SMLFHSC BOM2ICSS15P3S-M3/86AHSC BOM2P12V_HSC_GATE_RC0402LF10%25V33NFHSC BOM21%1/16WHSC BOM2HSC BOM2PSMNR58-30YLHSMLFP12V_HSC_GATE_G61/16W0402LFCHIPHSC BOM2SMLFPSMNR58-30YLHP12V_HSC_GATE_G51/16W1%HSC BOM2HSC BOM2HSC BOM2ICP12V_HSC_GATE_G41%1/16WCHIPP12V_HSC_GATE_G3SMLFPSMNR58-30YLHHSC BOM2PSMNR58-30YLHSMLF1%HSC BOM2HSC BOM2PSMNR58-30YLHHSC BOM2CHIP1/16W10HSC BOM2HSC BOM2267267267268 267267267267267267267268267267267267268267267268268267268267267267267268267268268267267267267268267267P12V_MAIN_R_0P12V_PSUP12V_MAIN_RP12V_AUXP12V_HSC_SENSE2_P
Anode_2CathodeAnode_1
PR2527
PR2526
PR2525
PR2524
PR2519
PR2518
PR2517
PR2516
PR2515
PR2514
2B
2A
1B
1A
4
44
2B
2A
1B
1A
2B
2A
1B
1A
5321K2153215321
PR6002
PPQ7 PPQ8
PPQ9
PD17
PPQ2
PR2536
PPQ1
PR2535
PR6001
2B
2A
1B
1A
PR2532
PR2533
PR2534
PR2531
PPQ6
PR2530
PPQ5
PR2529PR2528
21PR2510
21PR2511
PR2512
PR2513
21PR2520
PR2522
21PR2521
PR2523
1A 2A
1B 2B
D1
G1
S3 S2 S1
4
D1
G1
S3 S2 S1
4
D1
G1
S3 S2 S1
4
D1
G1
S3 S2 S1
4
D1
G1
S3 S2 S1
4
1A 2A
1B 2B
1A 2A
1B 2B
1A 2A
1B 2B
1A 2A
1B 2B
D1
G1
S3 S2 S1
4
D1
G1
S3 S2 S1
4
12531253
12531253125312531253
21
21
21
21
21
21
21
21
21
21
2
1
2
1PR2537
2
1PC1751
2
1
2
1
2
1
21
21
21
21
BOM NOTE:
4 4
2B2A1B1A
44
5321532153215321
SHEETDATE
DEPARTMENT
SIZE
PROJECT DOCUMENT NUMBER REV
REVIEWER
DESIGNER
123
7 3 2 1 6 5 4
E
A
B
C
E
D
C
B
A
7 6 5 4
D
OUT
OUT
OUT
OUT
OUT
IN
OUT
OUT
OUT
OUT
OUT
OUT
IN
IN
IN
IN
IN
OUT
IN
IN
IN
IN
IN
OUT
IN
IN
IN
IN
OUT
IN
IN
IN
IN
IN
PR2538
PC1750
C



LTC4282=1.0VLTC4287=1.5VQ6001 CLOSE TO MOSFETADDRESS: 0X98 (8-BIT)ADDRESS: 0X4C (7-BIT)OC DETECT ON MODULEPROCHOT
MAIN SOURCE:AL007718001 (NCT7718W(MSOP))2ND SOURCE:AL000788001 (G788P81U(MSOP8))UThu Sep 14 16:12:45 2023<NAME_2><NAME_1>MB FABCGT AMDV02267 OF 365
EMPTY0.1UFHSC BOM2P3V3_AUXHSC BOM21/16WC0402P3V3_AUXP3V3_AUXP3V3_AUXP3V3_AUXP3V3_AUX
P3V3_AUXP3V3_AUX
P3V3_AUXP12V_AUXP12V_PSUP3V3_AUXP12V_AUXP3V3_AUX54.9KSCONN21_91930-31121LFMB0_P12V_STBY_PWRGDSMB_SML1_PMBUS_HSC_R1_SCLIRQ_SML1_PMBUS_ALERT_NSMB_SML1_PMBUS_HSC_R1_SDA2682432630402LFHSC_TYPE_ADCCHIPHSC_CSOUTIRQ_HSC_FAULT_NSMLF8026985263HSC_EN2692632692721%268 267267267267267253 26882253 268253 268267268 82253 268
26380268268189254151151263267267SMLFMETR3904-GHSC BOM2P12V_HSC_TEMP_RP12V_HSC_TEMP_E1/16W0402LF CHIP1/16WP12V_HSC_TEMP_D-C0402HSC BOM20402LF1/16W10.5KHSC BOM2CHIP1/16W1%P12V_HSC_TEMP_ALERT_NSMB_P12V_HSC_TEMP_SDASMB_P12V_HSC_TEMP_SCLCHIP5%1/16WHSC BOM2HSC BOM22.2K2.2K1/16WCHIPHSC BOM2HSC BOM2100NFHSC BOM2AP331AWG-7EMPTYEMPTY0402LF10K1/16WLM4040AIM3X-2.5/NOPB0402LFHSC BOM21%1/16WEMPTY10KOC_P2V5_COMPHSC_OC_VOL1%1/16WHSC BOM21/16W5%HSC BOM20402LFHSC BOM2EMPTYHSC BOM2EMPTY0.1UFA_HSC_LOWA_HSC_HIGHHSC BOM20402LFEMPTY1/16W160KHSC BOM21%0402LFEMPTY1/16WHSC BOM2HSC BOM2160K1%10KEMPTYHSC BOM21K25V1UF04021/16W1/16WEMPTY10KHSC_CSOUTP12V_PSUP12V_HSC_SENSE1_PP12V_HSC_SENSE1_NP12V_HSC_SENSE2_PP12V_HSC_SENSE2_NP12V_HSC_ADC_P0EMPTYA_HSC_LOW_DRAIN
SMB_P12V_HSC_SDAP12V_HSC_TEMP_ALERT_R_NSMB_P12V_HSC_SCLSMB_P12V_HSC_SDAP12V_HSC_T_CRIT_NP12V_HSC_ADC_NHSC_CSOUTP12V_HSC_T_CRIT_R_NSMB_P12V_HSC_SCL
HSC_D_OCU142_VS
P12V HOTSWAP FOR MODULE(2/2)
0402LFEMPTY1/16W10K1%EMPTY33.2C040250VEMPTYC0402EMPTYSMLFNCT7718WIC0402LF0402LF5%0CHIP
1/16W00402LF05%1/16WEMPTY10K1%SMLFEMPTY10K1%1%0402LFCHIP0402LF0402LF00402LF06035%0402LF00402LF10%04020.1UFX7R25V10%EMPTY1%10%
1/16WIC
25VC04020402LFCHIPHSC BOM2HSC BOM22N7002KEMPTY0402LFA_HSC_LOW_GATE0402LFCHIP1/16W0402LFHSC BOM25%LT6700CS6-1#TRPBFSMLFHSC BOM21/16WEMPTY0402LFHSC BOM21%0402LF1MEMPTYHSC BOM2SMLF0402LFHSC BOM2160K1%1/16WHSC BOM210%50V100NFEMPTY10%HSC BOM2HSC BOM250V10%EMPTYHSC BOM2SMLFHSC_D_OC_R2 A_HSC_LOW_GATEHSC BOM21%100NFIOP12V_HSC_GATE1P12V_HSC_GATE2P12V_AUXHSC BOM25%1/16W1%HSC BOM210.5K1/16WCHIP5%1/16W0402LFCHIP5%0CHIPHSC BOM2HSC BOM2HSC BOM2HSC BOM2CHIP1%HSC BOM249.9HSC BOM249.91%HSC BOM2X7R10%50V1000PFP12V_HSC_TEMP_D+X7R10%16V1%HSC BOM21/16W
G
S D
C1786
R353
R2626
R2627
R2628
U8005
C9003
OUTPUT
IN-
IN+
GND VCC
C6084
C8014
R354
R6239
R6233
R6231R6230
R2625
R2624
4
1
3
3
2
1
G
5
6
1
4
3
2
G2
G1
21
20
19
18
17
16
15
14
13
12
11
10
9
8
7
6
5
4
3
2
1
1
4
7
8
5
3
2
6
C1787
52
S D
R9020
U8006
U6004U142
PJ38
U143
Q6001
SCL
SDA
ALERT#
GNDT_CRIT#
D-
D+
VDD
S
G
D
OUTB
INA+ OUTA
GND
INB-
VS
21
20
19
18
17
16
15
14
13
12
11
10
9
8
7
6
G2
G1
2
5
4
3
1
+
-
3
2-
1+
1
32
2
1
R9024
2
1
2
1
2
1
21
2
1
21
2
1 C8016
2
1 C8015
2
1
2
1
2
1
2
1
2
1
2
1
21
2
1
R6238
2
1
2
1
R6237
2
1
2
1
2
1
2
1
2
1
2
1
2
1
2
1
2
1
21
21
21
21
21
2
1
B
CE
SHEETDATE
DEPARTMENT
SIZE
PROJECT DOCUMENT NUMBER REV
REVIEWER
DESIGNER
123
7 3 2 1 6 5 4
E
A
B
C
E
D
C
B
A
7 6 5 4
D
OUT
OUT
OUT
IN
OUT
OUT
OUT
ININ
ININ
IN
OUTIN
OUT
OUT INOUT
OUTIN
OUTBI
IN
BI
OUT
IN
IN
R8111
R8110
R8108
R8109
R8107
R355
R6236
R6235
R6232
PC1789
C
R8112
21
R6234
R6210



NOTE:NEED TO SET UV VOLJUMPER 1-2Thu Sep 14 16:12:44 2023<NAME_2><NAME_1>MB FABCGT AMDV02268 OF 365
AGND_HSC0402LF1/16WI42P12V_AUX P3V3_AUXP12V_AUX
P12V_AUXP12V_AUXP3V3_AUXP3V3_AUXP12V_PSUP3V3_AUXP12V_AUXP12V_AUXP12V_AUXP3V3_AUXP3V3_AUX1512681512682698026980
263 268
269
2692698026980241
U206_VS267K1/16W25VCONN3_210-HP1-030BR1THLFIOSMB_SML1_PMBUS_HSC_R1_SDASMB_SML1_PMBUS_HSC_R1_SCL10%EMPTYLT6700CS6-1#TRPBF10K0402LF1UF25VEMPTY04020.1UF10%C04021/16W1KEMPTY1%SMLFEMPTY0402LF0402LFFM_UV_ADR_TRIGGER_NEMPTY1/16W5%CONN3_210-HP1-030BR1VR_DDR1_POWER_STAGETHLFSMLFLM4040AIM3X-2.5/NOPBP12V_AUX_UV_TRIGGERICAP331AWG-7BSS138K0402LFEMPTYIRQ_UV_DETECT_N1/16WA_P12V_STBY_FPH_GATE1%1KEMPTYA_P12V_STBY_ADR_TRIGGERA_P12V_STBY_FP_TRIGGER0402LFEMPTY26.7K0402LFEMPTY1/16W1/16WEMPTY50VCHIP33.2C040217.8K1%1/16WCHIP0402LFCHIP1/16WCHIPSMLFIRQ_UV_DETECT_R2_NAP331AWG-7EMPTYC0402X7R10%SMLFUV_ADR_P2V5_COMPP12V_AUX_UV_ADR_TRIGGER100NF10%CHIP100NFCHIP1%0402LF1/16WBSS138K1%1%0402LF0402LF1K1%1%EMPTY
IC1%EMPTY1%0402LF1%10K0402LF1%100NFIC10%C0402100NF50V17.8K10K1%C0402HSC_EN50VC0402HSC Shared Circuit
IC20A/125VSMLFIC5.0SMDJ14AICSMLF5.0SMDJ14AP12V_PSU_FUSESMLF0CHIP
2N7002KICSMLF10%100NFX7R50VC0402IO0402LFCHIP1%1/16W82KCHIP31.6K1%0402LF1/16WVR_DDR1_POWER_STAGEVR_DDR1_POWER_STAGE0402LF63.4K1/16W1%0402LF1/16W1%33K0402X7R25V10%0.1UFP12V_PSU_FUSE50V1/16W1% 1MSMLF0402LFUV_P2V5_COMP5.11K1%1/16WEMPTY10% 10%50V100NFICCHIP1/16W5.11KCHIP0402LFEMPTY0402LF1%1%CHIPLM4040AIM3X-2.5/NOPBCHIPC040210K1/16W1K1/16W1/16WFM_UV_ADR_TRIGGER_N_R233.21%100NF50V10%X7REMPTY0402LF1/16W1MCHIP0402LFFM_UV_ADR_TRIGGER_N1/16W1%1KIRQ_UV_DETECT_N1K1%1/16W0402LFCHIPPDB_PRSNT_R_N
G
S D
U290
C9004
OUTPUT
IN-
IN+
OUTPUT
IN-
IN+
GND VCCGND VCC
R4620
R2227
G
S D
3
2
1
3
2
1
4
1
3
4
1
3
3
2
1
5
6
1
4
3
2
3
2
1
G
5252
S D2 1CACA
JP10
R9021
U8009
U8010
U8008
U8007
U206
2
1
R2233
2
1
R2230
U325
2
1
R2221
2
1
R2222
2
1
R2219
PR3002
C2179
R4901
JP4003
R3923
R2585
R3907
FS1
PD13PD15
3
2-
1+
+
-
+
-
3
2-
1+
OUTB
INA+ OUTA
GND
INB-
VS
1
2
3
S
G
D
1
2
3
2 1CACA
2
1
2
1
2
1
2
1
2
1 C8021
21R8124
2
1 C8022
21
2
1 C8020
2
1
2
1
2
1
2
1
21
2
1 C8019
21
2
1
2
1
2
1
2
1
2
1
2
1
2
121
2
1
21
2
1
R8117
SHEETDATE
DEPARTMENT
SIZE
PROJECT DOCUMENT NUMBER REV
REVIEWER
DESIGNER
123
7 3 2 1 6 5 4
E
A
B
C
E
D
C
B
A
7 6 5 4
D
OUT
IN
OUT
OUT
OUT
OUT
IN
OUT
BIIN
R8125
C1561
R8120
R8119
R8118
R8113
C1797
C
R8123
R8121
R8122
C8017
R8114
R8115 C8018



1ST AL008626000/MPQ8626GD-Z/MPS2ND AL053317005/RS53317LR/REEDSEMI3RD AL54J061000/TPS54J061RPGR/TIIC TABLE1STR&C TABLE3RD2NDR2
TDC=2.0AMAX CURRENT=2.0ATRANSIENT TOLERANCE<100MVOUTPUT RIPPLE<30MVOUTPUT VOLTAGE=1.8V +/-5%DESIGN SPECIFICATION
VOUT=0.6(1+R1/R2)=1.8V
EFFICENCY>90%@TDCWORK FREQUENCY=600KHZSLEW RATE=2.5A/USOVER CURRENT PROTECTION(IMAX*1.3)=3A
R1FCCM/FREQ.=600KHZENABLE: VIH>1.27V7.3*6.6*3ISAT=12A @100CDCR=30 MOHMPCMC063T-3R3MNRCS=10K OCP=3AThu Sep 14 16:12:47 2023<NAME_2><NAME_1>MB FABCGT AMDV02269 OF 365
P1V8_AUXP3V3_AUXP12V_AUXP3V3_AUX1%10KC0402SW_P1V8_AUX_BT_RC0402SW_P1V8_AUX_PHX7R0.22UF10%25V2.2SW_P1V8_AUX_BT3.3UH/6ASMLFIND10%X7R100NFC040250V22UF4VC0805X6S20%1/16WCHIP0402LFCHIPP1V8_AUX_REF0402LF1/16W3300PF50V0402LF0402LF1/16WP1V8_AUX_MODECHIP0.1UFC0805X6S16V20%C040222UFMPQ8626GD-ZICSMLFC040225V1UF040210%10%330PF040250VX7R1%10K22UF4V 4V22UF20%X6SC0805X6S22UFC080520%4V100NFINDSMLFBLM18SN220TN1D/8000MA22UFP1V8_AUX_FBP1V8_AUX_CS20%X6SC08051%X7R10K10%X6SP1V8_AUXP1V8_AUX_VCCC08050402LF25V1/16W5%0402PWRGD_P1V8_AUX_R
05%1/16WEMPTY10%25V1UF60.4KCHIP1%X6S10%X6S16VSW_P12V_AUX_P1V8_AUX_FLTP1V8_AUX_ENABLE1/16WCHIPPWRGD_P3V3_AUX50V10%X7R020%20K1%0402LF0402LF CHIP1%PWRGD_P1V8_AUXCHIP1/16W0402LF33271255148818581190
R214
PC850PC867PC866
R6243
PC641
PC865
PR6007
PC6021
PC6019
PL6000
PR6010
PC384
PC6010
PU6000
PR6006
PC6008
PC6014PC6012
PL6002
PC6020
R6242
PR8003
21
3
13
8
11
2
9
14
1
12
6
5
4
10
7
21 1 2
1 2SW1
CS
MODE
TRK_REF
SW2
PGND1
VCC
AGND
FB
BST
EN
PGND2
PGOODVIN
21
21
2
1
21
2
1
2
1
2
1
2
1
2
1
2
1
21
2
1
212
12
1
2
1
21
2
1
2
1
2
1
2
1
2
1
21
C345
SHEETDATE
DEPARTMENT
SIZE
PROJECT DOCUMENT NUMBER REV
REVIEWER
DESIGNER
R6119
123
7 3 2 1 6 5 4
E
A
B
C
E
D
C
B
A
7 6 5 4
D
OUT
IN
PR6003
C



3RD AL54J061000/TPS54J061RPGR/TI2ND AL053317005/RS53317LR/REEDSEMI1ST AL008626000/MPQ8626GD-Z/MPSR&C TABLE7.3*6.6*3ISAT=13.5A @100CPCMC063T-2R2MNDCR=20 MOHMR2VOUT=0.6(1+R1/R2)=1.2VENABLE: VIH>1.27VFCCM/FREQ.=600KHZOUTPUT RIPPLE<30MVTDC=1.6ADESIGN SPECIFICATIONOUTPUT VOLTAGE=1.2V +/-5%TRANSIENT TOLERANCE<100MVEFFICENCY>90%@TDCWORK FREQUENCY=600KHZSLEW RATE=2.5A/USOVER CURRENT PROTECTION(IMAX*1.3)=3AMAX CURRENT=2.1A
IC TABLE1ST2NDR13RDRCS=11.5K OCP=3AThu Sep 14 16:12:47 2023<NAME_2><NAME_1>MB FABCGT AMDV02270 OF 365I15I4I36 I30I8I22I14I20I1I5P3V3_AUXP3V3_AUXP12V_AUXP1V2_AUX8125527081148255SW_P1V2_AUX_BT_RCHIP1%0402LFSW_P1V2_AUX_BTPWRGD_P1V2_AUX_R0402LF10KX7R1/16WP1V2_AUX_VCC60.4K0402LF5%P1V2_AUX_ENABLEC0805C040222UF10%X7R16V20%X6SC0805 C04021%BLM18SN220TN1D/8000MA50V100NFP1V2_AUX_REF01/16W10%11.5K1%C040225VCHIPX6S025V0.1UFX6S16V
P1V2_AUX
1/16WSW_P12V_AUX_P1V2_AUX_FLTP1V2_AUX_CSP1V2_AUX_MODECHIP1/16WX6S22UFC080520%4V22UF20%X6S10%330PF040250VX7R0402LFINDSMLF1%10%MPQ8626GD-ZICSMLFX6S10%25V1UF1%22UF20%EMPTYCHIPCHIP10K50VP1V2_AUX_FB00402LF1%1/16W04023300PF10K1/16WCHIP040210%1UF0402LF0402LFCHIP5%1/16W0402LF1/16WPWRGD_P1V8_AUX_RC08054VPWRGD_P1V2_AUX5%4VC0805X6S20%22UFC080522UF4V20%X6S100NF50V10%X7RC04022.2UHSMLFINDC0402X7R10%25V0.22UFSW_P1V2_AUX_PH2.20402LFCHIP
PC6023
PC6018PC6026PC6025PC6024
PR6008
PC852
PL6001
PC6022
PR6011
R6244
PC6017
PC6016
PU6001
PC6011
PR6005
PC6015
PC6009
PR6004
PC6013
PL6003
R6245
21
3
13
8
11
2
9
14
1
12
6
5
4
10
7
21
1 2
1 2
SW1
CS
MODE
TRK_REF
SW2
PGND1
VCC
AGND
FB
BST
EN
PGND2
PGOODVIN
21
21
2
1
21
2
1
2
1
2
1
2
1
2
1
21
21
2
1
2
1
2
1
2
1
2
1
2
1
21
2
1
2
1
2
1
2
1
21
C6085
SHEETDATE
DEPARTMENT
SIZE
PROJECT DOCUMENT NUMBER REV
REVIEWER
DESIGNER
R6241
R6240
123
7 3 2 1 6 5 4
E
A
B
C
E
D
C
B
A
7 6 5 4
D
OUT
IN
PR8004
C



ADDRESS : 0X84 (8-BIT)0X42 (7-BIT)
Thu Sep 14 16:12:48 2023<NAME_2><NAME_1>MB FABCGT AMDV02271 OF 365
P3V3_AUXP3V3_AUX236253253236268POWER MONITOR WILL CHANGE TO AL000230001
POWER MONITOR (3/4)
ICSMLFISL28022FRZ-T1/16W0402LF5%0CHIP4.7K1%1/16WCHIP0402LFX7R0.1UF25V10%0402X7R040210%0.1UF25V33.21%CHIP33.20402LF 1/16W1%CHIP1/16W1%CHIP 0402LF4.7K0402LFEMPTY1%4.7K 1/16WHSC_TYPE_ADC_A0SMB_HSC_TYPE_ADC_SDANC_HSC_TYPE_VINPHSC_TYPE_ADC_ALERTNC_HSC_TYPE_NC0NC_HSC_TYPE_NC1NC_HSC_TYPE_NC2NC_HSC_TYPE_NC3NC_HSC_TYPE_NC4NC_HSC_TYPE_NC5SMB_HSC_TYPE_ADC_SCLHSC_TYPE_ADC_A1SMB_LM75_0_3V3AUX_SCLSMB_LM75_0_3V3AUX_SDAHSC_TYPE_ADCNC_HSC_TYPE_VINM
R6250
R6254
R6251
13
12
9
11
TH
4
5
16
15
14
8
7
6
10
3
1
2
U6005
TH_GND
GND
NC5
NC4
NC3
NC2
NC1
NC0
EXT_CLK||INT
VINM
VINP
VBUS
SDA||SMBDAT
SCL|||SMBCLK
A0
A1
VCC
21
2
1
2
1
2
1
21
2
1
21R6253
21R6252
BOM NOTE:
SHEETDATE
DEPARTMENT
SIZE
PROJECT DOCUMENT NUMBER REV
REVIEWER
DESIGNER
123
7 3 2 1 6 5 4
E
A
B
C
E
D
C
B
A
7 6 5 4
D
INBI
IN
R6247
C6087
C6086
C



P/N SWAPP/N SWAPP/N SWAPP/N SWAPP/N SWAPP/N SWAPP/N SWAPP/N SWAPP/N SWAPP/N SWAPP/N SWAPP/N SWAPP5E_CPU0_P0_TX_C_DP/DN<0-15> LANE REVERSAL
CPU TO RETIMERCPU TO RETIMER
P/N SWAPP/N SWAP
Thu Sep 14 16:12:49 2023<NAME_2><NAME_1>MB FABCGT AMDV02272 OF 365
63636363SMLFPT5161LRSIC PT5161LRSIC
RETIMER_CPU0_P0(1)
SMLFP5E_CPU0_P0_TX_C_DP<7:0>P5E_CPU0_P0_TX_C_DN<7:0>P5E_CPU0_P0_TX_C_DN<15:8>P5E_CPU0_P0_TX_C_DP<15:8>
EV34
EL34
ED34
DU34
DK34
DC34
CT34
CJ34
EY35
EN35
EF35
DW35
DM35
DE35
CV35
CL35
CB34
BR34
BH34
BA34
AP34
AG34
Y34
N34
CD35
BU35
BK35
BC35
AT35
AJ35
AB35
R35
1
1
2
0
3
2
14
5
7
6
5
4
3
0
4
6
11
15
12
9
8
12
11
10
9
8
7
10
15
14
13
13
U6010
U6010
9/11
B_PERN15
B_PERP15
B_PERN14
B_PERP14
B_PERN13
B_PERP13
B_PERN12
B_PERP12
B_PERN11
B_PERP11
B_PERN10
B_PERP10
B_PERN9
B_PERP9
B_PERN8
B_PERP8
8/11
B_PERN7
B_PERP7
B_PERN6
B_PERP6
B_PERN5
B_PERP5
B_PERN4
B_PERP4
B_PERN3
B_PERP3
B_PERN2
B_PERP2
B_PERN1
B_PERP1
B_PERN0
B_PERP0
RX : B_PER[15:8]
RX : B_PER[7:0]
SHEETDATE
DEPARTMENT
SIZE
PROJECT DOCUMENT NUMBER REV
REVIEWER
DESIGNER
123
7 3 2 1 6 5 4
E
A
B
C
E
D
C
B
A
7 6 5 4
D
IN
ININ
IN
C



RETIMER TO CPU RETIMER TO CPU
P5E_CPU0_P0_RX_DP/DN<0-15> LANE REVERSAL
Thu Sep 14 16:12:49 2023<NAME_2><NAME_1>MB FABCGT AMDV02273 OF 365
24242424PT5161LRSSMLFPT5161LRSSMLFIC
RETIMER_CPU0_P0(2)
P5E_CPU0_P0_RX_DP<15:8>P5E_CPU0_P0_RX_DN<15:8>IC P5E_CPU0_P0_RX_DP<7:0>P5E_CPU0_P0_RX_DN<7:0>
EU26
EK26
EC26
DT26
DJ26
DB26
CR26
CH26
EW29
EM29
EE29
DV29
DL29
DD29
CU29
CK29
CA26
BP26
BG26
AY26
AN26
AF26
W26
M26
CC29
BT29
BJ29
BB29
AR29
AH29
AA29
P29
14
14
7
7
4
0
0
15
2
12
9
10
12
8
11
13
9
11
5
6
8
10
13
3
2
15
6
3
5
1
1
4
U6010U6010
7/11
A_PETN15
A_PETP15
A_PETN14
A_PETP14
A_PETN13
A_PETP13
A_PETN12
A_PETP12
A_PETN11
A_PETP11
A_PETN10
A_PETP10
A_PETN9
A_PETP9
A_PETN8
A_PETP8
6/11
A_PETN7
A_PETP7
A_PETN6
A_PETP6
A_PETN5
A_PETP5
A_PETN4
A_PETP4
A_PETN3
A_PETP3
A_PETN2
A_PETP2
A_PETN1
A_PETP1
A_PETN0
A_PETP0
TX : A_PET[15:8]
TX : A_PET[7:0]
SHEETDATE
DEPARTMENT
SIZE
PROJECT DOCUMENT NUMBER REV
REVIEWER
DESIGNER
123
7 3 2 1 6 5 4
E
A
B
C
E
D
C
B
A
7 6 5 4
D
OUT
OUT
OUT
OUT
C



EXAMAX TO RETIMEREXAMAX TO RETIMER
P5E_CPU0_P0_RX_BUF_DP/DN<0-15> LANE REVERSAL
Thu Sep 14 16:12:49 2023<NAME_2><NAME_1>MB FABCGT AMDV02274 OF 365
118118117117SMLFIC PT5161LRSSMLF
RETIMER_CPU0_P0(3)
PT5161LRSICP5E_CPU0_P0_RX_BUF_DN<7:0>P5E_CPU0_P0_RX_BUF_DP<7:0>P5E_CPU0_P0_RX_BUF_DN<15:8>P5E_CPU0_P0_RX_BUF_DP<15:8>
CD1
BU1
BK1
BC1
AT1
AJ1
AB1
R1
CB2
BR2
BH2
BA2
AP2
AG2
Y2
N2
EY1
EN1
EF1
DW1
DM1
DE1
CV1
CL1
EV2
EL2
ED2
DU2
DK2
DC2
CT2
CJ2
15
9
10
11
13
14
12
8
8
9
10
11
12
14
15
13
7
6
5
4
3
2
1
0
0
2
3
4
5
6
7
1
U6010 U6010
1/11
A_PERN7
A_PERP7
A_PERN6
A_PERP6
A_PERN5
A_PERP5
A_PERN4
A_PERP4
A_PERN3
A_PERP3
A_PERN2
A_PERP2
A_PERN1
A_PERP1
A_PERN0
A_PERP0
2/11
A_PERN15
A_PERP15
A_PERN14
A_PERP14
A_PERN13
A_PERP13
A_PERN12
A_PERP12
A_PERN11
A_PERP11
A_PERN10
A_PERP10
A_PERN9
A_PERP9
A_PERN8
A_PERP8
RX : A_PER[7:0]
RX : A_PER[15:8]
SHEETDATE
DEPARTMENT
SIZE
PROJECT DOCUMENT NUMBER REV
REVIEWER
DESIGNER
123
7 3 2 1 6 5 4
E
A
B
C
E
D
C
B
A
7 6 5 4
D
IN
ININ
IN
C



RETIMER TO EXAMAXRETIMER TO EXAMAX
P5E_CPU0_P0_TX_BUF_DP/DN<0-15> LANE REVERSAL
Thu Sep 14 16:12:49 2023<NAME_2><NAME_1>MB FABCGT AMDV02275 OF 365117117
276276276276
276276 118118276276P5E_CPU0_P0_TX_BUF_C_DN<15:8>P5E_CPU0_P0_TX_BUF_C_DP<15:8>DIFF BUS_0.22UFDIFF BUS_0.22UFDIFF BUS_0.22UFDIFF BUS_0.22UFDIFF BUS_0.22UFDIFF BUS_0.22UF
P5E_CPU0_P0_TX_BUF_DN<15:8>
DIFF BUS_0.22UFDIFF BUS_0.22UFDIFF BUS_0.22UFDIFF BUS_0.22UFDIFF BUS_0.22UFDIFF BUS_0.22UFDIFF BUS_0.22UFDIFF BUS_0.22UF
P5E_CPU0_P0_TX_BUF_DP<15:8>
DIFF BUS_0.22UFRETIMER_CPU0_P0(4)
ICSMLFPT5161LRSSMLFPT5161LRSICP5E_CPU0_P0_TX_BUF_DP<7:0>P5E_CPU0_P0_TX_BUF_DN<7:0>
C020120%X6S6.3VDIFF BUS_0.22UFP5E_CPU0_P0_TX_BUF_DN<15:8>P5E_CPU0_P0_TX_BUF_DP<15:8>DIFF BUS_0.22UFDIFF BUS_0.22UF6.3V20%DIFF BUS_0.22UFC0201X6SDIFF BUS_0.22UFDIFF BUS_0.22UFDIFF BUS_0.22UFDIFF BUS_0.22UFDIFF BUS_0.22UFDIFF BUS_0.22UFDIFF BUS_0.22UFDIFF BUS_0.22UFDIFF BUS_0.22UFDIFF BUS_0.22UFDIFF BUS_0.22UFDIFF BUS_0.22UFDIFF BUS_0.22UFP5E_CPU0_P0_TX_BUF_C_DN<7:0>P5E_CPU0_P0_TX_BUF_C_DP<7:0>P5E_CPU0_P0_TX_BUF_DP<7:0>P5E_CPU0_P0_TX_BUF_DN<7:0>
2 1
2 1
2 1
2 1
2 1
2 1
2 1
2 1
2 1
2 1
2 1
2 1
2 1
2 1
2 1
2 1
2 1
2 1
2 1
2 1
2 1
2 1
2 1
2 1
2 1
2 1
2 1
2 1
2 1
2 1
2 1
2 1
EU7
EK7
EC7
DT7
DJ7
DB7
CR7
CH7
EW10
EM10
EE10
DV10
DL10
DD10
CU10
CK10
CA7
BP7
BG7
AY7
AN7
AF7
W7
M7
CC10
BT10
BJ10
BB10
AR10
AH10
AA10
P10
11
13
12
10
8
10
10
12
8
12
13
11
12
12
11
11
11
13
11
15
14
13
9
8
9
10
14
15
7
6
5
4
3
2
1
0
0
1
2
3
4
5
6
7
9
8
9
10
10
12
13
14
14
15
15
8
9
8
9
14
13
14
15
15
0
1
2
1
0
2
3
4
3
4
5
7
6
5
6
7
0
1
2
0
2
1
3
4
3
4
5
6
7
5
6
7C6532
C6531
C6530
C6529
C6528
C6527
C6525
C6526
C6524
C6523
C6521
C6522
C6519
C6520
C6518
C6517
C6502
C6501
C6504
C6503
C6505
C6507
C6506
C6508
C6510
C6509
C6512
C6511
C6515
C6514
C6513
C6516
U6010U6010
11/11
B_PETN15
B_PETP15
B_PETN14
B_PETP14
B_PETN13
B_PETP13
B_PETN12
B_PETP12
B_PETN11
B_PETP11
B_PETN10
B_PETP10
B_PETN9
B_PETP9
B_PETN8
B_PETP8
10/11
B_PETN7
B_PETP7
B_PETN6
B_PETP6
B_PETN5
B_PETP5
B_PETN4
B_PETP4
B_PETN3
B_PETP3
B_PETN2
B_PETP2
B_PETN1
B_PETP1
B_PETN0
B_PETP0
TX : B_PET[15:8]
TX : B_PET[7:0]
2 12 1
2 12 1
2 12 1
2 12 1
2 12 1
2 12 1
2 12 1
2 12 1
2 12 1
2 12 1
2 1
2 1
2 1
2 1
2 12 1
2 12 1
2 1
2 12 1
2 1
SHEETDATE
DEPARTMENT
SIZE
PROJECT DOCUMENT NUMBER REV
REVIEWER
DESIGNER
123
7 3 2 1 6 5 4
E
A
B
C
E
D
C
B
A
7 6 5 4
D
OUTOUT
OUTOUTININ
OUT
OUT
OUT
OUT
ININ
C



CPU1 P0 RT ADDR: 0X48 (8-BIT) / 0X24 (7-BIT)
Thu Sep 14 16:13:07 2023<NAME_2><NAME_1>MB FABCGT AMDV02276 OF 365
P1V8_CPU0_RT_1DP1V8_CPU0_RT_1DP1V8_CPU0_RT_1DP1V8_CPU0_RT_1DP1V8_CPU0_RT_1DP1V8_CPU0_RT_1D
P1V8_CPU0_RT_1DSMB_RT_CPU0_P0_ROM_MUX_1D_R_SCLSMB_RT_CPU0_P0_ROM_MUX_1D_SCL1%49.90201LF1/20W CHIPSMB_RT_CPU0_P0_ROM_MUX_1D_R_SDASMB_RT_CPU0_P0_ROM_MUX_1D_SDA185186185186277277277812778127727727727727727727727727727727727727727727727727727727727727727718418427727727781277
182182
81277277277277277277CHIP2001%1/20W0201LFEMPTYJTAG_TCK_RT_CPU0_P0RST_RT_CPU0_P0_RESET_NJTAG_TDO_RT_CPU0_P0JTAG_TMS_RT_CPU0_P0EMPTY0201LFEMPTY0201LFRST_RT_CPU0_P0_RESET_R_NRST_RT_CPU0_P0_PERST_R_NJTAG_TRST_RT_CPU0_P0_NJTAG_TMS_RT_CPU0_P0JTAG_TDO_RT_CPU0_P0JTAG_TCK_RT_CPU0_P00201LF0201LF4.7K1/20W0201LFEMPTY1/20W1/20W05%1/20W4.7K4.7K0201LFRXDET_BYP_RT_CPU0_P00201LF4.7K5%1/20WICPT5161LRSJTAG_TEST_MODE_RT_CPU0_P0TEST2_RT_CPU0_P0TEST1_RT_CPU0_P0TEST0_RT_CPU0_P0GPIO3_RT_CPU0_P0GPIO2_RT_CPU0_P0EMPTY1/20W5%4.7K 4.7K10K1/20W0201LFRXDET_BYP_RT_CPU0_P00201LF5%4.7K1/20WEMPTYEMPTY0201LF0201LFMODE_RT_CPU0_P01%1/20WCHIP1/20WEMPTY1K0201LF
RETIMER_CPU0_P0(5)
SMLFGPIO2_RT_CPU0_P0GPIO3_RT_CPU0_P0CLK_100M_RETIMER_CPU0_P0_DNCLK_100M_RETIMER_CPU0_P0_DPRT_CPU0_P0_ADDR1RT_CPU0_P0_ADDR2RT_CPU0_P0_ADDR3SMB_RT_CPU0_P0_R2_SCLSMB_RT_CPU0_P0_R2_SDATEST0_RT_CPU0_P0TEST1_RT_CPU0_P0TEST2_RT_CPU0_P0CHIP1K1%0201LFCHIP1/20WCHIP1/20W0201LF4.7K5%4.7K1%1%EMPTY1K1/20WEMPTY0201LF1%0201LF4.7K0201LFEMPTY1/20W4.7KCHIP0201LF0201LF0201LFRT_CPU0_P0_SCAN_MODE5%SMB_RT_CPU0_P0_R_SDASMB_RT_CPU0_P0_R_SCL20KRT_CPU0_P0_ADDR34.7K5%1/20W1/20W0201LF4.7K1/20W0201LFRT_CPU0_P0_ADDR2RT_CPU0_P0_ADDR1CHIPCHIP1/20WRST_RT_CPU0_P0_RESET_R_NCHIP0CLK_100M_RETIMER_CPU0_P0_R_DNCLK_100M_RETIMER_CPU0_P0_R_DP1/20W00201LF5%4.7KEMPTY0201LF0201LF1%10K4.7K5% 5%0201LF1/20WEMPTY5%1/20W5%EMPTY0201LF5%4.7K1/20W5%EMPTY0201LF1/20W5%1/20W5%4.7KCHIP0201LFCHIP1K1%EMPTY1K1/20W1%1K0201LF1/20WCHIP1%10K1%10K1/20WCHIP0201LFRST_RT_CPU0_P0_PERST_R_N
CHIP0201LF1%51.10201LF1%1/20WEMPTYEMPTY1/20W51.1
5%1/20W10K1%1/20WCHIP0201LF1/20WCHIP
CHIP0201LF
0201LF0201LF1/20W
0CHIPRST_RT_CPU0_P0_PERST_NMODE_RT_CPU0_P01%CHIP 0201LFCLKREQ_RT_CPU0_P0_NRT_CPU0_P0_SCAN_MODE5%CHIP0201LF1K1%
1/20W1K4.7KJTAG_TDI_RT_CPU0_P0JTAG_TEST_MODE_RT_CPU0_P05%JTAG_TDI_RT_CPU0_P0
R970R971
FF30
FF27
FF24
E30
B28
B31
B25
B23
F34
FF33
E11
FF11
FJ16
FF18
B16
E18
F2
FJ9
E8
B12
FF8
B9
B6
B3
FJ31
FJ28
FJ25
FJ23
FJ6
FJ3
FF5
G35
U6010
CLOCK
3/11
EE_DAT
EE_CLK
CLKREQ_N
TEST2
TEST1
TEST0
T_SENSE
SMBDAT
SMBCLK
SMB_ADDR3
SMB_ADDR2
SMB_ADDR1
SCAN_MODE
RXDET_BYP
RESET_N
REFCLKP
REFCLKN
REFCLK_OUTP
REFCLK_OUTN
PERST_N
MODE
JTAG_TRST_N
JTAG_TMS
JTAG_TEST_MODE
JTAG_TDO
JTAG_TDI
JTAG_TCK
INT_N
GPIO3
GPIO2
GPIO1
GPIO0
MISCJTAGTEST EEPROMSMBUSGPIO
2
1
2
1
2
1
2
1
R1446
2
1
R1365
2
1
21
2
1
R1369
2
1
R1370
21R1364
2
1
R974
2
1
2
1
2
1
2
1
2
1
2
1
R964
2
1
R967
2
1
R965
21
21
2
1
R998
2
1
R1001
2
1
R975
2
1
R985
2
1
R983
2
1
R997
2
1
R995
2
1
R984
21
21
21
21
21
21
2
1
2
1
2
1
R981
2
1
R978
2
1
R982
2
1
R980
2
1
R979
2
1
R972
SHEETDATE
DEPARTMENT
SIZE
PROJECT DOCUMENT NUMBER REV
REVIEWER
DESIGNER
123
7 3 2 1 6 5 4
E
A
B
C
E
D
C
B
A
7 6 5 4
D
IN
OUT
IN
IN
IN
IN
IN
OUT
OUT
OUTOUTOUTOUT
OUT
IN
IN
IN
IN
IN
IN
IN
OUT
IN
BI
IN
OUT
BI
IN
IN
IN
IN
IN
IN
OUTOUTOUTOUT
IN
IN
OUT
OUT
IN
R1438 R1439 R1445
R973
R1368
R968
R969
R966
R963
R953
R976
R977
R666
R667
R596
R595
R624R623
C



Thu Sep 14 16:13:08 2023<NAME_2><NAME_1>MB FABCGT AMDV02277 OF 365
P1V8_CPU0_RT0_1A_1DP1V8_CPU0_RT_1DP0V9_CPU0_RT0_2A_2DP0V9_CPU0_RT_2DP1V8_CPU0_RT0_1AP0V9_CPU0_RT0_2A1%2001/20W0201LFCHIPEMPTY1/20W1K1%0201LFRT_CPU0_P0_VQPS
RETIMER_CPU0_P0 POWER(6)CHIP
PT5161LRS
1/20WNCF_A1_CPU0_P0_GNDNCF_CPU0_P0_GNDICPT5161LRS
1/20W5%0
SMLF
0201LF
ICSMLF
05%CHIP0201LF
FH34
FH2
FG35
FG1
FE34
FE2
D35
D1
C34
C2
A35
A1
V35
V1
U34
U2
T4
T32
T22
T13
L35
L1
K34
K2
J4
J22
H31
H19
H16
H12
FJ19
FJ12
FF21
FF14
FD35
FD1
FC9
FC6
FC3
FC28
FC25
FC23
FC19
FB34
FB2
FA32
FA15
ET35
ET1
ER34
ER2
EP4
EP32
EP22
EP13
EJ35
EJ1
EH34
EH2
EG4
EG32
EG22
EG13
EB35
EB1
EA34
EA2
E33
E27
E14
DY4
DY32
DY22
DY13
DR35
DR1
DP34
DP2
DN4
DN32
DN22
DN13
DH35
DH1
DG34
DG2
DF4
DF32
DF22
DF13
DA35
DA1
CY34
CY2
CW4
CW32
CW22
CW13
CP35
CP1
CN34
CN2
CM4
CM32
CM22
CM13
CG35
CG1
CF34
CF2
CE4
CE32
CE22
CE13
BY35
BY1
BW34
BW2
BV4
BV32
BV22
BV13
BN35
BN1
BM34
BM2
BL4
BL32
BL22
BL13
BF35
BF1
BE34
BE2
BD4
BD32
BD22
BD13
B19
AW35
AW1
AV34
AV2
AU4
AU32
AU22
AU13
AM35
AM1
AL34
AL2
AK4
AK32
AK22
AK13
AE35
AE1
AD34
AD2
AC4
AC32
AC22
AC13
G1
CW20
CW17
BL20
BL17
T20
T17
EP20
EP17
EG20
EG17
DY20
DY17
DN20
DN17
DF20
DF17
BD20
BD17
AU20
AU17
AK20
AK17
AC20
AC17
BV17
CM20
CM17
CE20
CE17
BV20
U6010
U6010
4/11
PWR_2A_20
PWR_2A_19
PWR_2A_18
PWR_2A_17
PWR_2A_16
PWR_2A_15
PWR_2A_14
PWR_2A_13
PWR_2A_12
PWR_2A_11
PWR_2A_10
PWR_2A_9
PWR_2A_8
PWR_2A_7
PWR_2A_6
PWR_2A_5
PWR_2A_4
PWR_2A_3
PWR_2A_2
PWR_2A_1
PWR_1D
PWR_2D_4
PWR_2D_3
PWR_2D_2
PWR_2D_1
PWR_1A_5
PWR_1A_4
PWR_1A_3
PWR_1A_2
PWR_1A_1
VQPS
5/11
GND151
GND150
GND149
GND148
GND147
GND146
GND145
GND144
GND143
GND142
GND141
GND140
GND139
GND138
GND137
GND136
GND135
GND134
GND133
GND132
GND131
GND130
GND129
GND128
GND127
GND126
GND125
GND124
GND123
GND122
GND121
GND120
GND119
GND118
GND117
GND116
GND115
GND114
GND113
GND112
GND111
GND110
GND109
GND108
GND107
GND106
GND105
GND104
GND103
GND102
GND101
GND100
GND99
GND98
GND97
GND96
GND95
GND94
GND93
GND92
GND91
GND90
GND89
GND88
GND87
GND86
GND85
GND84
GND83
NCF_GND12
NCF_GND11
NCF_GND10
NCF_GND9
NCF_GND8
NCF_GND7
NCF_GND6
NCF_GND5
NCF_GND4
NCF_GND3
NCF_GND2
NCF_GND1
GND82
GND81
GND80
GND79
GND78
GND77
GND76
GND75
GND74
GND73
GND72
GND71
GND70
GND69
GND68
GND67
GND66
GND65
GND64
GND63
GND62
GND61
GND60
GND59
GND58
GND57
GND56
GND55
GND54
GND53
GND52
GND51
GND50
GND49
GND48
GND47
GND46
GND45
GND44
GND43
GND42
GND41
GND40
GND39
GND38
GND37
GND36
GND35
GND34
GND33
GND32
GND31
GND30
GND29
GND28
GND27
GND26
GND25
GND24
GND23
GND22
GND21
GND20
GND19
GND18
GND17
GND16
GND15
GND14
GND13
GND12
GND11
GND10
GND9
GND8
GND7
GND6
GND5
GND4
GND3
GND2
GND1
0.9V0.9V1.8V/ 1.8V1.2V / 1.5V
2
1
R6808
2
1
2
1
2
1
SHEETDATE
DEPARTMENT
SIZE
PROJECT DOCUMENT NUMBER REV
REVIEWER
DESIGNER
123
7 3 2 1 6 5 4
E
A
B
C
E
D
C
B
A
7 6 5 4
D
R6809
R6820
R6821
C



RETIMER EEPRO ADDRESS: 0XA0 (8 BIT) / 0X50 (7 BIT)
Thu Sep 14 16:12:59 2023<NAME_2><NAME_1>MB FABCGT AMDV02278 OF 365
P1V8_CPU0_RT_1D185186185186SMB_RT_CPU0_P0_ROM_SDASMB_RT_CPU0_P0_ROM_R_SDA1%33.2SMB_RT_CPU0_P0_ROM_SCLSMB_RT_CPU0_P0_ROM_R_SCL1/20W CHIP 0201LFM24M02-DRMN6TPU11_E2X7SC0201SMLF0.1UF0201LFCHIP10%IC
RETIMER_CPU0_P0(7)
1%10V1/20W1K
7
4
8
5
6 3
2
1
U11
DU1
DU2
E2
VSSSDA
SCL
WC_N
VCC
2
1
2
1C7510
21 21
SHEETDATE
DEPARTMENT
SIZE
PROJECT DOCUMENT NUMBER REV
REVIEWER
DESIGNER
123
7 3 2 1 6 5 4
E
A
B
C
E
D
C
B
A
7 6 5 4
D
BIIN R6822R669R668
C



Thu Sep 14 16:13:08 2023<NAME_2><NAME_1>MB FABCGT AMDV02279 OF 365
P0V9_CPU0_RT_2D
P0V9_CPU0_RT0_2A_2D
P1V8_CPU0_RT_1DP1V8_CPU0_RT0_1AP1V8_CPU0_RT0_1A_1DP0V9_CPU0_RT0_2AX6SC080520%4V100UFC0805X6S20%4V100UF4VX6S100UF20%C0805X6S4V100UF20%C0805100UFC0805X6S4V20%X6S20%100UFC08054V20%X6S4VC0805100UFC02014V20%X6S20%20%4V470UF20%2.5VSPCAPSMLFC0805 C0805 C0805 C080522UF4V20%X6SC0402C020110V 10V 10V20%0.1UF0.1UF0.1UF10%10V02011UFIND47UFX6S X6S47UF4V47UF20%47UFX6S4VC080547UF4V20%2.5VSPCAP2.5VSPCAPSMLF10UF0.1UFX7SC0201X7SC02010.1UF10VC020110%10V0.1UFX7S020102010.1UF10V 10V6.3VX6S20%6.3V4.7UF20%X6S02010201X7S10%10VX7SX6S6.3V 6.3V20%X7S10%10V4V4V4V1UF20%020120%4VX6S1UF20%10%0.1UF0.1UFC020110%X7S0.1UF10V0603LF10%C020102010.1UF10%X7SC020110%0.1UF10V1UF4VX7S20%R961 AND R962 COLAY1/4W020%4V02011UFX6S20%4V1UF4V20%X6SC040220% 20%4.7UF20%4VX6SC040220%20%6.3V100NH/16ASMLF4VBLM21SN300SN1D/5A10UF6.3V22UF4V10%5%0X6S
X7SRETIMER_CPU0_P0 DECAPS(8)
IND05%0402LF0402LF05%1/16W1/16W1/16WEMPTYINDSMLFBLM15PD121SN1D/1300MAX6SX7S1/4W0603LF5%EMPTY0201X6S10V1UF20%22UFX6S X6SX7S10%C040210UF6.3VEMPTYX6S20%6.3V10UFX6S20%20%20%X7S20%4.7UFX6SC040210UF20%X6SC04024VX6SC040220%22UF4V22UFC02011UF4V1UF4VX6S1UF0402 0201020104024V0402LFEMPTYC020110%10VX7SC0201C0201X7SC0402 C0402X6S20%4.7UF20%02014.7UF1UF4V20%0201L26/R960 COLAY WITH R951/R9520402SMLF1UF0.1UF10V10V4V6.3V10UF6.3VX6S04020.1UFC02010.1UF10%X6S01UF4VX6S020110%10V0.1UF 0.1UF20%22UFCHIPX6SX6SC020110%10VX6S10VX7SC020110%4V0201X6S20%1UF1UF02014VX6S20%5%10VC0201X7SX7SC020110%10V0.1UF 0.1UF10%X6SX6S04021UF20%4V6.3V20%10UF6.3V4.7UF0.1UFX6SC0201 C0201SPCAP2.5VSMLF20%470UF2.5VSMLFSPCAP20%470UF4V100UFC0805X6S20%20%1UF020120%C040220%22UF4VC0402X7S6.3V20%X6SC040220%C0201X6SC0402 0402X6S20%10%SMLF470UF4V47UF470UF20%X6SX6SX7SX6SC08054.7UF6.3VX6S0402X6S0.1UFX6S20%C0402X7S10% 10%C0201
C504
L26
C7036C7035C7034C7033C7032
C7010
C7000 C7002
C511C506
C510
C502
C505C503
C513
2121
2 1
L12L11
1 21 2
12
2
1
2
1
2
1
2
1
2
1
2
1
2
1C7009
2
1C7008
2
1
2
1C7001
2
1
2
1
2
1
2
1
2
1
2
1
2
1
2
1
2
1
2
1
2
1
2
1
2
1
2
1
2
1
2
1
2
1
2
1
2
1
2
1
2
1
2
1
2
1
2
1
2
1
2
1
2
1
2
1
2
1
2
1
2
1
2
1
2
1
2
1
2
1
2
1
2
1
2
1
2
1
2
1
2
1
2
1
2
1
2
1
2
1
2
1
2
1
2
1
2
1
2
1
2
1
2
1
2
1
2
1
2
1
2
1
2
1
2
1
2
1
2
1
2
1
2
1
2
1
2
1
2
1
2
1
2
1
21
2
1
2
1
2
1
21
21R952
CAD NOTE:
CAD NOTE:
R960
C514C512C507
R951
SHEETDATE
DEPARTMENT
SIZE
PROJECT DOCUMENT NUMBER REV
REVIEWER
DESIGNER
123
7 3 2 1 6 5 4
E
A
B
C
E
D
C
B
A
7 6 5 4
D
C7003
C566C583
C545C542
C540C578C524
C567C584
C522C528C569
C568C575C565C586
C563 C574C559
C564C560C556C550
C526C521
C543C558
C529C525
C581C577
C572C557
C573C570
C585C523C582C541
C571C554C579
C562C539
C561
C555
C580C576
C544C538
C520C519C517C515
R962
R961
C516
C



Thu Aug 24 10:16:08 2023<NAME_2><NAME_1>MB FABCGT AMDV02280 OF 365RETIMER_CPU0_P0(9)
SHEETDATE
DEPARTMENT
SIZE
PROJECT DOCUMENT NUMBER REV
REVIEWER
DESIGNER
123
7 3 2 1 6 5 4
E
A
B
C
E
D
C
B
A
7 6 5 4
D
C



Thu Aug 24 10:16:09 2023<NAME_2><NAME_1>MB FABCGT AMDV02281 OF 365RETIMER_CPU0_P0(10)
SHEETDATE
DEPARTMENT
SIZE
PROJECT DOCUMENT NUMBER REV
REVIEWER
DESIGNER
123
7 3 2 1 6 5 4
E
A
B
C
E
D
C
B
A
7 6 5 4
D
C



Thu Aug 24 10:16:10 2023<NAME_2><NAME_1>MB FABCGT AMDV02282 OF 365BLANK
SHEETDATE
DEPARTMENT
SIZE
PROJECT DOCUMENT NUMBER REV
REVIEWER
DESIGNER
123
7 3 2 1 6 5 4
E
A
B
C
E
D
C
B
A
7 6 5 4
D
C



P/N SWAPP/N SWAPP/N SWAPP/N SWAPP/N SWAPP/N SWAPP/N SWAPP/N SWAPP/N SWAPCPU TO RETIMERCPU TO RETIMER
P5E_CPU0_P1_TX_C_DP/DN<0-15> LANE REVERSALP/N SWAPP/N SWAPP/N SWAPP/N SWAPP/N SWAP
Thu Sep 14 16:12:51 2023<NAME_2><NAME_1>MB FABCGT AMDV02283 OF 365
63636363IC
RETIMER_CPU0_P1(1)
SMLFPT5161LRSPT5161LRSICSMLFP5E_CPU0_P1_TX_C_DN<7:0>P5E_CPU0_P1_TX_C_DP<7:0>P5E_CPU0_P1_TX_C_DN<15:8>P5E_CPU0_P1_TX_C_DP<15:8>
EV34
EL34
ED34
DU34
DK34
DC34
CT34
CJ34
EY35
EN35
EF35
DW35
DM35
DE35
CV35
CL35
CB34
BR34
BH34
BA34
AP34
AG34
Y34
N34
CD35
BU35
BK35
BC35
AT35
AJ35
AB35
R35
13
13
12
12
1
3
6
3
6
10
8
9
10
11
2
4
0
0
5
8
9
11
7
7
4
5
15
2
1
14
14
15
U6011
U6011
9/11
B_PERN15
B_PERP15
B_PERN14
B_PERP14
B_PERN13
B_PERP13
B_PERN12
B_PERP12
B_PERN11
B_PERP11
B_PERN10
B_PERP10
B_PERN9
B_PERP9
B_PERN8
B_PERP8
8/11
B_PERN7
B_PERP7
B_PERN6
B_PERP6
B_PERN5
B_PERP5
B_PERN4
B_PERP4
B_PERN3
B_PERP3
B_PERN2
B_PERP2
B_PERN1
B_PERP1
B_PERN0
B_PERP0
RX : B_PER[15:8]
RX : B_PER[7:0]
SHEETDATE
DEPARTMENT
SIZE
PROJECT DOCUMENT NUMBER REV
REVIEWER
DESIGNER
123
7 3 2 1 6 5 4
E
A
B
C
E
D
C
B
A
7 6 5 4
D
IN
IN
IN
IN
C



RETIMER TO CPURETIMER TO CPU
P5E_CPU0_P1_RX_DP/DN<0-15> LANE REVERSAL
Thu Sep 14 16:12:51 2023<NAME_2><NAME_1>MB FABCGT AMDV02284 OF 365
24242424SMLFPT5161LRSP5E_CPU0_P1_RX_DN<7:0>P5E_CPU0_P1_RX_DP<7:0>PT5161LRS
RETIMER_CPU0_P1(2)
SMLFICICP5E_CPU0_P1_RX_DP<15:8>P5E_CPU0_P1_RX_DN<15:8>
EU26
EK26
EC26
DT26
DJ26
DB26
CR26
CH26
EW29
EM29
EE29
DV29
DL29
DD29
CU29
CK29
CA26
BP26
BG26
AY26
AN26
AF26
W26
M26
CC29
BT29
BJ29
BB29
AR29
AH29
AA29
P29 15
3
2
5
4
7
5
7
13
13
11
10
10
15
11
8
8
6
4
1
0
3
2
1
0
9
12
9
6
12
14
14
U6011U6011
7/11
A_PETN15
A_PETP15
A_PETN14
A_PETP14
A_PETN13
A_PETP13
A_PETN12
A_PETP12
A_PETN11
A_PETP11
A_PETN10
A_PETP10
A_PETN9
A_PETP9
A_PETN8
A_PETP8
6/11
A_PETN7
A_PETP7
A_PETN6
A_PETP6
A_PETN5
A_PETP5
A_PETN4
A_PETP4
A_PETN3
A_PETP3
A_PETN2
A_PETP2
A_PETN1
A_PETP1
A_PETN0
A_PETP0
TX : A_PET[15:8]
TX : A_PET[7:0]
SHEETDATE
DEPARTMENT
SIZE
PROJECT DOCUMENT NUMBER REV
REVIEWER
DESIGNER
123
7 3 2 1 6 5 4
E
A
B
C
E
D
C
B
A
7 6 5 4
D
OUT
OUT
OUT
OUT
C



P5E_CPU0_P1_RX_BUF_DP/DN<0-15>
EXAMAX TO RETIMEREXAMAX TO RETIMERThu Sep 14 16:12:52 2023<NAME_2><NAME_1>MB FABCGT AMDV02285 OF 365
118118117117P5E_CPU0_P1_RX_BUF_DN<7:0>P5E_CPU0_P1_RX_BUF_DP<7:0>P5E_CPU0_P1_RX_BUF_DN<15:8>P5E_CPU0_P1_RX_BUF_DP<15:8>PT5161LRSICSMLFICSMLFPT5161LRS
RETIMER_CPU0_P1(3)
EY1
EN1
EF1
DW1
DM1
DE1
CV1
CL1
EV2
EL2
ED2
DU2
DK2
DC2
CT2
CJ2
CD1
BU1
BK1
BC1
AT1
AJ1
AB1
R1
CB2
BR2
BH2
BA2
AP2
AG2
Y2
N2
15
3
0
7
6
5
4
2
1
4
5
6
0
3
2
1
7
15
14
13
12
11
10
9
8
8
9
10
11
12
13
14
U6011U6011
2/11
A_PERN15
A_PERP15
A_PERN14
A_PERP14
A_PERN13
A_PERP13
A_PERN12
A_PERP12
A_PERN11
A_PERP11
A_PERN10
A_PERP10
A_PERN9
A_PERP9
A_PERN8
A_PERP8
1/11
A_PERN7
A_PERP7
A_PERN6
A_PERP6
A_PERN5
A_PERP5
A_PERN4
A_PERP4
A_PERN3
A_PERP3
A_PERN2
A_PERP2
A_PERN1
A_PERP1
A_PERN0
A_PERP0
RX : A_PER[15:8]
RX : A_PER[7:0]
SHEETDATE
DEPARTMENT
SIZE
PROJECT DOCUMENT NUMBER REV
REVIEWER
DESIGNER
123
7 3 2 1 6 5 4
E
A
B
C
E
D
C
B
A
7 6 5 4
D
IN
ININ
IN
C



P5E_CPU0_P1_TX_BUF_DP/DN<0-15> LANE REVERSAL
RETIMER TO EXAMAXRETIMER TO EXAMAXThu Sep 14 16:12:52 2023<NAME_2><NAME_1>MB FABCGT AMDV02286 OF 365287287118118287287117117
287287287287
P5E_CPU0_P1_TX_BUF_DN<7:0>P5E_CPU0_P1_TX_BUF_DP<7:0> P5E_CPU0_P1_TX_BUF_C_DP<7:0>P5E_CPU0_P1_TX_BUF_C_DN<7:0>DIFF BUS_0.22UFDIFF BUS_0.22UFDIFF BUS_0.22UFDIFF BUS_0.22UFDIFF BUS_0.22UFDIFF BUS_0.22UFDIFF BUS_0.22UFDIFF BUS_0.22UFDIFF BUS_0.22UFDIFF BUS_0.22UFDIFF BUS_0.22UFDIFF BUS_0.22UFDIFF BUS_0.22UFDIFF BUS_0.22UFDIFF BUS_0.22UF20%6.3VX6SC0201DIFF BUS_0.22UFP5E_CPU0_P1_TX_BUF_DN<15:8>P5E_CPU0_P1_TX_BUF_DP<15:8> P5E_CPU0_P1_TX_BUF_C_DP<15:8>P5E_CPU0_P1_TX_BUF_C_DN<15:8>DIFF BUS_0.22UFDIFF BUS_0.22UFDIFF BUS_0.22UFDIFF BUS_0.22UFDIFF BUS_0.22UFDIFF BUS_0.22UFDIFF BUS_0.22UFDIFF BUS_0.22UFDIFF BUS_0.22UFDIFF BUS_0.22UFDIFF BUS_0.22UFDIFF BUS_0.22UFDIFF BUS_0.22UF6.3VC0201X6S20%DIFF BUS_0.22UFDIFF BUS_0.22UFDIFF BUS_0.22UF
PT5161LRSP5E_CPU0_P1_TX_BUF_DN<7:0>SMLFPT5161LRSP5E_CPU0_P1_TX_BUF_DP<7:0>P5E_CPU0_P1_TX_BUF_DN<15:8>P5E_CPU0_P1_TX_BUF_DP<15:8>SMLFIC
RETIMER_CPU0_P1(4)
IC
2 1
2 1
2 1
2 1
2 1
2 1
2 1
2 1
2 1
2 1
2 1
2 1
2 1
2 1
2 1
2 1
2 1
2 1
2 1
2 1
2 1
2 1
2 1
2 1
2 1
2 1
2 1
2 1
2 1
2 1
2 1
2 1
EU7
EK7
EC7
DT7
DJ7
DB7
CR7
CH7
EW10
EM10
EE10
DV10
DL10
DD10
CU10
CK10
CA7
BP7
BG7
AY7
AN7
AF7
W7
M7
CC10
BT10
BJ10
BB10
AR10
AH10
AA10
P10
7
6
5
4
3
2
1
0
7
6
5
4
3
2
1
0
7
7
5
6
6
5
4
2
3
4
3
2
1
0
1
0
15
14
15
14
11
12
13
13
12
9
10
11
10
9
8
8
15
14
15
14
13
12
13
12
11
10
9
10
9
8
8
11
7
3
6
5
4
2
1
0
0
1
2
3
4
5
6
7
15
14
13
12
11
10
9
8
14
13
12
11
10
9
8
15
U6011
C6549
C6550
C6552
C6551
C6554
C6553
C6555
C6556
C6557
C6558
C6559
C6560
C6561
C6562
C6563
C6564
C6534
C6533
C6535
C6536
U6011
C6537
C6538
C6539
C6540
C6542
C6541
C6544
C6543
C6546
C6545
C6547
C6548
10/11
B_PETN7
B_PETP7
B_PETN6
B_PETP6
B_PETN5
B_PETP5
B_PETN4
B_PETP4
B_PETN3
B_PETP3
B_PETN2
B_PETP2
B_PETN1
B_PETP1
B_PETN0
B_PETP0
11/11
B_PETN15
B_PETP15
B_PETN14
B_PETP14
B_PETN13
B_PETP13
B_PETN12
B_PETP12
B_PETN11
B_PETP11
B_PETN10
B_PETP10
B_PETN9
B_PETP9
B_PETN8
B_PETP8
TX : B_PET[7:0]
TX : B_PET[15:8]
2 12 1
2 12 1
2 12 1
2 12 1
2 12 1
2 12 1
2 12 1
2 12 1
2 12 1
2 12 1
2 12 1
2 12 1
2 12 1
2 12 1
2 12 1
2 12 1
SHEETDATE
DEPARTMENT
SIZE
PROJECT DOCUMENT NUMBER REV
REVIEWER
DESIGNER
123
7 3 2 1 6 5 4
E
A
B
C
E
D
C
B
A
7 6 5 4
D
OUT
OUT
ININ OUT OUTIN
OUT
OUT
OUTOUT IN
C



CPU1 P0 RT ADDR: 0X48 (8-BIT) / 0X24 (7-BIT)
Thu Sep 14 16:13:03 2023<NAME_2><NAME_1>MB FABCGT AMDV02287 OF 365
P1V8_CPU0_RT_1DP1V8_CPU0_RT_1DP1V8_CPU0_RT_1DP1V8_CPU0_RT_1DP1V8_CPU0_RT_1DP1V8_CPU0_RT_1D
P1V8_CPU0_RT_1DSMB_RT_CPU0_P1_ROM_MUX_1D_R_SCLSMB_RT_CPU0_P1_ROM_MUX_1D_SCL1%49.9CHIP1/20W0201LFSMB_RT_CPU0_P1_ROM_MUX_1D_R_SDASMB_RT_CPU0_P1_ROM_MUX_1D_SDA185186185186288288288288288288288
288288
182182288
2882882881842882882882888128881288288
28818428828828881288812882882882882882882882882882882881/20W2001%CHIP0201LFRST_RT_CPU0_P1_RESET_N0201LF0201LF10K1%1/20WCHIP1/20WEMPTY1K1%0201LF05%RT_CPU0_P1_ADDR3RT_CPU0_P1_SCAN_MODEGPIO2_RT_CPU0_P1GPIO3_RT_CPU0_P1RXDET_BYP_RT_CPU0_P1SMB_RT_CPU0_P1_R2_SDART_CPU0_P1_ADDR2TEST0_RT_CPU0_P1
GPIO2_RT_CPU0_P1GPIO3_RT_CPU0_P1
CHIP1/20W51.11%51.11%RETIMER_CPU0_P1(5)0201LF1/20WEMPTY0201LFCLK_100M_RETIMER_CPU0_P1_DNEMPTYCHIP0201LFCLK_100M_RETIMER_CPU0_P1_R_DPCLK_100M_RETIMER_CPU0_P1_R_DNTEST1_RT_CPU0_P1ICTEST1_RT_CPU0_P1TEST0_RT_CPU0_P1MODE_RT_CPU0_P1SMB_RT_CPU0_P1_R_SDATEST2_RT_CPU0_P1JTAG_TEST_MODE_RT_CPU0_P1RT_CPU0_P1_ADDR2RT_CPU0_P1_ADDR1RST_RT_CPU0_P1_RESET_R_NRST_RT_CPU0_P1_PERST_R_NRT_CPU0_P1_ADDR3PT5161LRSSMLFRT_CPU0_P1_ADDR1SMB_RT_CPU0_P1_R2_SCLSMB_RT_CPU0_P1_R_SCL
1/20W0201LFEMPTY4.7K5%1%1/20W0201LFCHIP10K1/20W10K0201LF1%CHIP0201LFEMPTY1K1%1/20W1/20WCHIP0201LF1K1%0201LF1%EMPTY1K1/20W0201LFCHIP1/20W1K1%1/20W1%0201LF20KCHIP1%EMPTY0201LF1/20W1K1/20W4.7K5%CHIP0201LF0201LF4.7K5%1/20WEMPTY0201LF5%4.7K1/20WEMPTY0201LF5%4.7KEMPTY1/20W1/20W4.7K5%EMPTY0201LF4.7K0201LF1/20WCHIP5%CHIP1/20W5%4.7K0201LF4.7K1/20WCHIP0201LF5%1/20W0201LFCHIP
5%1/20W0201LFEMPTY4.7K4.7K1/20WEMPTY0201LF5%5%4.7K1/20WCHIP0201LF10K1%CHIP0201LF1/20W0201LFCHIP1/20W1%10KEMPTY5%0201LF1/20W4.7KTEST2_RT_CPU0_P1CLK_100M_RETIMER_CPU0_P1_DP0201LF1/20W05%CHIP1K0CHIP4.7K00201LF0201LFJTAG_TCK_RT_CPU0_P1JTAG_TDO_RT_CPU0_P1RST_RT_CPU0_P1_PERST_R_NRST_RT_CPU0_P1_RESET_R_NRT_CPU0_P1_SCAN_MODERXDET_BYP_RT_CPU0_P1MODE_RT_CPU0_P1RST_RT_CPU0_P1_PERST_N0201LFCHIP1/20W4.7K5%JTAG_TEST_MODE_RT_CPU0_P1JTAG_TRST_RT_CPU0_P1_NJTAG_TDI_RT_CPU0_P1JTAG_TMS_RT_CPU0_P1CLKREQ_RT_CPU0_P1_N1/20W5%1K1%0201LF4.7K5%1/20WEMPTY1/20W5%4.7K0201LF1/20WEMPTY4.7KEMPTY0201LF0201LFEMPTY0201LFJTAG_TDI_RT_CPU0_P1JTAG_TCK_RT_CPU0_P1JTAG_TDO_RT_CPU0_P1JTAG_TMS_RT_CPU0_P1
R1020 R1019
FF30
FF27
FF24
E30
B28
B31
B25
B23
F34
FF33
E11
FF11
FJ16
FF18
B16
E18
F2
FJ9
E8
B12
FF8
B9
B6
B3
FJ31
FJ28
FJ25
FJ23
FJ6
FJ3
FF5
G35
U6011
CLOCK
3/11
EE_DAT
EE_CLK
CLKREQ_N
TEST2
TEST1
TEST0
T_SENSE
SMBDAT
SMBCLK
SMB_ADDR3
SMB_ADDR2
SMB_ADDR1
SCAN_MODE
RXDET_BYP
RESET_N
REFCLKP
REFCLKN
REFCLK_OUTP
REFCLK_OUTN
PERST_N
MODE
JTAG_TRST_N
JTAG_TMS
JTAG_TEST_MODE
JTAG_TDO
JTAG_TDI
JTAG_TCK
INT_N
GPIO3
GPIO2
GPIO1
GPIO0
MISCJTAGTEST EEPROMSMBUSGPIO
2
1
R1473
2
1
2
1
R1392
2
1
2
1
2
1
2
1
R1397
2
1
R1398
21
21R1391
2
1
R1023
2
1
2
1
2
1
2
1
2
1
2
1
R1013
2
1
R1016
2
1
R1014
21
21
2
1
R1039
2
1
R1006
2
1
R1024
2
1
R1034
2
1
R1032
2
1
R1037
2
1
R1035
2
1
R1033
21
21
21
21
2
1
R1030
2
1
R1027
2
1
R1031
2
1
R1029
2
1
R1028
2
1
R1021
21
2
1
2
1
21
SHEETDATE
DEPARTMENT
SIZE
PROJECT DOCUMENT NUMBER REV
REVIEWER
DESIGNER
123
7 3 2 1 6 5 4
E
A
B
C
E
D
C
B
A
7 6 5 4
D
IN
IN
IN
IN
OUT
OUT
OUT
IN
IN
IN
IN
OUT
OUT
OUT
OUTOUTOUTOUT
IN
IN
IN
IN
IN
IN
OUT
IN
BI
IN
IN
IN
OUT
BI
IN
IN
IN
IN
OUTOUTOUTOUT
IN
IN
R1472R1471R1470
R1022
R1395
R1017
R1018
R1015
R1004
R1012
R1025
R1026
R676
R677
R611
R630R629
R612
C



Thu Sep 14 16:13:08 2023<NAME_2><NAME_1>MB FABCGT AMDV02288 OF 365
P1V8_CPU0_RT_1DP0V9_CPU0_RT1_2AP0V9_CPU0_RT1_2A_2DP1V8_CPU0_RT1_1A_1DP1V8_CPU0_RT1_1AP0V9_CPU0_RT_2DCHIP1/20W1%2000201LF1/20W0201LF1%1KEMPTYRT_CPU0_P1_VQPS0201LF05%1/20WCHIP00201LFCHIP5%1/20WRETIMER_CPU0_P1 POWER(6)
PT5161LRSICSMLFICSMLFPT5161LRS
NCF_A1_CPU0_P1_GNDNCF_CPU0_P1_GND
FH34
FH2
FG35
FG1
FE34
FE2
D35
D1
C34
C2
A35
A1
V35
V1
U34
U2
T4
T32
T22
T13
L35
L1
K34
K2
J4
J22
H31
H19
H16
H12
FJ19
FJ12
FF21
FF14
FD35
FD1
FC9
FC6
FC3
FC28
FC25
FC23
FC19
FB34
FB2
FA32
FA15
ET35
ET1
ER34
ER2
EP4
EP32
EP22
EP13
EJ35
EJ1
EH34
EH2
EG4
EG32
EG22
EG13
EB35
EB1
EA34
EA2
E33
E27
E14
DY4
DY32
DY22
DY13
DR35
DR1
DP34
DP2
DN4
DN32
DN22
DN13
DH35
DH1
DG34
DG2
DF4
DF32
DF22
DF13
DA35
DA1
CY34
CY2
CW4
CW32
CW22
CW13
CP35
CP1
CN34
CN2
CM4
CM32
CM22
CM13
CG35
CG1
CF34
CF2
CE4
CE32
CE22
CE13
BY35
BY1
BW34
BW2
BV4
BV32
BV22
BV13
BN35
BN1
BM34
BM2
BL4
BL32
BL22
BL13
BF35
BF1
BE34
BE2
BD4
BD32
BD22
BD13
B19
AW35
AW1
AV34
AV2
AU4
AU32
AU22
AU13
AM35
AM1
AL34
AL2
AK4
AK32
AK22
AK13
AE35
AE1
AD34
AD2
AC4
AC32
AC22
AC13
G1
CW20
CW17
BL20
BL17
T20
T17
EP20
EP17
EG20
EG17
DY20
DY17
DN20
DN17
DF20
DF17
BD20
BD17
AU20
AU17
AK20
AK17
AC20
AC17
BV17
CM20
CM17
CE20
CE17
BV20
U6011
U6011
4/11
PWR_2A_20
PWR_2A_19
PWR_2A_18
PWR_2A_17
PWR_2A_16
PWR_2A_15
PWR_2A_14
PWR_2A_13
PWR_2A_12
PWR_2A_11
PWR_2A_10
PWR_2A_9
PWR_2A_8
PWR_2A_7
PWR_2A_6
PWR_2A_5
PWR_2A_4
PWR_2A_3
PWR_2A_2
PWR_2A_1
PWR_1D
PWR_2D_4
PWR_2D_3
PWR_2D_2
PWR_2D_1
PWR_1A_5
PWR_1A_4
PWR_1A_3
PWR_1A_2
PWR_1A_1
VQPS
5/11
GND151
GND150
GND149
GND148
GND147
GND146
GND145
GND144
GND143
GND142
GND141
GND140
GND139
GND138
GND137
GND136
GND135
GND134
GND133
GND132
GND131
GND130
GND129
GND128
GND127
GND126
GND125
GND124
GND123
GND122
GND121
GND120
GND119
GND118
GND117
GND116
GND115
GND114
GND113
GND112
GND111
GND110
GND109
GND108
GND107
GND106
GND105
GND104
GND103
GND102
GND101
GND100
GND99
GND98
GND97
GND96
GND95
GND94
GND93
GND92
GND91
GND90
GND89
GND88
GND87
GND86
GND85
GND84
GND83
NCF_GND12
NCF_GND11
NCF_GND10
NCF_GND9
NCF_GND8
NCF_GND7
NCF_GND6
NCF_GND5
NCF_GND4
NCF_GND3
NCF_GND2
NCF_GND1
GND82
GND81
GND80
GND79
GND78
GND77
GND76
GND75
GND74
GND73
GND72
GND71
GND70
GND69
GND68
GND67
GND66
GND65
GND64
GND63
GND62
GND61
GND60
GND59
GND58
GND57
GND56
GND55
GND54
GND53
GND52
GND51
GND50
GND49
GND48
GND47
GND46
GND45
GND44
GND43
GND42
GND41
GND40
GND39
GND38
GND37
GND36
GND35
GND34
GND33
GND32
GND31
GND30
GND29
GND28
GND27
GND26
GND25
GND24
GND23
GND22
GND21
GND20
GND19
GND18
GND17
GND16
GND15
GND14
GND13
GND12
GND11
GND10
GND9
GND8
GND7
GND6
GND5
GND4
GND3
GND2
GND1
0.9V0.9V1.8V/ 1.8V1.2V / 1.5V
2
1
R1040
2
1
2
1
2
1
SHEETDATE
DEPARTMENT
SIZE
PROJECT DOCUMENT NUMBER REV
REVIEWER
DESIGNER
123
7 3 2 1 6 5 4
E
A
B
C
E
D
C
B
A
7 6 5 4
D
R1041
R1043
R1042
C



RETIMER EEPRO ADDRESS: 0XA0 (8 BIT) / 0X50 (7 BIT)
Thu Sep 14 16:13:00 2023<NAME_2><NAME_1>MB FABCGT AMDV02289 OF 365
P1V8_CPU0_RT_1D185186185186SMB_RT_CPU0_P1_ROM_SDASMB_RT_CPU0_P1_ROM_R_SDA1%33.2SMB_RT_CPU0_P1_ROM_SCLSMB_RT_CPU0_P1_ROM_R_SCLCHIP1/20W 0201LF0201LF1KCHIP1%1/20WC0201X7S10%10V0.1UFICU15_E2
RETIMER_CPU0_P1(7)
M24M02-DRMN6TPSMLF
7
4
8
5
6 3
2
1
U15
DU1
DU2
E2
VSSSDA
SCL
WC_N
VCC
2
1C664
2
1
21 21
SHEETDATE
DEPARTMENT
SIZE
PROJECT DOCUMENT NUMBER REV
REVIEWER
DESIGNER
123
7 3 2 1 6 5 4
E
A
B
C
E
D
C
B
A
7 6 5 4
D
INBI R1044R679R678
C



Thu Sep 14 16:13:08 2023<NAME_2><NAME_1>MB FABCGT AMDV02290 OF 365P0V9_CPU0_RT1_2A_2DP1V8_CPU0_RT1_1A_1DP1V8_CPU0_RT1_1AP0V9_CPU0_RT_2DP1V8_CPU0_RT_1DP0V9_CPU0_RT1_2A100UFC080520%X6S4VC0805X6S20%4V100UFX6S100UF4VC080520%20%100UFC0805X6S4VC0805100UF4VX6S20%C0805X6S20%4V100UF20%X6S100UFC08054V20%X6S020120%4V1UF0.1UF10%X7SC02010.1UF470UF1UFX7SC0201470UF20%SMLF2.5VSPCAP SPCAP2.5V20%SMLFC0805X6S4V100UF20%4V10%10V10V10VX7S X7S X7S X7S10% 10% 10%C0201C0201C0201020120%C04024.7UF6.3VX6S10V10%4VEMPTY1/4W1/16WBLM15PD121SN1D/1300MA040210V0201X6S20%4V1UF20%4V1UF4V0.1UF1UF4V1UF4V10V0.1UFX6S10V10%C0201X7S10%10V0.1UF020120%20%20%0201X6S0.1UFX7SC020110V0.1UF4V6.3V20%20%20%BLM21SN300SN1D/5AC0402C020120%4V1UF 1UF10VX7SC0201SMLFC040220%10UF22UFC0201C0201
20%C0402X6S20%0603LF0.1UF 0.1UF10V0.1UFEMPTYL28/R1008 COLAY WITH R1002/R10031UF 1UF10V 10VX6SC0402X6S10%X6S1UF4.7UF10UFX6S20%4V22UF22UFC0402X6S4V 4V22UF20%20%4V1UFX6S20%10UF6.3V4.7UFX6SC0201 C0201X7S10%10%10V10V20%20%20%20%10%0.1UFX6S20%10V10%X7S X7S0201X6S0201X6SR1010 AND R1011 COLAY0603LF010%10%C04026.3VC02010.1UF10V0.1UF0.1UF0.1UF1UF4VX7S04024.7UF4VX6S20%22UF10UF6.3VX6S6.3VC040220%IND22UF4VC0201SMLFIND05%0402LF0402LF1/16W0402LFEMPTY1/16W05%EMPTY
RETIMER_CPU0_P1 DECAPS(8)
5%00201X6SX7S0.1UF10%10V05%20%X6S10V1/4W5%X7SX6SINDSMLFX6S4V6.3VC0402 0402X6S4.7UF0201C0402X6S20%X7S X7S10%C0201X7S10V0201X6S6.3VX6S100NH/16AC04021UF10UFC040222UF10%X6S
10%X7S0402X6S20%6.3V0.1UF 0.1UF 0.1UF10V10%C0201C020110%4V4.7UF6.3VX6SC040210UF4V20%X6S20%6.3V1UFX6SX6S4V0402C0402X7SX7S1UF4VC0201 C0201X6S20%02010.1UFC02010201X6S20%0201X6S20%CHIP0.1UF0201X6S040210UF6.3V20%20%02010201020120%4V4V1UF4.7UF6.3VX6S0402X6S20%6.3V
C589
L28
C7013
C596C591
C594
C587
C590C588
C598
2121
2 1
L14L13
1 21 2
12
2
1
2
1C7012
2
1C7011
2
1
2
1
2
1
2
1
2
1
2
1
2
1
2
1
2
1
2
1
2
1
2
1
2
1
2
1
2
1
2
1
2
1
2
1
2
1
2
1
2
1
2
1
2
1
2
1
2
1
2
1
2
1
2
1
2
1
2
1
2
1
2
1
2
1
2
1
2
1
2
1
2
1
2
1
2
1
2
1
2
1
2
1
2
1
2
1
2
1
2
1
2
1
2
1
2
1
21
2
1
2
1
2
1
2
1
2
1
2
1
2
1
2
1
2
1
2
1
2
1
2
1
2
1
2
1
2
1
2
1
2
1
2
1
2
1
21
21R1003
CAD NOTE:
CAD NOTE:
R1008
C599C597C595
R1002
SHEETDATE
DEPARTMENT
SIZE
PROJECT DOCUMENT NUMBER REV
REVIEWER
DESIGNER
123
7 3 2 1 6 5 4
E
A
B
C
E
D
C
B
A
7 6 5 4
D
C660
C659C658
C624C621
C652
C622
C614
C619C615C610C608
C648C661C656
C655C651C646
C630C663C634C637C633
C636C632
C628C625
C613C620
C650C631
C653C649C638C644
C654C647
C627C635
C643C607
C657C616
C645C626
C618C609
C662
R1011
C623C617
C606C603C602C600
R1010
C601
C



Thu Aug 24 10:16:17 2023<NAME_2><NAME_1>MB FABCGT AMDV02291 OF 365RETIMER_CPU0_P1(9)
SHEETDATE
DEPARTMENT
SIZE
PROJECT DOCUMENT NUMBER REV
REVIEWER
DESIGNER
123
7 3 2 1 6 5 4
E
A
B
C
E
D
C
B
A
7 6 5 4
D
C



Thu Aug 24 10:16:18 2023<NAME_2><NAME_1>MB FABCGT AMDV02292 OF 365RETIMER_CPU0_P1(10)
SHEETDATE
DEPARTMENT
SIZE
PROJECT DOCUMENT NUMBER REV
REVIEWER
DESIGNER
123
7 3 2 1 6 5 4
E
A
B
C
E
D
C
B
A
7 6 5 4
D
C



Thu Aug 24 10:16:19 2023<NAME_2><NAME_1>MB FABCGT AMDV02293 OF 365BLANK
SHEETDATE
DEPARTMENT
SIZE
PROJECT DOCUMENT NUMBER REV
REVIEWER
DESIGNER
123
7 3 2 1 6 5 4
E
A
B
C
E
D
C
B
A
7 6 5 4
D
C



P/N SWAPP/N SWAPP/N SWAPP/N SWAPP/N SWAPP/N SWAPP/N SWAPP/N SWAPP/N SWAPP/N SWAPP/N SWAPP/N SWAPP/N SWAPP/N SWAPP/N SWAPCPU TO RETIMER CPU TO RETIMER
P5E_CPU0_P2_TX_C_DP/DN<0-15> LANE REVERSAL
Thu Sep 14 16:12:52 2023<NAME_2><NAME_1>MB FABCGT AMDV02294 OF 365
64646464P5E_CPU0_P2_TX_C_DP<15:8>IC PT5161LRSSMLF
RETIMER_CPU0_P2(1)
PT5161LRSSMLFICP5E_CPU0_P2_TX_C_DN<7:0>P5E_CPU0_P2_TX_C_DP<7:0>P5E_CPU0_P2_TX_C_DN<15:8>
CB34
BR34
BH34
BA34
AP34
AG34
Y34
N34
CD35
BU35
BK35
BC35
AT35
AJ35
AB35
R35
EV34
EL34
ED34
DU34
DK34
DC34
CT34
CJ34
EY35
EN35
EF35
DW35
DM35
DE35
CV35
CL35
8
10
11
12
13
15
1
1
6
5
3
2
3
4
5
6
15
14
9
13
12
11
10
9
8
14
7
2
0
0
4
7
U6012
U6012
8/11
B_PERN7
B_PERP7
B_PERN6
B_PERP6
B_PERN5
B_PERP5
B_PERN4
B_PERP4
B_PERN3
B_PERP3
B_PERN2
B_PERP2
B_PERN1
B_PERP1
B_PERN0
B_PERP0
9/11
B_PERN15
B_PERP15
B_PERN14
B_PERP14
B_PERN13
B_PERP13
B_PERN12
B_PERP12
B_PERN11
B_PERP11
B_PERN10
B_PERP10
B_PERN9
B_PERP9
B_PERN8
B_PERP8
RX : B_PER[7:0]
RX : B_PER[15:8]
SHEETDATE
DEPARTMENT
SIZE
PROJECT DOCUMENT NUMBER REV
REVIEWER
DESIGNER
123
7 3 2 1 6 5 4
E
A
B
C
E
D
C
B
A
7 6 5 4
D
IN
IN
IN
IN
C



RETIMER TO CPURETIMER TO CPU
P5E_CPU0_P2_RX_DP/DN<0-15> LANE REVERSAL
Thu Sep 14 16:12:52 2023<NAME_2><NAME_1>MB FABCGT AMDV02295 OF 365
25252525P5E_CPU0_P2_RX_DN<7:0>P5E_CPU0_P2_RX_DP<7:0>
RETIMER_CPU0_P2(2)
ICSMLFPT5161LRSICPT5161LRSSMLFP5E_CPU0_P2_RX_DN<15:8>P5E_CPU0_P2_RX_DP<15:8>
EU26
EK26
EC26
DT26
DJ26
DB26
CR26
CH26
EW29
EM29
EE29
DV29
DL29
DD29
CU29
CK29
CA26
BP26
BG26
AY26
AN26
AF26
W26
M26
CC29
BT29
BJ29
BB29
AR29
AH29
AA29
P29
14
14
13
13
12
10
12
10
9
8
8
11
2
2
7
7
6
6
5
5
4
4
3
3
1
1
0
0
9
11
15
15
U6012
U6012
7/11
A_PETN15
A_PETP15
A_PETN14
A_PETP14
A_PETN13
A_PETP13
A_PETN12
A_PETP12
A_PETN11
A_PETP11
A_PETN10
A_PETP10
A_PETN9
A_PETP9
A_PETN8
A_PETP8
6/11
A_PETN7
A_PETP7
A_PETN6
A_PETP6
A_PETN5
A_PETP5
A_PETN4
A_PETP4
A_PETN3
A_PETP3
A_PETN2
A_PETP2
A_PETN1
A_PETP1
A_PETN0
A_PETP0
TX : A_PET[15:8]
TX : A_PET[7:0]
SHEETDATE
DEPARTMENT
SIZE
PROJECT DOCUMENT NUMBER REV
REVIEWER
DESIGNER
123
7 3 2 1 6 5 4
E
A
B
C
E
D
C
B
A
7 6 5 4
D
OUT
OUT
OUT
OUT
C



P5E_CPU0_P2_RX_BUF_DP/DN <0-15> LANE REVERSAL
EXAMAX TO RETIMEREXAMAX TO RETIMERThu Sep 14 16:12:52 2023<NAME_2><NAME_1>MB FABCGT AMDV02296 OF 365
116116115115SMLFP5E_CPU0_P2_RX_BUF_DN<7:0>P5E_CPU0_P2_RX_BUF_DP<7:0>P5E_CPU0_P2_RX_BUF_DN<15:8>P5E_CPU0_P2_RX_BUF_DP<15:8>PT5161LRSSMLFIC ICPT5161LRS
RETIMER_CPU0_P2(3)
EY1
EN1
EF1
DW1
DM1
DE1
CV1
CL1
EV2
EL2
ED2
DU2
DK2
DC2
CT2
CJ2
CD1
BU1
BK1
BC1
AT1
AJ1
AB1
R1
CB2
BR2
BH2
BA2
AP2
AG2
Y2
N2 7
6
5
4
3
2
1
0
0
1
2
3
4
5
6
7
15
14
13
12
11
10
9
8
8
9
10
11
12
13
14
15
U6012U6012
2/11
A_PERN15
A_PERP15
A_PERN14
A_PERP14
A_PERN13
A_PERP13
A_PERN12
A_PERP12
A_PERN11
A_PERP11
A_PERN10
A_PERP10
A_PERN9
A_PERP9
A_PERN8
A_PERP8
1/11
A_PERN7
A_PERP7
A_PERN6
A_PERP6
A_PERN5
A_PERP5
A_PERN4
A_PERP4
A_PERN3
A_PERP3
A_PERN2
A_PERP2
A_PERN1
A_PERP1
A_PERN0
A_PERP0
RX : A_PER[15:8]
RX : A_PER[7:0]
SHEETDATE
DEPARTMENT
SIZE
PROJECT DOCUMENT NUMBER REV
REVIEWER
DESIGNER
123
7 3 2 1 6 5 4
E
A
B
C
E
D
C
B
A
7 6 5 4
D
IN
IN
IN
IN
C



P5E_CPU0_P2_TX_BUF_DP/DN <0-15> LANE REVERSAL
RETIMER TO EXAMAXRETIMER TO EXAMAXThu Sep 14 16:12:53 2023<NAME_2><NAME_1>MB FABCGT AMDV02297 OF 365298298116116298298115115
298298298298
P5E_CPU0_P2_TX_BUF_DN<7:0>P5E_CPU0_P2_TX_BUF_DP<7:0>P5E_CPU0_P2_TX_BUF_C_DN<7:0>P5E_CPU0_P2_TX_BUF_C_DP<7:0>DIFF BUS_0.22UFDIFF BUS_0.22UFDIFF BUS_0.22UFDIFF BUS_0.22UFDIFF BUS_0.22UFDIFF BUS_0.22UFDIFF BUS_0.22UFDIFF BUS_0.22UFDIFF BUS_0.22UFDIFF BUS_0.22UFDIFF BUS_0.22UFDIFF BUS_0.22UFDIFF BUS_0.22UFDIFF BUS_0.22UF6.3V20%X6SC0201DIFF BUS_0.22UFDIFF BUS_0.22UFP5E_CPU0_P2_TX_BUF_DP<15:8>P5E_CPU0_P2_TX_BUF_DN<15:8>P5E_CPU0_P2_TX_BUF_C_DP<15:8>P5E_CPU0_P2_TX_BUF_C_DN<15:8>DIFF BUS_0.22UFDIFF BUS_0.22UFDIFF BUS_0.22UFDIFF BUS_0.22UFDIFF BUS_0.22UFDIFF BUS_0.22UFDIFF BUS_0.22UFDIFF BUS_0.22UFDIFF BUS_0.22UFDIFF BUS_0.22UFDIFF BUS_0.22UFDIFF BUS_0.22UFDIFF BUS_0.22UFDIFF BUS_0.22UF6.3VC0201X6S20%DIFF BUS_0.22UFDIFF BUS_0.22UF
P5E_CPU0_P2_TX_BUF_DN<15:8>P5E_CPU0_P2_TX_BUF_DP<15:8>
RETIMER_CPU0_P2(4)
PT5161LRSSMLFIC P5E_CPU0_P2_TX_BUF_DP<7:0>P5E_CPU0_P2_TX_BUF_DN<7:0>SMLFICPT5161LRS
2 1
2 1
2 1
2 1
2 1
2 1
2 1
2 1
2 1
2 1
2 1
2 1
2 1
2 1
2 1
2 1
2 1
2 1
2 1
2 1
2 1
2 1
2 1
2 1
2 1
2 1
2 1
2 1
2 1
2 1
2 1
2 1
EU7
EK7
EC7
DT7
DJ7
DB7
CR7
CH7
EW10
EM10
EE10
DV10
DL10
DD10
CU10
CK10
CA7
BP7
BG7
AY7
AN7
AF7
W7
M7
CC10
BT10
BJ10
BB10
AR10
AH10
AA10
P10
7
6
5
7
6
4
3
4
5
3
2
0
1
2
1
0
7
7
6
6
5
5
4
4
3
3
2
2
1
0
1
0
15
14
13
15
14
13
12
11
10
12
11
9
8
10
9
8
15
15
14
13
14
13
12
11
12
10
11
10
9
8
9
8
5
7
15
8
9
10
11
12
13
14
8
9
10
11
12
13
14
15
7
2
3
4
6
0
1
0
1
2
3
4
5
6
U6012
C6582
C6581
C6583
C6584
C6585
C6586
C6587
C6588
C6589
C6590
C6591
C6592
C6593
C6594
C6595
C6596
C6565
C6566
U6012
C6569
C6568
C6567
C6570
C6571
C6572
C6574
C6573
C6576
C6575
C6578
C6577
C6579
C6580
10/11
B_PETN7
B_PETP7
B_PETN6
B_PETP6
B_PETN5
B_PETP5
B_PETN4
B_PETP4
B_PETN3
B_PETP3
B_PETN2
B_PETP2
B_PETN1
B_PETP1
B_PETN0
B_PETP0
11/11
B_PETN15
B_PETP15
B_PETN14
B_PETP14
B_PETN13
B_PETP13
B_PETN12
B_PETP12
B_PETN11
B_PETP11
B_PETN10
B_PETP10
B_PETN9
B_PETP9
B_PETN8
B_PETP8
TX : B_PET[7:0]
TX : B_PET[15:8]
2 12 1
2 12 1
2 12 1
2 12 1
2 12 1
2 12 1
2 12 1
2 12 1
2 12 1
2 1
2 12 1
2 1
2 12 1
2 12 1
2 12 1
2 12 1
2 12 1
SHEETDATE
DEPARTMENT
SIZE
PROJECT DOCUMENT NUMBER REV
REVIEWER
DESIGNER
123
7 3 2 1 6 5 4
E
A
B
C
E
D
C
B
A
7 6 5 4
D
OUT
OUT
ININ OUTOUTIN
OUT
OUT
OUTOUT
IN
C



CPU1 P0 RT ADDR: 0X48 (8-BIT) / 0X24 (7-BIT)
Thu Sep 14 16:12:57 2023<NAME_2><NAME_1>MB FABCGT AMDV02298 OF 365
P1V8_CPU0_RT_1DP1V8_CPU0_RT_1D
P1V8_CPU0_RT_1DP1V8_CPU0_RT_1DP1V8_CPU0_RT_1DP1V8_CPU0_RT_1DP1V8_CPU0_RT_1DSMB_RT_CPU0_P2_ROM_MUX_1D_R_SDASMB_RT_CPU0_P2_ROM_MUX_1D_SDASMB_RT_CPU0_P2_ROM_MUX_1D_R_SCLSMB_RT_CPU0_P2_ROM_MUX_1D_SCL1%49.90201LFCHIP1/20W1851861851862992992992992992992992992992992998129981299299299299299299299299299299299184182299299
299299
299299
2992992991842998129981299
1822992001%1/20WCHIP0201LFJTAG_TDI_RT_CPU0_P2JTAG_TMS_RT_CPU0_P2JTAG_TCK_RT_CPU0_P2RST_RT_CPU0_P2_RESET_NJTAG_TDO_RT_CPU0_P2RST_RT_CPU0_P2_PERST_NCLKREQ_RT_CPU0_P2_NRT_CPU0_P2_SCAN_MODERXDET_BYP_RT_CPU0_P2MODE_RT_CPU0_P24.7K5%1/20WEMPTY0201LF1/20W5%EMPTY4.7K0201LFEMPTY0201LF1/20W1%1K4.7K0201LF5%EMPTY1/20W1KJTAG_TEST_MODE_RT_CPU0_P2JTAG_TDI_RT_CPU0_P2CHIP0201LF5%4.7K1/20WCHIP0201LF4.7K0JTAG_TRST_RT_CPU0_P2_NJTAG_TMS_RT_CPU0_P2JTAG_TDO_RT_CPU0_P20201LFRST_RT_CPU0_P2_RESET_R_NRST_RT_CPU0_P2_PERST_R_N0201LFCHIP 0201LF0201LF1%CHIP1/20W10K1%1/20WEMPTY1K0201LFRXDET_BYP_RT_CPU0_P2RT_CPU0_P2_SCAN_MODEGPIO2_RT_CPU0_P2GPIO3_RT_CPU0_P20201LFPT5161LRSSMLFMODE_RT_CPU0_P2JTAG_TEST_MODE_RT_CPU0_P2TEST2_RT_CPU0_P2TEST1_RT_CPU0_P2TEST0_RT_CPU0_P2GPIO3_RT_CPU0_P2SMB_RT_CPU0_P2_R_SDASMB_RT_CPU0_P2_R2_SCLCLK_100M_RETIMER_CPU0_P2_DPCLK_100M_RETIMER_CPU0_P2_DN1%1%
IC
0201LFEMPTYRETIMER_CPU0_P2(5)51.11/20WEMPTY0201LF1/20W51.1CHIP0201LF05%CHIPCLK_100M_RETIMER_CPU0_P2_R_DNTEST2_RT_CPU0_P20201LFTEST0_RT_CPU0_P2
RT_CPU0_P2_ADDR3RT_CPU0_P2_ADDR2
TEST1_RT_CPU0_P2RT_CPU0_P2_ADDR3
RT_CPU0_P2_ADDR1RT_CPU0_P2_ADDR1RT_CPU0_P2_ADDR2SMB_RT_CPU0_P2_R_SCLSMB_RT_CPU0_P2_R2_SDAGPIO2_RT_CPU0_P2RST_RT_CPU0_P2_PERST_R_NRST_RT_CPU0_P2_RESET_R_N0201LF1/20WEMPTY4.7K5%1/20W10K0201LF1%CHIP0201LFCHIP10K1/20W1%EMPTY0201LF1K1%1/20WCHIP1/20W1%1K0201LF0201LFEMPTY1/20W1K1%1/20WCHIP1K1%0201LF0201LFCHIP1/20W1%20K1/20W1%EMPTY1K0201LF0
4.7KCHIP5%1/20W0201LF0201LF4.7K5%1/20WEMPTY0201LF5%4.7K1/20WEMPTY0201LF5%4.7KEMPTY1/20W1/20WEMPTY0201LF4.7K5%1/20WCHIP0201LF4.7K5%1/20WCHIP5%4.7K0201LF4.7KCHIP0201LF5%1/20W0201LF5%01/20W CHIP
4.7K5%1/20W0201LFEMPTY1/20WEMPTY0201LF4.7K5%10K1%CHIP0201LF1/20W0201LF1/20W5%4.7KEMPTY5%4.7K1/20WCHIP0201LFCHIP1/20W1%10K
CLK_100M_RETIMER_CPU0_P2_R_DP1/20WJTAG_TCK_RT_CPU0_P2
R1061R1062
FF30
FF27
FF24
E30
B28
B31
B25
B23
F34
FF33
E11
FF11
FJ16
FF18
B16
E18
F2
FJ9
E8
B12
FF8
B9
B6
B3
FJ31
FJ28
FJ25
FJ23
FJ6
FJ3
FF5
G35
U6012
CLOCK
3/11
EE_DAT
EE_CLK
CLKREQ_N
TEST2
TEST1
TEST0
T_SENSE
SMBDAT
SMBCLK
SMB_ADDR3
SMB_ADDR2
SMB_ADDR1
SCAN_MODE
RXDET_BYP
RESET_N
REFCLKP
REFCLKN
REFCLK_OUTP
REFCLK_OUTN
PERST_N
MODE
JTAG_TRST_N
JTAG_TMS
JTAG_TEST_MODE
JTAG_TDO
JTAG_TDI
JTAG_TCK
INT_N
GPIO3
GPIO2
GPIO1
GPIO0
MISCJTAGTEST EEPROMSMBUSGPIO
2
1
R1479
2
1
R1401
2
1
2
1
2
1
2
1
21
2
1
R1405
2
1
R1406
21R1400
2
1
R1065
2
1
2
1
2
1
2
1
2
1
2
1
R1055
2
1
R1058
2
1
R1056
21
21
2
1
R1080
2
1
R1048
2
1
R1066
2
1
R1077
2
1
R1075
2
1
R1079
2
1
R1078
2
1
R1076
21
21
21
21
21
21
2
1
2
1
2
1
R1073
2
1
R1069
2
1
R1072
2
1
R1063
2
1
R1074
2
1
R1070
SHEETDATE
DEPARTMENT
SIZE
PROJECT DOCUMENT NUMBER REV
REVIEWER
DESIGNER
123
7 3 2 1 6 5 4
E
A
B
C
E
D
C
B
A
7 6 5 4
D
IN
OUT
IN
IN
OUT
OUT
IN
IN
IN
IN
IN
OUT
OUT
OUTOUTOUTOUT
OUT
IN
IN
IN
IN
IN
IN
OUT
IN
BI
IN
IN
IN
OUT
BI
IN
IN
IN
IN
OUTOUTOUTOUT
IN
IN
R1478R1477R1476
R1064
R1404
R1059
R1060
R1057
R1047
R1054
R1068
R1067
R680
R681
R614
R613
R634R631
C



Thu Sep 14 16:13:09 2023<NAME_2><NAME_1>MB FABCGT AMDV02299 OF 365
200P1V8_CPU0_RT_1DP0V9_CPU0_RT2_2A_2DP0V9_CPU0_RT2_2AP1V8_CPU0_RT2_1A_1DP1V8_CPU0_RT2_1AP0V9_CPU0_RT_2DCHIP0201LF1/20W1%0201LF1%1KEMPTY1/20WRT_CPU0_P2_VQPS0201LF01/20WCHIP5%1/20W00201LF5%CHIP
SMLFPT5161LRSPT5161LRSSMLFICIC
RETIMER_CPU0_P2 POWER(6)NCF_A1_CPU0_P2_GNDNCF_CPU0_P2_GND
FH34
FH2
FG35
FG1
FE34
FE2
D35
D1
C34
C2
A35
A1
V35
V1
U34
U2
T4
T32
T22
T13
L35
L1
K34
K2
J4
J22
H31
H19
H16
H12
FJ19
FJ12
FF21
FF14
FD35
FD1
FC9
FC6
FC3
FC28
FC25
FC23
FC19
FB34
FB2
FA32
FA15
ET35
ET1
ER34
ER2
EP4
EP32
EP22
EP13
EJ35
EJ1
EH34
EH2
EG4
EG32
EG22
EG13
EB35
EB1
EA34
EA2
E33
E27
E14
DY4
DY32
DY22
DY13
DR35
DR1
DP34
DP2
DN4
DN32
DN22
DN13
DH35
DH1
DG34
DG2
DF4
DF32
DF22
DF13
DA35
DA1
CY34
CY2
CW4
CW32
CW22
CW13
CP35
CP1
CN34
CN2
CM4
CM32
CM22
CM13
CG35
CG1
CF34
CF2
CE4
CE32
CE22
CE13
BY35
BY1
BW34
BW2
BV4
BV32
BV22
BV13
BN35
BN1
BM34
BM2
BL4
BL32
BL22
BL13
BF35
BF1
BE34
BE2
BD4
BD32
BD22
BD13
B19
AW35
AW1
AV34
AV2
AU4
AU32
AU22
AU13
AM35
AM1
AL34
AL2
AK4
AK32
AK22
AK13
AE35
AE1
AD34
AD2
AC4
AC32
AC22
AC13
G1
CW20
CW17
BL20
BL17
T20
T17
EP20
EP17
EG20
EG17
DY20
DY17
DN20
DN17
DF20
DF17
BD20
BD17
AU20
AU17
AK20
AK17
AC20
AC17
BV17
CM20
CM17
CE20
CE17
BV20
U6012
U6012
4/11
PWR_2A_20
PWR_2A_19
PWR_2A_18
PWR_2A_17
PWR_2A_16
PWR_2A_15
PWR_2A_14
PWR_2A_13
PWR_2A_12
PWR_2A_11
PWR_2A_10
PWR_2A_9
PWR_2A_8
PWR_2A_7
PWR_2A_6
PWR_2A_5
PWR_2A_4
PWR_2A_3
PWR_2A_2
PWR_2A_1
PWR_1D
PWR_2D_4
PWR_2D_3
PWR_2D_2
PWR_2D_1
PWR_1A_5
PWR_1A_4
PWR_1A_3
PWR_1A_2
PWR_1A_1
VQPS
5/11
GND151
GND150
GND149
GND148
GND147
GND146
GND145
GND144
GND143
GND142
GND141
GND140
GND139
GND138
GND137
GND136
GND135
GND134
GND133
GND132
GND131
GND130
GND129
GND128
GND127
GND126
GND125
GND124
GND123
GND122
GND121
GND120
GND119
GND118
GND117
GND116
GND115
GND114
GND113
GND112
GND111
GND110
GND109
GND108
GND107
GND106
GND105
GND104
GND103
GND102
GND101
GND100
GND99
GND98
GND97
GND96
GND95
GND94
GND93
GND92
GND91
GND90
GND89
GND88
GND87
GND86
GND85
GND84
GND83
NCF_GND12
NCF_GND11
NCF_GND10
NCF_GND9
NCF_GND8
NCF_GND7
NCF_GND6
NCF_GND5
NCF_GND4
NCF_GND3
NCF_GND2
NCF_GND1
GND82
GND81
GND80
GND79
GND78
GND77
GND76
GND75
GND74
GND73
GND72
GND71
GND70
GND69
GND68
GND67
GND66
GND65
GND64
GND63
GND62
GND61
GND60
GND59
GND58
GND57
GND56
GND55
GND54
GND53
GND52
GND51
GND50
GND49
GND48
GND47
GND46
GND45
GND44
GND43
GND42
GND41
GND40
GND39
GND38
GND37
GND36
GND35
GND34
GND33
GND32
GND31
GND30
GND29
GND28
GND27
GND26
GND25
GND24
GND23
GND22
GND21
GND20
GND19
GND18
GND17
GND16
GND15
GND14
GND13
GND12
GND11
GND10
GND9
GND8
GND7
GND6
GND5
GND4
GND3
GND2
GND1
0.9V0.9V1.8V/ 1.8V1.2V / 1.5V
2
1
R1081
2
1
2
1
2
1
SHEETDATE
DEPARTMENT
SIZE
PROJECT DOCUMENT NUMBER REV
REVIEWER
DESIGNER
123
7 3 2 1 6 5 4
E
A
B
C
E
D
C
B
A
7 6 5 4
D
R1082
R1084
R1083
C



RETIMER EEPRO ADDRESS: 0XA0 (8 BIT) / 0X50 (7 BIT)
Thu Sep 14 16:13:00 2023<NAME_2><NAME_1>MB FABCGT AMDV02300 OF 365
P1V8_CPU0_RT_1D185186185186SMB_RT_CPU0_P2_ROM_SDASMB_RT_CPU0_P2_ROM_R_SDA1%33.2SMB_RT_CPU0_P2_ROM_SCLSMB_RT_CPU0_P2_ROM_R_SCL1/20W0201LFCHIP0201LFCHIP1/20W1%1K0.1UF10%10VX7SC0201U16_E2
RETIMER_CPU0_P2(7)
ICSMLFM24M02-DRMN6TP
7
4
8
5
6 3
2
1
U16
DU1
DU2
E2
VSSSDA
SCL
WC_N
VCC
2
1C989
2
1
21 21
SHEETDATE
DEPARTMENT
SIZE
PROJECT DOCUMENT NUMBER REV
REVIEWER
DESIGNER
123
7 3 2 1 6 5 4
E
A
B
C
E
D
C
B
A
7 6 5 4
D
BIIN R1085R683R682
C



Thu Sep 14 16:13:09 2023<NAME_2><NAME_1>MB FABCGT AMDV02301 OF 365P0V9_CPU0_RT2_2A_2D
P1V8_CPU0_RT_1DP0V9_CPU0_RT_2DP1V8_CPU0_RT2_1AP1V8_CPU0_RT2_1A_1DP0V9_CPU0_RT2_2AC0805X6S20%4V100UF100UFX6S4VC080520%X6S100UF20%4VC08054VX6S100UF20%C0805C0805100UF20%X6S4V4V100UFC0805X6S20%100UF4V20%C0805X6SC0201470UF20%SMLF2.5VSPCAP0.1UF2.5VSMLFSPCAP20%470UF4V100UFC0805X6S20%C02010.1UF10V04020.1UF10V10%X7S1UF4V0201X6S20%1UF20%4V1UFX6S0201020110%20%4V02011UF20%02014VX6SX7SC0201X7S10V0.1UF20%10UFCHIPX7SC02011UF20%1UFC04020.1UF4VX6S4V4V4.7UFC0402X6S10V04026.3V4.7UF6.3V0.1UF10%20%X6S X6S20%040220%10%X7S X7SX6S5%0603LF0.1UF6.3V10V22UFX6SC0402C040220%10UF6.3V20%10UFX6S20%22UF4VX6S20%4VX6S20%4VC04024V020104024VC0201X7S10V10%0201X6S0.1UF4V1UF4.7UF10UFX6SBLM21SN300SN1D/5A0402C0201X7SC0201X7S10%10V0.1UF0.1UF10V22UF20%X6SC040220%SMLFBLM15PD121SN1D/1300MAINDSMLFL29/R1050 COLAY WITH R1045/R10461/16W05%EMPTY0402LFINDR1051 AND R1053 COLAYRETIMER_CPU0_P2 DECAPS(8)
10VX7SC0201C0402X6S20%X7SC020110V0.1UF10%X7S4VX6SX6S4VX6S1UFX6SX7SC020110%10VC0201INDSMLFX6SC0402X6S01/4W0603LF5%1/4WEMPTY0X7S040210%0.1UFX7SC0201EMPTY1/16W5%0402LF1/16W EMPTY00402LF5%C0402X6S20%6.3V10UF0.1UF4.7UF6.3VC02011UF10V10% 10%20%4V22UF4.7UF20%6.3V10UF6.3V20%10V0.1UF20%20%20%10%6.3V4V0.1UF010VX7SC040220%X6S02011UFX6S0201X6S20%6.3V22UF4V20%X6SC040210VC020110%100NH/16A0.1UFC020110%X6SX7S22UF20%C0402 C0402X6SC040222UF02016.3VX6SX6S10%X7S20%1UFX6S20%X6S20%20%040210UF02014V1UF6.3V6.3V20%1UF4VX6S4V20%20%020110%X6SC02011UF0.1UF10V10%0.1UF020120%4.7UF1UFC020110V0.1UF10V10%02011UF4V20%02010.1UF10V10%C0201 C0201X6S0201X7S10V20%4VX6S4.7UF6.3VX6S1UF4V020110%X7SC02010.1UF10V10%X7SC0201
C667
L29
C7016
C672C669C665
C670
C676
C668C666
2121
2 1
L21L18
1 21 2
12
2
1
2
1C7015
2
1C7014
2
1
2
1
2
1
2
1
2
1
2
1
2
1
2
1
2
1
2
1
2
1
2
1
2
1
2
1
2
1
2
1
2
1
2
1
2
1
2
1
2
1
2
1
2
1
2
1
2
1
2
1
2
1
2
1
2
1
2
1
2
1
2
1
2
1
2
1
2
1
2
1
2
1
2
1
2
1
2
1
2
1
2
1
2
1
2
1
2
1
2
1
2
1
2
1
2
1
2
1
2
1
2
1
2
1
2
1
2
1
21
2
1
2
1
2
1
2
1
2
1
2
1
2
1
2
1
2
1
2
1
2
1
2
1
2
1
21
21R1046
CAD NOTE:
CAD NOTE:
R1050
C677C673C671
R1045
SHEETDATE
DEPARTMENT
SIZE
PROJECT DOCUMENT NUMBER REV
REVIEWER
DESIGNER
123
7 3 2 1 6 5 4
E
A
B
C
E
D
C
B
A
7 6 5 4
D
C985C972
C793C787
C803
C789C785C782C780C980C976C971C805C801
C973C986
C779C786
C968C804
C983
C799C974C988
C783C978C977
C969C966
C970C967
C979C975C792
C802C798
C981
C795
C796
C788C781C797
C784C800C987C790
C794C791
C984C982
R1053
R1051
C778C777C776C774
C775
C



Thu Aug 24 10:16:26 2023<NAME_2><NAME_1>MB FABCGT AMDV02302 OF 365RETIMER_CPU0_P2(9)
SHEETDATE
DEPARTMENT
SIZE
PROJECT DOCUMENT NUMBER REV
REVIEWER
DESIGNER
123
7 3 2 1 6 5 4
E
A
B
C
E
D
C
B
A
7 6 5 4
D
C



Thu Aug 24 10:16:27 2023<NAME_2><NAME_1>MB FABCGT AMDV02303 OF 365RETIMER_CPU0_P2(10)
SHEETDATE
DEPARTMENT
SIZE
PROJECT DOCUMENT NUMBER REV
REVIEWER
DESIGNER
123
7 3 2 1 6 5 4
E
A
B
C
E
D
C
B
A
7 6 5 4
D
C



Thu Aug 24 10:16:28 2023<NAME_2><NAME_1>MB FABCGT AMDV02304 OF 365BLANK
SHEETDATE
DEPARTMENT
SIZE
PROJECT DOCUMENT NUMBER REV
REVIEWER
DESIGNER
123
7 3 2 1 6 5 4
E
A
B
C
E
D
C
B
A
7 6 5 4
D
C



P/N SWAPP/N SWAPP/N SWAPP/N SWAPP/N SWAPP/N SWAPP/N SWAPP/N SWAPP/N SWAPP/N SWAPP/N SWAPP/N SWAPP/N SWAPP/N SWAPP5E_CPU0_P3_TX_C_DP/DN<0-15> LANE REVERSAL
CPU TO RETIMER CPU TO RETIMERThu Sep 14 16:12:53 2023<NAME_2><NAME_1>MB FABCGT AMDV02305 OF 365
64646464P5E_CPU0_P3_TX_C_DN<7:0>SMLFSMLFPT5161LRSPT5161LRS
RETIMER_CPU0_P3(1)
IC ICP5E_CPU0_P3_TX_C_DN<15:8>P5E_CPU0_P3_TX_C_DP<15:8>P5E_CPU0_P3_TX_C_DP<7:0>
EV34
EL34
ED34
DU34
DK34
DC34
CT34
CJ34
EY35
EN35
EF35
DW35
DM35
DE35
CV35
CL35
CB34
BR34
BH34
BA34
AP34
AG34
Y34
N34
CD35
BU35
BK35
BC35
AT35
AJ35
AB35
R35
12
10
11
8
11
13
8
10
12
0
0
6
7
7
1
3
2
4
5
2
1
6
5
4
15
15
9
13
14
14
9
3
U6013
U6013
9/11
B_PERN15
B_PERP15
B_PERN14
B_PERP14
B_PERN13
B_PERP13
B_PERN12
B_PERP12
B_PERN11
B_PERP11
B_PERN10
B_PERP10
B_PERN9
B_PERP9
B_PERN8
B_PERP8
8/11
B_PERN7
B_PERP7
B_PERN6
B_PERP6
B_PERN5
B_PERP5
B_PERN4
B_PERP4
B_PERN3
B_PERP3
B_PERN2
B_PERP2
B_PERN1
B_PERP1
B_PERN0
B_PERP0
RX : B_PER[15:8]
RX : B_PER[7:0]
SHEETDATE
DEPARTMENT
SIZE
PROJECT DOCUMENT NUMBER REV
REVIEWER
DESIGNER
123
7 3 2 1 6 5 4
E
A
B
C
E
D
C
B
A
7 6 5 4
D
IN
ININ
IN
C



P5E_CPU0_P3_RX_DP/DN<0-15> LANE REVERSAL
RETIMER TO CPURETIMER TO CPUThu Sep 14 16:12:53 2023<NAME_2><NAME_1>MB FABCGT AMDV02306 OF 365
2525 2525PT5161LRSICSMLFSMLFPT5161LRS
RETIMER_CPU0_P3(2)
P5E_CPU0_P3_RX_DP<15:8>P5E_CPU0_P3_RX_DN<15:8> P5E_CPU0_P3_RX_DP<7:0>P5E_CPU0_P3_RX_DN<7:0>IC
EU26
EK26
EC26
DT26
DJ26
DB26
CR26
CH26
EW29
EM29
EE29
DV29
DL29
DD29
CU29
CK29
CA26
BP26
BG26
AY26
AN26
AF26
W26
M26
CC29
BT29
BJ29
BB29
AR29
AH29
AA29
P29
14
14
6
1
0
1
2
3
0
4
5
7
5
7
8
8
9
9
10
10
11
11
12
12
13
13
15
3
2
4
6
15
U6013
U6013
7/11
A_PETN15
A_PETP15
A_PETN14
A_PETP14
A_PETN13
A_PETP13
A_PETN12
A_PETP12
A_PETN11
A_PETP11
A_PETN10
A_PETP10
A_PETN9
A_PETP9
A_PETN8
A_PETP8
6/11
A_PETN7
A_PETP7
A_PETN6
A_PETP6
A_PETN5
A_PETP5
A_PETN4
A_PETP4
A_PETN3
A_PETP3
A_PETN2
A_PETP2
A_PETN1
A_PETP1
A_PETN0
A_PETP0
TX : A_PET[15:8]
TX : A_PET[7:0]
SHEETDATE
DEPARTMENT
SIZE
PROJECT DOCUMENT NUMBER REV
REVIEWER
DESIGNER
123
7 3 2 1 6 5 4
E
A
B
C
E
D
C
B
A
7 6 5 4
D
OUT
OUT
OUT
OUT
C



EXAMAX TO RETIMEREXAMAX TO RETIMER
P5E_CPU0_P3_RX_BUF_DP/DN<0-15> LANE REVERSAL
Thu Sep 14 16:12:53 2023<NAME_2><NAME_1>MB FABCGT AMDV02307 OF 365
115116115116P5E_CPU0_P3_RX_BUF_DN<15:8>P5E_CPU0_P3_RX_BUF_DN<7:0>
RETIMER_CPU0_P3(3)
SMLFICPT5161LRSPT5161LRSICSMLFP5E_CPU0_P3_RX_BUF_DP<15:8>P5E_CPU0_P3_RX_BUF_DP<7:0>
EY1
EN1
EF1
DW1
DM1
DE1
CV1
CL1
EV2
EL2
ED2
DU2
DK2
DC2
CT2
CJ2
CD1
BU1
BK1
BC1
AT1
AJ1
AB1
R1
CB2
BR2
BH2
BA2
AP2
AG2
Y2
N2
15
15 7
7
12
14
14
13
12
11
10
9
8
8
9
11
13
10
0
1
2
3
4
5
6
2
3
4
5
6
0
1
U6013U6013
2/11
A_PERN15
A_PERP15
A_PERN14
A_PERP14
A_PERN13
A_PERP13
A_PERN12
A_PERP12
A_PERN11
A_PERP11
A_PERN10
A_PERP10
A_PERN9
A_PERP9
A_PERN8
A_PERP8
1/11
A_PERN7
A_PERP7
A_PERN6
A_PERP6
A_PERN5
A_PERP5
A_PERN4
A_PERP4
A_PERN3
A_PERP3
A_PERN2
A_PERP2
A_PERN1
A_PERP1
A_PERN0
A_PERP0
RX : A_PER[15:8]
RX : A_PER[7:0]
SHEETDATE
DEPARTMENT
SIZE
PROJECT DOCUMENT NUMBER REV
REVIEWER
DESIGNER
123
7 3 2 1 6 5 4
E
A
B
C
E
D
C
B
A
7 6 5 4
D
IN
ININ
IN
C



P5E_CPU0_P3_TX_BUF_DP/PD<0-15> LANE REVERSAL
RETIMER TO EXAMAXRETIMER TO EXAMAXThu Sep 14 16:12:54 2023<NAME_2><NAME_1>MB FABCGT AMDV02308 OF 365309309116116309309115115
309309309309
6.3VDIFF BUS_0.22UFDIFF BUS_0.22UFP5E_CPU0_P3_TX_BUF_DN<7:0>P5E_CPU0_P3_TX_BUF_DP<7:0> P5E_CPU0_P3_TX_BUF_C_DP<7:0>P5E_CPU0_P3_TX_BUF_C_DN<7:0>DIFF BUS_0.22UFDIFF BUS_0.22UFDIFF BUS_0.22UFDIFF BUS_0.22UFDIFF BUS_0.22UFDIFF BUS_0.22UFDIFF BUS_0.22UFDIFF BUS_0.22UFDIFF BUS_0.22UFDIFF BUS_0.22UFDIFF BUS_0.22UFDIFF BUS_0.22UFDIFF BUS_0.22UFC0201X6S6.3V20%DIFF BUS_0.22UFP5E_CPU0_P3_TX_BUF_DN<15:8>P5E_CPU0_P3_TX_BUF_DP<15:8> P5E_CPU0_P3_TX_BUF_C_DP<15:8>P5E_CPU0_P3_TX_BUF_C_DN<15:8>DIFF BUS_0.22UFDIFF BUS_0.22UFDIFF BUS_0.22UFDIFF BUS_0.22UFDIFF BUS_0.22UFDIFF BUS_0.22UFDIFF BUS_0.22UFDIFF BUS_0.22UFDIFF BUS_0.22UFDIFF BUS_0.22UFDIFF BUS_0.22UFDIFF BUS_0.22UFDIFF BUS_0.22UFDIFF BUS_0.22UFDIFF BUS_0.22UFDIFF BUS_0.22UF20%X6SC0201
P5E_CPU0_P3_TX_BUF_DP<15:8>P5E_CPU0_P3_TX_BUF_DN<15:8>
RETIMER_CPU0_P3(4)
SMLFICICSMLFPT5161LRSP5E_CPU0_P3_TX_BUF_DP<7:0>PT5161LRSP5E_CPU0_P3_TX_BUF_DN<7:0>
2 1
2 1
2 1
2 1
2 1
2 1
2 1
2 1
2 1
2 1
2 1
2 1
2 1
2 1
2 1
2 1
2 1
2 1
2 1
2 1
2 1
2 1
2 1
2 1
2 1
2 1
2 1
2 1
2 1
2 1
2 1
2 1
EU7
EK7
EC7
DT7
DJ7
DB7
CR7
CH7
EW10
EM10
EE10
DV10
DL10
DD10
CU10
CK10
CA7
BP7
BG7
AY7
AN7
AF7
W7
M7
CC10
BT10
BJ10
BB10
AR10
AH10
AA10
P10
7
7 7
7
5
6
4
3
2
1
0
6
4
5
3
2
1
0
6
5
4
3
2
6
5
4
3
2
1
0
0
1
15
14
15
14
11
12
13
13
12
11
10
9
10
9
8
8
15
14
15
14
13
12
11
13
12
11
10
9
10
9
8
8
8
15
14
12
13
10
11
9
8
9
10
11
12
13
14
15 7
0
1
2
3
4
5
6
0
1
2
3
4
5
6
7
U6013
C6613
C6614
C6616
C6615
C6617
C6619
C6618
C6620
C6622
C6621
C6624
C6623
C6627
C6626
C6625
C6628
U6013
C6597
C6598
C6599
C6600
C6601
C6602
C6603
C6604
C6605
C6606
C6607
C6608
C6609
C6610
C6612
C6611
10/11
B_PETN7
B_PETP7
B_PETN6
B_PETP6
B_PETN5
B_PETP5
B_PETN4
B_PETP4
B_PETN3
B_PETP3
B_PETN2
B_PETP2
B_PETN1
B_PETP1
B_PETN0
B_PETP0
11/11
B_PETN15
B_PETP15
B_PETN14
B_PETP14
B_PETN13
B_PETP13
B_PETN12
B_PETP12
B_PETN11
B_PETP11
B_PETN10
B_PETP10
B_PETN9
B_PETP9
B_PETN8
B_PETP8
TX : B_PET[7:0]
TX : B_PET[15:8]
2 12 1
2 12 1
2 1
2 1
2 1
2 1
2 12 1
2 12 1
2 1
2 12 1
2 1
2 12 1
2 12 1
2 12 1
2 12 1
2 12 1
2 12 1
2 12 1
2 12 1
SHEETDATE
DEPARTMENT
SIZE
PROJECT DOCUMENT NUMBER REV
REVIEWER
DESIGNER
123
7 3 2 1 6 5 4
E
A
B
C
E
D
C
B
A
7 6 5 4
D
OUT
OUT
ININ OUT OUTIN
OUT
OUT
OUTOUT IN
C



CPU1 P0 RT ADDR: 0X48 (8-BIT) / 0X24 (7-BIT)
Thu Sep 14 16:12:57 2023<NAME_2><NAME_1>MB FABCGT AMDV02309 OF 365
P1V8_CPU0_RT_1DP1V8_CPU0_RT_1DP1V8_CPU0_RT_1DP1V8_CPU0_RT_1DP1V8_CPU0_RT_1DP1V8_CPU0_RT_1DP1V8_CPU0_RT_1DSMB_RT_CPU0_P3_ROM_MUX_1D_R_SCLSMB_RT_CPU0_P3_ROM_MUX_1D_SCL1%49.91/20W CHIP0201LFSMB_RT_CPU0_P3_ROM_MUX_1D_R_SDASMB_RT_CPU0_P3_ROM_MUX_1D_SDA185186185186 813103103103103108131081310310310
310310
310310
310
310
310182182310310184184310310310310310310310310310813103103103103103103103103102001%1/20WCHIP0201LFRST_RT_CPU0_P3_RESET_N RST_RT_CPU0_P3_RESET_R_NCHIP1%0201LF10K1/20W1KEMPTY1/20W1%0201LFRXDET_BYP_RT_CPU0_P30201LFRT_CPU0_P3_SCAN_MODEGPIO2_RT_CPU0_P3CLK_100M_RETIMER_CPU0_P3_DP01/20WGPIO3_RT_CPU0_P31/20W5%4.7KEMPTY0201LFCHIP1/20W1%10K0201LF10K1%CHIP1/20W0201LF5%4.7K1/20WCHIP1/20WEMPTY0201LF4.7K5%4.7K5%1/20W0201LFEMPTY5%CHIP1/20W0201LF0CHIP1/20W0201LF4.7K5%0201LF1/20W5%4.7KCHIP0201LFCHIP1/20W5%4.7K4.7K1/20WEMPTY0201LF5%4.7K0201LF5%EMPTY1/20W4.7K0201LF5%1/20WEMPTY4.7K5%1/20WEMPTY0201LF4.7KCHIP5%1/20W0201LF1%1K0201LF1/20WEMPTY0201LF1%20K1/20WCHIP1%1/20WCHIP0201LF1KEMPTY0201LF1/20W1K1%CHIP1K1%1/20W0201LFEMPTY1K0201LF1%1/20W0201LFCHIP1/20W1%10K0201LFCHIP10K1/20W1%1/20W5%4.7KEMPTY0201LFRST_RT_CPU0_P3_RESET_R_NRST_RT_CPU0_P3_PERST_R_NMODE_RT_CPU0_P3JTAG_TEST_MODE_RT_CPU0_P3PT5161LRSTEST2_RT_CPU0_P3TEST1_RT_CPU0_P3
RT_CPU0_P3_ADDR1RT_CPU0_P3_ADDR2
RT_CPU0_P3_ADDR3
RT_CPU0_P3_ADDR3
TEST0_RT_CPU0_P30201LFCLK_100M_RETIMER_CPU0_P3_R_DP5%CLK_100M_RETIMER_CPU0_P3_R_DN CLK_100M_RETIMER_CPU0_P3_DN1/20WEMPTY51.11%51.1EMPTY0201LF 0201LF0201LF1%1/20W
ICSMLF
RETIMER_CPU0_P3(5)CHIPCHIPRT_CPU0_P3_ADDR1RT_CPU0_P3_ADDR2SMB_RT_CPU0_P3_R2_SDASMB_RT_CPU0_P3_R2_SCLSMB_RT_CPU0_P3_R_SDASMB_RT_CPU0_P3_R_SCLTEST2_RT_CPU0_P3TEST1_RT_CPU0_P3TEST0_RT_CPU0_P3GPIO3_RT_CPU0_P3GPIO2_RT_CPU0_P3MODE_RT_CPU0_P30JTAG_TDO_RT_CPU0_P3CHIP0201LF0201LFJTAG_TMS_RT_CPU0_P3JTAG_TDI_RT_CPU0_P300201LF0201LFRST_RT_CPU0_P3_PERST_R_NCLKREQ_RT_CPU0_P3_N1KCHIP5%4.7K1/20WCHIP0201LF
JTAG_TCK_RT_CPU0_P3RT_CPU0_P3_SCAN_MODERXDET_BYP_RT_CPU0_P3JTAG_TEST_MODE_RT_CPU0_P3JTAG_TRST_RT_CPU0_P3_N4.7K4.7K0201LF5%EMPTY1/20WEMPTY0201LF1/20W1%1K1/20W5%EMPTY4.7K0201LF4.7K5%1/20WEMPTY0201LFJTAG_TMS_RT_CPU0_P3JTAG_TDI_RT_CPU0_P3JTAG_TCK_RT_CPU0_P3JTAG_TDO_RT_CPU0_P3RST_RT_CPU0_P3_PERST_N
R1104 R1103
FF30
FF27
FF24
E30
B28
B31
B25
B23
F34
FF33
E11
FF11
FJ16
FF18
B16
E18
F2
FJ9
E8
B12
FF8
B9
B6
B3
FJ31
FJ28
FJ25
FJ23
FJ6
FJ3
FF5
G35
U6013
CLOCK
3/11
EE_DAT
EE_CLK
CLKREQ_N
TEST2
TEST1
TEST0
T_SENSE
SMBDAT
SMBCLK
SMB_ADDR3
SMB_ADDR2
SMB_ADDR1
SCAN_MODE
RXDET_BYP
RESET_N
REFCLKP
REFCLKN
REFCLK_OUTP
REFCLK_OUTN
PERST_N
MODE
JTAG_TRST_N
JTAG_TMS
JTAG_TEST_MODE
JTAG_TDO
JTAG_TDI
JTAG_TCK
INT_N
GPIO3
GPIO2
GPIO1
GPIO0
MISCJTAGTEST EEPROMSMBUSGPIO
2
1
R1485
2
1
2
1
R1409
2
1
2
1
2
1
21
2
1
R1413
2
1
R1414
21R1408
2
1
R1107
2
1
2
1
2
1
2
1
2
1
2
1
R1097
2
1
R1100
2
1
R1098
21
21
2
1
R1122
2
1
R1091
2
1
R1108
2
1
R1119
2
1
R1116
2
1
R1121
2
1
R1120
2
1
R1118
21
21
21
21
21
2
1
2
1
21
2
1
R1114
2
1
R1111
2
1
R1115
2
1
R1113
2
1
R1112
2
1
R1105
SHEETDATE
DEPARTMENT
SIZE
PROJECT DOCUMENT NUMBER REV
REVIEWER
DESIGNER
123
7 3 2 1 6 5 4
E
A
B
C
E
D
C
B
A
7 6 5 4
D
IN
IN
IN
IN
OUT
OUT
OUT
IN
IN
IN
IN
IN
OUT
OUT
OUTOUTOUT
OUT
OUT
IN
IN
IN
IN
IN
OUT
IN
BI
IN
IN
IN
IN
OUT
BI
IN
IN
IN
IN
OUTOUT
OUTOUT
IN
R1484R1483R1482
R1106
R1412
R1101
R1102
R1099
R1088
R1096
R1110
R1109
R684
R686
R615
R636R635
R616
C



Thu Sep 14 16:13:09 2023<NAME_2><NAME_1>MB FABCGT AMDV02310 OF 365
P0V9_CPU0_RT3_2A_2DP0V9_CPU0_RT3_2AP1V8_CPU0_RT3_1AP0V9_CPU0_RT_2DP1V8_CPU0_RT3_1A_1DP1V8_CPU0_RT_1DICSMLFPT5161LRSICPT5161LRSSMLF
RETIMER_CPU0_P3 POWER(6)NCF_A1_CPU0_P3_GNDNCF_CPU0_P3_GND1/20W00201LF5%CHIP0201LF01/20WCHIP5%RT_CPU0_P3_VQPS0201LFEMPTY1/20W1%1K1/20W0201LFCHIP1%200
FH34
FH2
FG35
FG1
FE34
FE2
D35
D1
C34
C2
A35
A1
V35
V1
U34
U2
T4
T32
T22
T13
L35
L1
K34
K2
J4
J22
H31
H19
H16
H12
FJ19
FJ12
FF21
FF14
FD35
FD1
FC9
FC6
FC3
FC28
FC25
FC23
FC19
FB34
FB2
FA32
FA15
ET35
ET1
ER34
ER2
EP4
EP32
EP22
EP13
EJ35
EJ1
EH34
EH2
EG4
EG32
EG22
EG13
EB35
EB1
EA34
EA2
E33
E27
E14
DY4
DY32
DY22
DY13
DR35
DR1
DP34
DP2
DN4
DN32
DN22
DN13
DH35
DH1
DG34
DG2
DF4
DF32
DF22
DF13
DA35
DA1
CY34
CY2
CW4
CW32
CW22
CW13
CP35
CP1
CN34
CN2
CM4
CM32
CM22
CM13
CG35
CG1
CF34
CF2
CE4
CE32
CE22
CE13
BY35
BY1
BW34
BW2
BV4
BV32
BV22
BV13
BN35
BN1
BM34
BM2
BL4
BL32
BL22
BL13
BF35
BF1
BE34
BE2
BD4
BD32
BD22
BD13
B19
AW35
AW1
AV34
AV2
AU4
AU32
AU22
AU13
AM35
AM1
AL34
AL2
AK4
AK32
AK22
AK13
AE35
AE1
AD34
AD2
AC4
AC32
AC22
AC13
G1
CW20
CW17
BL20
BL17
T20
T17
EP20
EP17
EG20
EG17
DY20
DY17
DN20
DN17
DF20
DF17
BD20
BD17
AU20
AU17
AK20
AK17
AC20
AC17
BV17
CM20
CM17
CE20
CE17
BV20
U6013
U6013
4/11
PWR_2A_20
PWR_2A_19
PWR_2A_18
PWR_2A_17
PWR_2A_16
PWR_2A_15
PWR_2A_14
PWR_2A_13
PWR_2A_12
PWR_2A_11
PWR_2A_10
PWR_2A_9
PWR_2A_8
PWR_2A_7
PWR_2A_6
PWR_2A_5
PWR_2A_4
PWR_2A_3
PWR_2A_2
PWR_2A_1
PWR_1D
PWR_2D_4
PWR_2D_3
PWR_2D_2
PWR_2D_1
PWR_1A_5
PWR_1A_4
PWR_1A_3
PWR_1A_2
PWR_1A_1
VQPS
5/11
GND151
GND150
GND149
GND148
GND147
GND146
GND145
GND144
GND143
GND142
GND141
GND140
GND139
GND138
GND137
GND136
GND135
GND134
GND133
GND132
GND131
GND130
GND129
GND128
GND127
GND126
GND125
GND124
GND123
GND122
GND121
GND120
GND119
GND118
GND117
GND116
GND115
GND114
GND113
GND112
GND111
GND110
GND109
GND108
GND107
GND106
GND105
GND104
GND103
GND102
GND101
GND100
GND99
GND98
GND97
GND96
GND95
GND94
GND93
GND92
GND91
GND90
GND89
GND88
GND87
GND86
GND85
GND84
GND83
NCF_GND12
NCF_GND11
NCF_GND10
NCF_GND9
NCF_GND8
NCF_GND7
NCF_GND6
NCF_GND5
NCF_GND4
NCF_GND3
NCF_GND2
NCF_GND1
GND82
GND81
GND80
GND79
GND78
GND77
GND76
GND75
GND74
GND73
GND72
GND71
GND70
GND69
GND68
GND67
GND66
GND65
GND64
GND63
GND62
GND61
GND60
GND59
GND58
GND57
GND56
GND55
GND54
GND53
GND52
GND51
GND50
GND49
GND48
GND47
GND46
GND45
GND44
GND43
GND42
GND41
GND40
GND39
GND38
GND37
GND36
GND35
GND34
GND33
GND32
GND31
GND30
GND29
GND28
GND27
GND26
GND25
GND24
GND23
GND22
GND21
GND20
GND19
GND18
GND17
GND16
GND15
GND14
GND13
GND12
GND11
GND10
GND9
GND8
GND7
GND6
GND5
GND4
GND3
GND2
GND1
0.9V0.9V1.8V/ 1.8V1.2V / 1.5V
2
1
R1123
2
1
2
1
2
1
SHEETDATE
DEPARTMENT
SIZE
PROJECT DOCUMENT NUMBER REV
REVIEWER
DESIGNER
123
7 3 2 1 6 5 4
E
A
B
C
E
D
C
B
A
7 6 5 4
D
R1124
R1126
R1125
C



RETIMER EEPRO ADDRESS: 0XA0 (8 BIT) / 0X50 (7 BIT)
Thu Sep 14 16:13:00 2023<NAME_2><NAME_1>MB FABCGT AMDV02311 OF 365
P1V8_CPU0_RT_1D185186185186SMB_RT_CPU0_P3_ROM_SDASMB_RT_CPU0_P3_ROM_R_SDA1%33.2SMB_RT_CPU0_P3_ROM_SCLSMB_RT_CPU0_P3_ROM_R_SCL0201LF1/20W CHIP1K1%1/20WCHIP0201LF0.1UFC0201X7S10%10VM24M02-DRMN6TPICSMLFU17_E2
RETIMER_CPU0_P3(7)
7
4
8
5
6 3
2
1
U17
DU1
DU2
E2
VSSSDA
SCL
WC_N
VCC
2
1C1057
2
1
21 21
SHEETDATE
DEPARTMENT
SIZE
PROJECT DOCUMENT NUMBER REV
REVIEWER
DESIGNER
123
7 3 2 1 6 5 4
E
A
B
C
E
D
C
B
A
7 6 5 4
D
INBI R1127R688R687
C



Thu Sep 14 16:13:10 2023<NAME_2><NAME_1>MB FABCGT AMDV02312 OF 365P0V9_CPU0_RT3_2A_2D
P0V9_CPU0_RT_2DP1V8_CPU0_RT_1DP1V8_CPU0_RT3_1AP1V8_CPU0_RT3_1A_1DP0V9_CPU0_RT3_2A100UF4V20%X6SC0805100UF4VX6SC080520%100UF4VX6S20%C0805C0805X6S4V20%100UFC08054V100UFX6S20%4V100UF20%X6SC0805X6S4VC0805100UF20%0201 0201SPCAP2.5VSMLF20%470UF 470UF20%SPCAPSMLF2.5V20%X6SC0805100UF4V0.1UFC0201C0201X7S10%020120%C0402X6S20%4V4.7UF6.3V0402X6S20%22UF10VX6S20%0402C0402X6S20%4V20%X6S0201X6S0.1UF10V10%C0201 C020110%0.1UF10V10%10V0.1UF0.1UFX7S1UF20%0201X6S1UF4V4V20%X6S0201X7SC020110%X7S10V0.1UF10V10%6.3VX6S0201X6S4.7UF20%20%10UF10V0.1UF4V20%4VX6S1UF20%X6S04020.1UF10V1UFX6SX6SC02014V4VX6S020102014V1UFX6S20%10UFX6SC0402X6S20%X6SX7S1UF6.3V6.3VC0201 C0201X7S10%0.1UF10V10%10V10V0.1UF4V0.1UFX7SX7S X7SC020110V0.1UF0.1UF6.3V20%C020110VX7SC0201010UF10V10%4VIND22UFX6S20%5%5%BLM21SN300SN1D/5AX6S20%SMLFR1094 AND R1095 COLAY0.1UF4V
RETIMER_CPU0_P3 DECAPS(8)0603LF1/4W5%00EMPTY1/4W5%0603LFX7SEMPTY20%0201X6SC0201X7S10%10VX6S20%6.3VX6S040210% 10%X7S10%0.1UFC0201X7S10V10%0.1UFX6S X6S20%20%10V10%C0201INDC0402X6SC0201X7SC0201X7S10%X6S1UF10VX7SX7SX7S4V0.1UF01UF00402LF1/16W0402LF1/16W5%INDSMLFBLM15PD121SN1D/1300MA0402LFEMPTY1/16WEMPTYX6S20%10UF22UF4.7UFC0402C040220%4V20%6.3V1UF4VX6S20%C0402C04021UFSMLF100NH/16A22UFX6S10UF6.3VX6SC04021UF4V20%6.3V20%20%4.7UF10%20%X6S02010402L30/R1093 COLAY WITH R1086/R108702010.1UF10V0.1UF0402X6S0402X6S4.7UF6.3VX6S0201C02016.3VC040210UF10UF20%4.7UF4V 4V 4V6.3V20%20%20%22UF 22UF 22UF6.3V4.7UFX6S20%20%4V4VC0402 C0402 C04021UF02011UF1UF4V20%20%0.1UF1UFX7S1UF4V10V10%X6S0201020110% 10%10V20%1UFC02010.1UFCHIP10%C0201 C02016.3VC04024V0201X7SC0201
C992
C7019
C997C994C990
C996C993C991
C999
2121
2 1
L23L22
1 21 2
L3012
2
1
2
1C7018
2
1C7017
2
1
2
1
2
1
2
1
2
1
2
1
2
1
2
1
2
1
2
1
2
1
2
1
2
1
2
1
2
1
2
1
2
1
2
1
2
1
2
1
2
1
2
1
2
1
2
1
2
1
2
1
2
1
2
1
2
1
2
1
2
1
2
1
2
1
2
1
2
1
2
1
2
1
2
1
2
1
2
1
2
1
2
1
2
1
2
1
2
1
2
1
2
1
2
1
2
1
21
2
1
2
1
2
1
2
1
2
1
2
1
2
1
2
1
2
1
2
1
2
1
2
1
2
1
2
1
2
1
2
1
2
1
2
1
2
1
21
21R1087
CAD NOTE:
CAD NOTE:
R1093
C1000C998C995
R1086
SHEETDATE
DEPARTMENT
SIZE
PROJECT DOCUMENT NUMBER REV
REVIEWER
DESIGNER
123
7 3 2 1 6 5 4
E
A
B
C
E
D
C
B
A
7 6 5 4
D
C1053C1051
C1020C1018
C1045
C1040
C1048C1012C1009C1007
C1049C1037C1041C1030
C1016C1038C1032 C1044
C1026C1033C1029
C1028
C1025C1022
C1017C1013C1050C1046
C1019
C1047C1043C1011C1008
C1056C1054
C1015C1039
C1034
C1006C1031
C1035C1055C1052C1010
C1036C1023
C1027C1024
R1095
C1021C1014
C1005C1004C1003C1001
R1094
C1002
C



Thu Aug 24 10:16:35 2023<NAME_2><NAME_1>MB FABCGT AMDV02313 OF 365RETIMER_CPU0_P3(9)
SHEETDATE
DEPARTMENT
SIZE
PROJECT DOCUMENT NUMBER REV
REVIEWER
DESIGNER
123
7 3 2 1 6 5 4
E
A
B
C
E
D
C
B
A
7 6 5 4
D
C



Thu Aug 24 10:16:36 2023<NAME_2><NAME_1>MB FABCGT AMDV02314 OF 365RETIMER_CPU0_P3(10)
SHEETDATE
DEPARTMENT
SIZE
PROJECT DOCUMENT NUMBER REV
REVIEWER
DESIGNER
123
7 3 2 1 6 5 4
E
A
B
C
E
D
C
B
A
7 6 5 4
D
C



Thu Aug 24 10:16:37 2023<NAME_2><NAME_1>MB FABCGT AMDV02315 OF 365BLANK
SHEETDATE
DEPARTMENT
SIZE
PROJECT DOCUMENT NUMBER REV
REVIEWER
DESIGNER
123
7 3 2 1 6 5 4
E
A
B
C
E
D
C
B
A
7 6 5 4
D
C



P/N SWAPP/N SWAPP/N SWAP
P5E_CPU1_P0_TX_C_DP/DN<0-15> LANE REVERSALP/N SWAPP/N SWAPP/N SWAPP/N SWAPP/N SWAPP/N SWAPP/N SWAPP/N SWAPP/N SWAPP/N SWAPP/N SWAPCPU TO RETIMER CPU TO RETIMERThu Sep 14 16:12:54 2023<NAME_2><NAME_1>MB FABCGT AMDV02316 OF 365
65656565ICPT5161LRSSMLFICPT5161LRSSMLF
RETIMER_CPU1_P0(1)
P5E_CPU1_P0_TX_C_DP<7:0>P5E_CPU1_P0_TX_C_DN<7:0>P5E_CPU1_P0_TX_C_DN<15:8>P5E_CPU1_P0_TX_C_DP<15:8>
EV34
EL34
ED34
DU34
DK34
DC34
CT34
CJ34
EY35
EN35
EF35
DW35
DM35
DE35
CV35
CL35
CB34
BR34
BH34
BA34
AP34
AG34
Y34
N34
CD35
BU35
BK35
BC35
AT35
AJ35
AB35
R35
13
14
13
15
15
6
12
11
10
9
8
8
9
10
11
12
14
6
5
4
3
2
0
0
2
3
4
5
7
7
1
1
U6014
U6014
9/11
B_PERN15
B_PERP15
B_PERN14
B_PERP14
B_PERN13
B_PERP13
B_PERN12
B_PERP12
B_PERN11
B_PERP11
B_PERN10
B_PERP10
B_PERN9
B_PERP9
B_PERN8
B_PERP8
8/11
B_PERN7
B_PERP7
B_PERN6
B_PERP6
B_PERN5
B_PERP5
B_PERN4
B_PERP4
B_PERN3
B_PERP3
B_PERN2
B_PERP2
B_PERN1
B_PERP1
B_PERN0
B_PERP0
RX : B_PER[15:8]
RX : B_PER[7:0]
SHEETDATE
DEPARTMENT
SIZE
PROJECT DOCUMENT NUMBER REV
REVIEWER
DESIGNER
123
7 3 2 1 6 5 4
E
A
B
C
E
D
C
B
A
7 6 5 4
D
IN
IN
IN
IN
C



P5E_CPU1_P0_RX_DP/DN<0-15> LANE REVERSAL
RETIMER TO CPURETIMER TO CPUThu Sep 14 16:12:54 2023<NAME_2><NAME_1>MB FABCGT AMDV02317 OF 365
51515151P5E_CPU1_P0_RX_DN<7:0>P5E_CPU1_P0_RX_DP<7:0>PT5161LRS
RETIMER_CPU1_P0(2)
ICSMLFPT5161LRSICSMLFP5E_CPU1_P0_RX_DP<15:8>P5E_CPU1_P0_RX_DN<15:8>
EU26
EK26
EC26
DT26
DJ26
DB26
CR26
CH26
EW29
EM29
EE29
DV29
DL29
DD29
CU29
CK29
CA26
BP26
BG26
AY26
AN26
AF26
W26
M26
CC29
BT29
BJ29
BB29
AR29
AH29
AA29
P29
1
1
7
3
4
3
2
5
8
6
4
6
5
2
0
15
15
13
12
12
13
11
10
9
9
10
11
8
0
7
14
14
U6014
U6014
7/11
A_PETN15
A_PETP15
A_PETN14
A_PETP14
A_PETN13
A_PETP13
A_PETN12
A_PETP12
A_PETN11
A_PETP11
A_PETN10
A_PETP10
A_PETN9
A_PETP9
A_PETN8
A_PETP8
6/11
A_PETN7
A_PETP7
A_PETN6
A_PETP6
A_PETN5
A_PETP5
A_PETN4
A_PETP4
A_PETN3
A_PETP3
A_PETN2
A_PETP2
A_PETN1
A_PETP1
A_PETN0
A_PETP0
TX : A_PET[15:8]
TX : A_PET[7:0]
SHEETDATE
DEPARTMENT
SIZE
PROJECT DOCUMENT NUMBER REV
REVIEWER
DESIGNER
123
7 3 2 1 6 5 4
E
A
B
C
E
D
C
B
A
7 6 5 4
D
OUT
OUT
OUT
OUT
C



EXAMAX TO RETIMEREXAMAX TO RETIMER
P5E_CPU1_P0_RX_BUF_DP/DN<0-15> LANE REVERSAL
Thu Sep 14 16:12:51 2023<NAME_2><NAME_1>MB FABCGT AMDV02318 OF 365
122122121121P5E_CPU1_P0_RX_BUF_DN<7:0>P5E_CPU1_P0_RX_BUF_DP<7:0>P5E_CPU1_P0_RX_BUF_DN<15:8>P5E_CPU1_P0_RX_BUF_DP<15:8>SMLFICPT5161LRSPT5161LRSICSMLF
RETIMER_CPU1_P0(3)
EY1
EN1
EF1
DW1
DM1
DE1
CV1
CL1
EV2
EL2
ED2
DU2
DK2
DC2
CT2
CJ2
CD1
BU1
BK1
BC1
AT1
AJ1
AB1
R1
CB2
BR2
BH2
BA2
AP2
AG2
Y2
N2 7
6
5
4
3
2
1
0
6
5
4
3
2
1
0
7
15
14
13
12
11
10
9
8
14
13
12
11
10
9
8
15
U6014U6014
2/11
A_PERN15
A_PERP15
A_PERN14
A_PERP14
A_PERN13
A_PERP13
A_PERN12
A_PERP12
A_PERN11
A_PERP11
A_PERN10
A_PERP10
A_PERN9
A_PERP9
A_PERN8
A_PERP8
1/11
A_PERN7
A_PERP7
A_PERN6
A_PERP6
A_PERN5
A_PERP5
A_PERN4
A_PERP4
A_PERN3
A_PERP3
A_PERN2
A_PERP2
A_PERN1
A_PERP1
A_PERN0
A_PERP0
RX : A_PER[15:8]
RX : A_PER[7:0]
SHEETDATE
DEPARTMENT
SIZE
PROJECT DOCUMENT NUMBER REV
REVIEWER
DESIGNER
123
7 3 2 1 6 5 4
E
A
B
C
E
D
C
B
A
7 6 5 4
D
IN
ININ
IN
C



RETIMER TO EXAMAX
P5E_CPU1_P0_TX_BUF_DP/DN<0-15> LANE REVERSAL
RETIMER TO EXAMAXThu Sep 14 16:12:54 2023<NAME_2><NAME_1>MB FABCGT AMDV02319 OF 365320320122122320320121121
320320320320
DIFF BUS_0.22UFP5E_CPU1_P0_TX_BUF_DP<7:0>P5E_CPU1_P0_TX_BUF_DN<7:0>P5E_CPU1_P0_TX_BUF_C_DP<7:0>P5E_CPU1_P0_TX_BUF_C_DN<7:0>DIFF BUS_0.22UFDIFF BUS_0.22UFDIFF BUS_0.22UFDIFF BUS_0.22UFDIFF BUS_0.22UFDIFF BUS_0.22UFDIFF BUS_0.22UFDIFF BUS_0.22UFDIFF BUS_0.22UFDIFF BUS_0.22UFDIFF BUS_0.22UFDIFF BUS_0.22UFC0201DIFF BUS_0.22UF6.3V20%X6SDIFF BUS_0.22UFDIFF BUS_0.22UFP5E_CPU1_P0_TX_BUF_DN<15:8>P5E_CPU1_P0_TX_BUF_DP<15:8>P5E_CPU1_P0_TX_BUF_C_DN<15:8>P5E_CPU1_P0_TX_BUF_C_DP<15:8>DIFF BUS_0.22UFDIFF BUS_0.22UFDIFF BUS_0.22UFDIFF BUS_0.22UFDIFF BUS_0.22UFDIFF BUS_0.22UFDIFF BUS_0.22UFDIFF BUS_0.22UFDIFF BUS_0.22UFDIFF BUS_0.22UFDIFF BUS_0.22UFDIFF BUS_0.22UFDIFF BUS_0.22UFDIFF BUS_0.22UFDIFF BUS_0.22UFC020120%X6S6.3VDIFF BUS_0.22UF
IC ICPT5161LRSSMLFPT5161LRSSMLF
RETIMER_CPU1_P0(4)
P5E_CPU1_P0_TX_BUF_DP<15:8>P5E_CPU1_P0_TX_BUF_DN<15:8>P5E_CPU1_P0_TX_BUF_DP<7:0>P5E_CPU1_P0_TX_BUF_DN<7:0>
2 1
2 1
2 1
2 1
2 1
2 1
2 1
2 1
2 1
2 1
2 1
2 1
2 1
2 1
2 1
2 1
2 1
2 1
2 1
2 1
2 1
2 1
2 1
2 1
2 1
2 1
2 1
2 1
2 1
2 1
2 1
2 1
EU7
EK7
EC7
DT7
DJ7
DB7
CR7
CH7
EW10
EM10
EE10
DV10
DL10
DD10
CU10
CK10
CA7
BP7
BG7
AY7
AN7
AF7
W7
M7
CC10
BT10
BJ10
BB10
AR10
AH10
AA10
P10
7
6
5
4
7
6
5
7
5
7
4
5
3
2
1
0
4
3
2
1
0
4
3
2
1
0
3
2
1
0
6
6
13
15
14
12
11
10
9
8
15
14
13
12
11
10
9
8
15
15
14
14
13
13
12
11
11
10
10
9
8
9
8
12
14
8
9
10
11
12
13
8
9
10
11
12
13
14
15
7
0
1
2
3
4
5
6
0
1
2
3
4
5
6
7
15
U6014
C6645
C6646
C6648
C6647
C6650
C6649
C6651
C6652
C6653
C6654
C6655
C6656
C6657
C6658
C6659
C6660
C6630
C6629
C6631
C6632
U6014
C6633
C6634
C6635
C6636
C6638
C6637
C6640
C6639
C6642
C6641
C6643
C6644
10/11
B_PETN7
B_PETP7
B_PETN6
B_PETP6
B_PETN5
B_PETP5
B_PETN4
B_PETP4
B_PETN3
B_PETP3
B_PETN2
B_PETP2
B_PETN1
B_PETP1
B_PETN0
B_PETP0
11/11
B_PETN15
B_PETP15
B_PETN14
B_PETP14
B_PETN13
B_PETP13
B_PETN12
B_PETP12
B_PETN11
B_PETP11
B_PETN10
B_PETP10
B_PETN9
B_PETP9
B_PETN8
B_PETP8
TX : B_PET[7:0]
TX : B_PET[15:8]
2 12 1
2 12 1
2 12 1
2 12 1
2 12 1
2 12 1
2 12 1
2 12 1
2 12 1
2 12 1
2 12 1
2 12 1
2 12 1
2 12 1
2 12 1
2 12 1
SHEETDATE
DEPARTMENT
SIZE
PROJECT DOCUMENT NUMBER REV
REVIEWER
DESIGNER
123
7 3 2 1 6 5 4
E
A
B
C
E
D
C
B
A
7 6 5 4
D
OUT
OUT
ININ OUTOUTIN
OUT
OUT
OUTOUT IN
C



CPU1 P0 RT ADDR: 0X48 (8-BIT) / 0X24 (7-BIT)
Thu Sep 14 16:12:51 2023<NAME_2><NAME_1>MB FABCGT AMDV02320 OF 365
P1V8_CPU1_RT_1DP1V8_CPU1_RT_1DP1V8_CPU1_RT_1DP1V8_CPU1_RT_1DP1V8_CPU1_RT_1DP1V8_CPU1_RT_1DP1V8_CPU1_RT_1D221%1/20WGPIO2_RT_CPU1_P0RST_RT_CPU1_P0_RESET_R_N0201LFEMPTY1/20W5%4.7K10K1/20W0201LFRT_CPU1_P0_ADDR3RETIMER_CPU1_P0(5)CLK_100M_RETIMER_CPU1_P0_R_DNSMB_RT_CPU1_P0_R_SCLTEST1_RT_CPU1_P0GPIO3_RT_CPU1_P0GPIO2_RT_CPU1_P0SMB_RT_CPU1_P0_R_SDAJTAG_TEST_MODE_RT_CPU1_P0TEST0_RT_CPU1_P0TEST2_RT_CPU1_P0 RST_RT_CPU1_P0_PERST_R_N
TEST2_RT_CPU1_P0TEST0_RT_CPU1_P0SMB_RT_CPU1_P0_R2_SCLSMB_RT_CPU1_P0_R2_SDART_CPU1_P0_ADDR1RT_CPU1_P0_ADDR2TEST1_RT_CPU1_P0CLK_100M_RETIMER_CPU1_P0_DN
MODE_RT_CPU1_P0RT_CPU1_P0_ADDR3RT_CPU1_P0_ADDR2RT_CPU1_P0_ADDR11K1/20W1%0201LFEMPTY0201LF1/20WCHIP1%1K0201LF1/20W1%20KCHIP1%EMPTY1/20W1K0201LF1/20WEMPTY1%1K0201LF1K1/20W1%CHIP0201LF1%0201LFCHIP1/20W10KCHIP1%0201LF1/20WEMPTY4.7K5%CHIP4.7K1/20W0201LF5%5%4.7KEMPTY1/20W0201LF00
0201LFEMPTY4.7K5%1/20W0201LF1/20WCHIP5%4.7K0201LFCHIP1/20W1%10K0201LFCHIP1/20W1%10KCHIP0201LF1/20W5%4.7K4.7K1/20WCHIP0201LF5%CHIP1/20W4.7K0201LF5%0201LFEMPTY1/20W4.7K5%4.7K1/20WEMPTY0201LF5%EMPTY0201LF4.7K5%1/20W1/20W0201LFEMPTY4.7K5%
51.11/20WEMPTY1%0201LF51.11/20W0201LFEMPTY1%1/20W0201LF5%0CHIPCHIP0201LF0201LFICPT5161LRSSMLFCHIP1/20W5%0CLK_100M_RETIMER_CPU1_P0_R_DP CLK_100M_RETIMER_CPU1_P0_DPRXDET_BYP_RT_CPU1_P0GPIO3_RT_CPU1_P0RT_CPU1_P0_SCAN_MODE1KEMPTY1/20W1%0201LFCHIP0201LF1/20W10K1%CHIP0201LF4.7K5%1/20WCHIP0201LFMODE_RT_CPU1_P0RST_RT_CPU1_P0_PERST_R_NJTAG_TRST_RT_CPU1_P0_N1K0201LF0201LF0201LFRST_RT_CPU1_P0_RESET_R_N4.7KJTAG_TEST_MODE_RT_CPU1_P0CHIPJTAG_TCK_RT_CPU1_P0JTAG_TDO_RT_CPU1_P0JTAG_TMS_RT_CPU1_P0JTAG_TDI_RT_CPU1_P00201LFEMPTY1/20W4.7K5%0201LFEMPTY1/20W4.7K5%0201LFEMPTY1/20W1%1K0201LFEMPTY1/20W4.7K5%RXDET_BYP_RT_CPU1_P0RT_CPU1_P0_SCAN_MODECLKREQ_RT_CPU1_P0_NRST_RT_CPU1_P0_PERST_NJTAG_TCK_RT_CPU1_P0JTAG_TDO_RT_CPU1_P0JTAG_TMS_RT_CPU1_P0JTAG_TDI_RT_CPU1_P0RST_RT_CPU1_P0_RESET_NCHIP1%1/20W0201LF20032132181
32118318432132132118432132132132181
321321321
321321321321
183 3213213213213218132181321321321321321321321321321321321186 185186 185SMB_RT_CPU1_P0_ROM_MUX_1D_R_SDASMB_RT_CPU1_P0_ROM_MUX_1D_SDA0201LF49.9 1/20W1%CHIP321SMB_RT_CPU1_P0_ROM_MUX_1D_R_SCLSMB_RT_CPU1_P0_ROM_MUX_1D_SCL0201LFCHIP321
R6720R6721
FF30
FF27
FF24
E30
B28
B31
B25
B23
F34
FF33
E11
FF11
FJ16
FF18
B16
E18
F2
FJ9
E8
B12
FF8
B9
B6
B3
FJ31
FJ28
FJ25
FJ23
FJ6
FJ3
FF5
G35
U6014
CLOCK
3/11
EE_DAT
EE_CLK
CLKREQ_N
TEST2
TEST1
TEST0
T_SENSE
SMBDAT
SMBCLK
SMB_ADDR3
SMB_ADDR2
SMB_ADDR1
SCAN_MODE
RXDET_BYP
RESET_N
REFCLKP
REFCLKN
REFCLK_OUTP
REFCLK_OUTN
PERST_N
MODE
JTAG_TRST_N
JTAG_TMS
JTAG_TEST_MODE
JTAG_TDO
JTAG_TDI
JTAG_TCK
INT_N
GPIO3
GPIO2
GPIO1
GPIO0
MISCJTAGTEST EEPROMSMBUSGPIO
21
2
1
2
1
R1467
2
1
2
1
2
1
R1381
2
1
2
1
R1388
2
1
R1389
21R1380
21
2
1
2
1
2
1
R6715
2
1
2
1
R6713
2
1
R6712
2
1
R6724
2
1
2
1
2
1
R6725
2
1
R726
2
1
R6722
21
21
2
1
R728
2
1
R727
2
1
R707
2
1
R715
2
1
R719
2
1
R723
2
1
R725
2
1
R706
2
1
R716
2
1
R720
2
1
R724
2
1
2
1
21
21
21
21
21
SHEETDATE
DEPARTMENT
SIZE
PROJECT DOCUMENT NUMBER REV
REVIEWER
DESIGNER
123
7 3 2 1 6 5 4
E
A
B
C
E
D
C
B
A
7 6 5 4
D
IN
IN
IN
OUT
OUT
IN
OUT
OUT
OUT
IN
IN
IN
IN
IN
OUT
IN
OUTOUTOUT
IN
IN
IN
OUT
OUT
IN
BI
IN
IN
IN
IN IN
IN
IN
IN
OUT
OUTOUT
OUTOUT
IN
BI
IN
R674
R1464 R1466R1465
R6723
R1387
R6716
R6717
R6714
R6709
R6708
R628R627
R6813
R6812
R675
R599
R609
C



Thu Sep 14 16:12:51 2023<NAME_2><NAME_1>MB FABCGT AMDV02321 OF 365
P0V9_CPU1_RT_2DP0V9_CPU1_RT0_2AP0V9_CPU1_RT0_2A_2DP1V8_CPU1_RT0_1AP1V8_CPU1_RT0_1A_1DP1V8_CPU1_RT_1D2001%CHIP0201LF1/20WRT_CPU1_P0_VQPS
RETIMER_CPU1_P0 POWER(6)
ICPT5161LRSSMLF
1/20WCHIP5%00201LF1/20WCHIP5%00201LF
ICPT5161LRSSMLF
NCF_CPU1_P0_GNDNCF_A1_CPU1_P0_GND1K1/20WEMPTY1%0201LF
FH34
FH2
FG35
FG1
FE34
FE2
D35
D1
C34
C2
A35
A1
V35
V1
U34
U2
T4
T32
T22
T13
L35
L1
K34
K2
J4
J22
H31
H19
H16
H12
FJ19
FJ12
FF21
FF14
FD35
FD1
FC9
FC6
FC3
FC28
FC25
FC23
FC19
FB34
FB2
FA32
FA15
ET35
ET1
ER34
ER2
EP4
EP32
EP22
EP13
EJ35
EJ1
EH34
EH2
EG4
EG32
EG22
EG13
EB35
EB1
EA34
EA2
E33
E27
E14
DY4
DY32
DY22
DY13
DR35
DR1
DP34
DP2
DN4
DN32
DN22
DN13
DH35
DH1
DG34
DG2
DF4
DF32
DF22
DF13
DA35
DA1
CY34
CY2
CW4
CW32
CW22
CW13
CP35
CP1
CN34
CN2
CM4
CM32
CM22
CM13
CG35
CG1
CF34
CF2
CE4
CE32
CE22
CE13
BY35
BY1
BW34
BW2
BV4
BV32
BV22
BV13
BN35
BN1
BM34
BM2
BL4
BL32
BL22
BL13
BF35
BF1
BE34
BE2
BD4
BD32
BD22
BD13
B19
AW35
AW1
AV34
AV2
AU4
AU32
AU22
AU13
AM35
AM1
AL34
AL2
AK4
AK32
AK22
AK13
AE35
AE1
AD34
AD2
AC4
AC32
AC22
AC13
G1
CW20
CW17
BL20
BL17
T20
T17
EP20
EP17
EG20
EG17
DY20
DY17
DN20
DN17
DF20
DF17
BD20
BD17
AU20
AU17
AK20
AK17
AC20
AC17
BV17
CM20
CM17
CE20
CE17
BV20
U6014
U6014
5/11
GND151
GND150
GND149
GND148
GND147
GND146
GND145
GND144
GND143
GND142
GND141
GND140
GND139
GND138
GND137
GND136
GND135
GND134
GND133
GND132
GND131
GND130
GND129
GND128
GND127
GND126
GND125
GND124
GND123
GND122
GND121
GND120
GND119
GND118
GND117
GND116
GND115
GND114
GND113
GND112
GND111
GND110
GND109
GND108
GND107
GND106
GND105
GND104
GND103
GND102
GND101
GND100
GND99
GND98
GND97
GND96
GND95
GND94
GND93
GND92
GND91
GND90
GND89
GND88
GND87
GND86
GND85
GND84
GND83
NCF_GND12
NCF_GND11
NCF_GND10
NCF_GND9
NCF_GND8
NCF_GND7
NCF_GND6
NCF_GND5
NCF_GND4
NCF_GND3
NCF_GND2
NCF_GND1
GND82
GND81
GND80
GND79
GND78
GND77
GND76
GND75
GND74
GND73
GND72
GND71
GND70
GND69
GND68
GND67
GND66
GND65
GND64
GND63
GND62
GND61
GND60
GND59
GND58
GND57
GND56
GND55
GND54
GND53
GND52
GND51
GND50
GND49
GND48
GND47
GND46
GND45
GND44
GND43
GND42
GND41
GND40
GND39
GND38
GND37
GND36
GND35
GND34
GND33
GND32
GND31
GND30
GND29
GND28
GND27
GND26
GND25
GND24
GND23
GND22
GND21
GND20
GND19
GND18
GND17
GND16
GND15
GND14
GND13
GND12
GND11
GND10
GND9
GND8
GND7
GND6
GND5
GND4
GND3
GND2
GND1
4/11
PWR_2A_20
PWR_2A_19
PWR_2A_18
PWR_2A_17
PWR_2A_16
PWR_2A_15
PWR_2A_14
PWR_2A_13
PWR_2A_12
PWR_2A_11
PWR_2A_10
PWR_2A_9
PWR_2A_8
PWR_2A_7
PWR_2A_6
PWR_2A_5
PWR_2A_4
PWR_2A_3
PWR_2A_2
PWR_2A_1
PWR_1D
PWR_2D_4
PWR_2D_3
PWR_2D_2
PWR_2D_1
PWR_1A_5
PWR_1A_4
PWR_1A_3
PWR_1A_2
PWR_1A_1
VQPS
0.9V0.9V1.8V/ 1.8V1.2V / 1.5V
2
1
R699
2
1
2
1
2
1
SHEETDATE
DEPARTMENT
SIZE
PROJECT DOCUMENT NUMBER REV
REVIEWER
DESIGNER
123
7 3 2 1 6 5 4
E
A
B
C
E
D
C
B
A
7 6 5 4
D
R701
R709
R711
C



RETIMER EEPRO ADDRESS: 0XA0 (8 BIT) / 0X50 (7 BIT)
Thu Sep 14 16:13:00 2023<NAME_2><NAME_1>MB FABCGT AMDV02322 OF 365
P1V8_CPU1_RT_1D185186185186SMB_RT_CPU1_P0_ROM_SDASMB_RT_CPU1_P0_ROM_R_SDA1%33.2SMB_RT_CPU1_P0_ROM_SCLSMB_RT_CPU1_P0_ROM_R_SCL0201LF1/20W CHIPM24M02-DRMN6TPU12_E20.1UFIC10VSMLFCHIP0201LFC020110%
RETIMER_CPU1_P0(7)
1K1%X7S1/20W
7
4
8
5
6 3
2
1
U12
DU1
DU2
E2
VSSSDA
SCL
WC_N
VCC
2
1
2
1C7501
21 21
SHEETDATE
DEPARTMENT
SIZE
PROJECT DOCUMENT NUMBER REV
REVIEWER
DESIGNER
123
7 3 2 1 6 5 4
E
A
B
C
E
D
C
B
A
7 6 5 4
D
BIIN R6788R673R672
C



Thu Sep 14 16:13:01 2023<NAME_2><NAME_1>MB FABCGT AMDV02323 OF 365P0V9_CPU1_RT0_2A_2D
P0V9_CPU1_RT_2DP1V8_CPU1_RT0_1A_1DP1V8_CPU1_RT_1DP1V8_CPU1_RT0_1AP0V9_CPU1_RT0_2A20%100UFX6S4VC0805X6S20%100UF4VC0805 C0805X6S20%4V100UFC0805X6S20%4V100UF100UF4V20%C0805X6S20%100UF4VC0805X6S4VX6SC0805100UF20%470UF20%SMLF2.5VSPCAP2.5VSMLFSPCAP20%470UF4V100UFC0805X6S20%10%10V4.7UF20%0.1UFX6S4.7UF4.7UF10UF6.3VC04021UFX6S02010.1UF10%10V0.1UF10V0.1UF10%10%10V4V20%X6S020120%X6S020110%X7SC020110V10V10%020102010.1UFX7SC0201X7SX7SC0201C0201X7S0.1UF10%4V1UFX6S20%020120%X6S0201X6S10V 10V 10V 10V0.1UFX6S20% 20%4V20%4.7UF1UFC02010201X6SX6S0201X6S20%6.3V20%20%6.3VX6S20%C04026.3VC0402C0402X6S20%C04024V10UF22UF22UF4VX7SC02011UFX7SC0201020110%0402X6S20%6.3V4.7UF20%4V1UF10UF0.1UF10%X7S10V20%4VC0402C02010402X6S20%6.3V10UF0.1UF020110V0.1UF10% 10%X7S4V4.7UF
RETIMER_CPU1_P0 DECAPS (8)
X6S22UFC04021UF1UFX6S4VSMLF100NH/16AIND20%X6S6.3VC04024VX6SCHIP05%1/4W5%1/4W0R6704 AND R6705 COLAYX6S1UF20%4VEMPTY05%0402LF05%EMPTY0.1UF10VC020110VX7SC020110%C0201
10%X7SX7SC0201X7S
10%10VX7SC020110%C02010603LFC04024VIND1/16W1/16WSMLF1/16WBLM21SN300SN1D/5A5%EMPTY0402LFL27/R6701 COLAY WITH R6702/R670320%X6SX6S20%SMLFBLM15PD121SN1D/1300MA0INDX6S0402C0402X6S22UF6.3VX6SX6S20%10UF20%4.7UF6.3V22UF1UF20%020110%10V0.1UF0.1UF10V4V20%10%X7SC0201X7SX6S20%0201X6S0.1UFX7SC0402X6S6.3VC020110V0.1UFX6S1UF040210%4V20%22UF20%6.3V6.3VX6S10UF20%X6SC040220%10UFX6S4VX6S20%20%040204024V1UF020120%4V4V1UF20%6.3VX6S040220%10V0.1UFX6S6.3VC0402020102010.1UF10%C02010.1UFX6SC020110V1UF4V1UF1UF0.1UF 0.1UFX7S10%4V1UF0402LFEMPTY0603LFC020120%C0201X7S10%20%4V4V1UF0.1UF10VX7S22UF4V20%X6SC04024V0201C0201X7S
C115
C7022
C125
C122C118C113
C121C117C114
2121
2 1
L4L3
1 21 2
L2712
2
1
2
1C7021
2
1C7020
2
1
2
1
2
1
2
1
2
1
2
1
21
2
1
2
1
2
1
2
1
2
1
2
1
2
1
2
1
2
1
2
1
2
1
2
1
2
1
2
1
2
1
2
1
2
1
2
1
2
1
2
1
2
1
2
1
2
1
2
1
2
1
2
1
2
1
2
1
2
1
2
1
2
1
2
1
2
1
2
1
2
1
2
1
2
1
2
1
2
1
2
1
2
1
2
1
2
1
2
1
2
1
2
1
21R6703
21
2
1
2
1
2
1
2
1
2
1
2
1
2
1
2
1
2
1
2
1
2
1
2
1
2
1
2
1
2
1
2
1
CAD NOTE:
CAD NOTE:
R6701
R6702
C119 C123 C126
SHEETDATE
DEPARTMENT
SIZE
PROJECT DOCUMENT NUMBER REV
REVIEWER
DESIGNER
123
7 3 2 1 6 5 4
E
A
B
C
E
D
C
B
A
7 6 5 4
D
C283C281
C201C187
R6704
R6705
C191 C198
C228 C253 C184 C260 C192C141 C264 C282
C137 C139 C266 C189
C247
C241C269C250
C286C254C259C262C255
C285C190C280C186C227
C265C188
C284C240C225
C258C221
C257C138C243C135
C220
C222
C185C256C261C244C229
C130
C134C133C131C129
C



Thu Aug 24 10:16:45 2023<NAME_2><NAME_1>MB FABCGT AMDV02324 OF 365RETIMER_CPU1_P0 (9)
SHEETDATE
DEPARTMENT
SIZE
PROJECT DOCUMENT NUMBER REV
REVIEWER
DESIGNER
123
7 3 2 1 6 5 4
E
A
B
C
E
D
C
B
A
7 6 5 4
D
C



Thu Aug 24 10:16:45 2023<NAME_2><NAME_1>MB FABCGT AMDV02325 OF 365RETIMER_CPU1_P0(10)
SHEETDATE
DEPARTMENT
SIZE
PROJECT DOCUMENT NUMBER REV
REVIEWER
DESIGNER
123
7 3 2 1 6 5 4
E
A
B
C
E
D
C
B
A
7 6 5 4
D
C



Thu Aug 24 10:16:46 2023<NAME_2><NAME_1>MB FABCGT AMDV02326 OF 365BLANK
SHEETDATE
DEPARTMENT
SIZE
PROJECT DOCUMENT NUMBER REV
REVIEWER
DESIGNER
123
7 3 2 1 6 5 4
E
A
B
C
E
D
C
B
A
7 6 5 4
D
C



P/N SWAPP/N SWAPP/N SWAPP/N SWAPP/N SWAPP/N SWAPP/N SWAPP/N SWAPP/N SWAPP/N SWAPP/N SWAPP/N SWAPP/N SWAPP/N SWAP
P5E_CPU1_P1_TX_C_DP/DN<0-15> LANE REVERSAL
CPU TO RETIMERCPU TO RETIMERThu Sep 14 16:12:50 2023<NAME_2><NAME_1>MB FABCGT AMDV02327 OF 365
66666666P5E_CPU1_P1_TX_C_DP<15:8>P5E_CPU1_P1_TX_C_DN<15:8>P5E_CPU1_P1_TX_C_DP<7:0>P5E_CPU1_P1_TX_C_DN<7:0>
RETIMER_CPU1_P1(1)
ICPT5161LRSSMLFPT5161LRSSMLFIC
EV34
EL34
ED34
DU34
DK34
DC34
CT34
CJ34
EY35
EN35
EF35
DW35
DM35
DE35
CV35
CL35
CB34
BR34
BH34
BA34
AP34
AG34
Y34
N34
CD35
BU35
BK35
BC35
AT35
AJ35
AB35
R35
14
14
13
13
12
12
2
3
3
4
5
6
7
11
10
9
2
0
6
5
4
0
7
11
8
9
8
10
15
15
1
1
U6015
U6015
9/11
B_PERN15
B_PERP15
B_PERN14
B_PERP14
B_PERN13
B_PERP13
B_PERN12
B_PERP12
B_PERN11
B_PERP11
B_PERN10
B_PERP10
B_PERN9
B_PERP9
B_PERN8
B_PERP8
8/11
B_PERN7
B_PERP7
B_PERN6
B_PERP6
B_PERN5
B_PERP5
B_PERN4
B_PERP4
B_PERN3
B_PERP3
B_PERN2
B_PERP2
B_PERN1
B_PERP1
B_PERN0
B_PERP0
RX : B_PER[15:8]
RX : B_PER[7:0]
SHEETDATE
DEPARTMENT
SIZE
PROJECT DOCUMENT NUMBER REV
REVIEWER
DESIGNER
123
7 3 2 1 6 5 4
E
A
B
C
E
D
C
B
A
7 6 5 4
D
IN
IN
IN
IN
C



P5E_CPU1_P1_RX_DP/DN<0-15> LANE REVERSAL
RETIMER TO CPU RETIMER TO CPUThu Sep 14 16:12:50 2023<NAME_2><NAME_1>MB FABCGT AMDV02328 OF 365
51515151SMLFICPT5161LRSSMLFICPT5161LRS
RETIMER_CPU1_P1(2)
P5E_CPU1_P1_RX_DP<15:8>P5E_CPU1_P1_RX_DN<15:8>P5E_CPU1_P1_RX_DP<7:0>P5E_CPU1_P1_RX_DN<7:0>
EU26
EK26
EC26
DT26
DJ26
DB26
CR26
CH26
EW29
EM29
EE29
DV29
DL29
DD29
CU29
CK29
CA26
BP26
BG26
AY26
AN26
AF26
W26
M26
CC29
BT29
BJ29
BB29
AR29
AH29
AA29
P29
12
12
13
13
15
5
11
9
8
8
9
11
15
0
3
2
1
0
1
2
3
4
6
7
5
6
7
10
4
10
14
14
U6015
U6015
7/11
A_PETN15
A_PETP15
A_PETN14
A_PETP14
A_PETN13
A_PETP13
A_PETN12
A_PETP12
A_PETN11
A_PETP11
A_PETN10
A_PETP10
A_PETN9
A_PETP9
A_PETN8
A_PETP8
6/11
A_PETN7
A_PETP7
A_PETN6
A_PETP6
A_PETN5
A_PETP5
A_PETN4
A_PETP4
A_PETN3
A_PETP3
A_PETN2
A_PETP2
A_PETN1
A_PETP1
A_PETN0
A_PETP0
TX : A_PET[15:8]
TX : A_PET[7:0]
SHEETDATE
DEPARTMENT
SIZE
PROJECT DOCUMENT NUMBER REV
REVIEWER
DESIGNER
123
7 3 2 1 6 5 4
E
A
B
C
E
D
C
B
A
7 6 5 4
D
OUT
OUT
OUT
OUT
C



P5E_CPU1_P1_RX_BUF_DP/DN<0-15> LANE REVERSAL
EXAMAX TO RETIMEREXAMAX TO RETIMERThu Sep 14 16:12:50 2023<NAME_2><NAME_1>MB FABCGT AMDV02329 OF 365
122122121121P5E_CPU1_P1_RX_BUF_DN<7:0>P5E_CPU1_P1_RX_BUF_DP<7:0>P5E_CPU1_P1_RX_BUF_DN<15:8>P5E_CPU1_P1_RX_BUF_DP<15:8>PT5161LRSICSMLFSMLFICPT5161LRS
RETIMER_CPU1_P1(3)
EY1
EN1
EF1
DW1
DM1
DE1
CV1
CL1
EV2
EL2
ED2
DU2
DK2
DC2
CT2
CJ2
CD1
BU1
BK1
BC1
AT1
AJ1
AB1
R1
CB2
BR2
BH2
BA2
AP2
AG2
Y2
N2 7
6
5
2
1
0
0
1
2
3
4
6
15
15
14
8
14
13
12
11
10
9
8
13
12
11
10
9
7
5
4
3
U6015U6015
2/11
A_PERN15
A_PERP15
A_PERN14
A_PERP14
A_PERN13
A_PERP13
A_PERN12
A_PERP12
A_PERN11
A_PERP11
A_PERN10
A_PERP10
A_PERN9
A_PERP9
A_PERN8
A_PERP8
1/11
A_PERN7
A_PERP7
A_PERN6
A_PERP6
A_PERN5
A_PERP5
A_PERN4
A_PERP4
A_PERN3
A_PERP3
A_PERN2
A_PERP2
A_PERN1
A_PERP1
A_PERN0
A_PERP0
RX : A_PER[15:8]
RX : A_PER[7:0]
SHEETDATE
DEPARTMENT
SIZE
PROJECT DOCUMENT NUMBER REV
REVIEWER
DESIGNER
123
7 3 2 1 6 5 4
E
A
B
C
E
D
C
B
A
7 6 5 4
D
IN
ININ
IN
C



RETIMER TO EXAMAX
P5E_CPU1_P1_TX_BUF_DP/DN<0-15> LANE REVERSAL
RETIMER TO EXAMAXThu Sep 14 16:12:50 2023<NAME_2><NAME_1>MB FABCGT AMDV02330 OF 365
331331331331
121121331331 122122331331
SMLFP5E_CPU1_P1_TX_BUF_DP<15:8>PT5161LRSIC IC
RETIMER_CPU1_P1(4)
P5E_CPU1_P1_TX_BUF_DN<15:8>P5E_CPU1_P1_TX_BUF_DP<7:0>PT5161LRSSMLFP5E_CPU1_P1_TX_BUF_DN<7:0>
DIFF BUS_0.22UF6.3VX6S20%C0201DIFF BUS_0.22UFDIFF BUS_0.22UFDIFF BUS_0.22UFDIFF BUS_0.22UFDIFF BUS_0.22UFDIFF BUS_0.22UFDIFF BUS_0.22UFDIFF BUS_0.22UFDIFF BUS_0.22UFDIFF BUS_0.22UFDIFF BUS_0.22UFDIFF BUS_0.22UFDIFF BUS_0.22UFDIFF BUS_0.22UFDIFF BUS_0.22UFP5E_CPU1_P1_TX_BUF_C_DN<15:8>P5E_CPU1_P1_TX_BUF_C_DP<15:8>P5E_CPU1_P1_TX_BUF_DN<15:8>P5E_CPU1_P1_TX_BUF_DP<15:8>DIFF BUS_0.22UF6.3VX6S20%C0201DIFF BUS_0.22UFDIFF BUS_0.22UFDIFF BUS_0.22UFDIFF BUS_0.22UFDIFF BUS_0.22UFDIFF BUS_0.22UFDIFF BUS_0.22UFDIFF BUS_0.22UFDIFF BUS_0.22UFDIFF BUS_0.22UFDIFF BUS_0.22UFDIFF BUS_0.22UFDIFF BUS_0.22UFDIFF BUS_0.22UFP5E_CPU1_P1_TX_BUF_C_DN<7:0>P5E_CPU1_P1_TX_BUF_C_DP<7:0>P5E_CPU1_P1_TX_BUF_DP<7:0>P5E_CPU1_P1_TX_BUF_DN<7:0>DIFF BUS_0.22UF
2 1
2 1
2 1
2 1
2 1
2 1
2 1
2 1
2 1
2 1
2 1
2 1
2 1
2 1
2 1
2 1
2 1
2 1
2 1
2 1
2 1
2 1
2 1
2 1
2 1
2 1
2 1
2 1
2 1
2 1
2 1
2 1
EU7
EK7
EC7
DT7
DJ7
DB7
CR7
CH7
EW10
EM10
EE10
DV10
DL10
DD10
CU10
CK10
CA7
BP7
BG7
AY7
AN7
AF7
W7
M7
CC10
BT10
BJ10
BB10
AR10
AH10
AA10
P10
15
14
13
12
11
10
9
8
8
9
10
11
12
14
15
7
6
5
4
3
2
1
0
0
1
2
3
4
5
6
7
13
8
8
9
10
11
12
13
9
10
11
12
13
14
15
14
15
8
8
9
10
11
12
13
14
15
9
10
12
11
13
14
15
0
1
0
1
2
3
4
5
6
7
3
2
6
5
4
7
0
1
0
2
1
3
5
4
6
2
3
4
5
6
7
7
U6015
C6677
C6678
C6680
C6679
C6682
C6681
C6683
C6684
C6685
C6686
C6687
C6688
C6689
C6690
C6691
C6692
C6661
U6015
C6662
C6664
C6663
C6665
C6666
C6668
C6667
C6669
C6670
C6671
C6672
C6673
C6674
C6675
C6676
10/11
B_PETN7
B_PETP7
B_PETN6
B_PETP6
B_PETN5
B_PETP5
B_PETN4
B_PETP4
B_PETN3
B_PETP3
B_PETN2
B_PETP2
B_PETN1
B_PETP1
B_PETN0
B_PETP0
11/11
B_PETN15
B_PETP15
B_PETN14
B_PETP14
B_PETN13
B_PETP13
B_PETN12
B_PETP12
B_PETN11
B_PETP11
B_PETN10
B_PETP10
B_PETN9
B_PETP9
B_PETN8
B_PETP8
TX : B_PET[7:0]
TX : B_PET[15:8]
2 12 1
2 12 1
2 12 1
2 12 1
2 12 1
2 12 1
2 12 1
2 12 1
2 12 1
2 12 1
2 12 1
2 12 1
2 12 1
2 12 1
2 12 1
2 12 1
SHEETDATE
DEPARTMENT
SIZE
PROJECT DOCUMENT NUMBER REV
REVIEWER
DESIGNER
123
7 3 2 1 6 5 4
E
A
B
C
E
D
C
B
A
7 6 5 4
D
OUT
OUT
OUTININ OUT IN
OUT
OUT
OUTOUT IN
C



CPU1 P1 RT ADDR: 0X48 (8-BIT) / 0X24 (7-BIT)
Thu Sep 14 16:13:04 2023<NAME_2><NAME_1>MB FABCGT AMDV02331 OF 365P1V8_CPU1_RT_1DP1V8_CPU1_RT_1DP1V8_CPU1_RT_1DP1V8_CPU1_RT_1DP1V8_CPU1_RT_1DP1V8_CPU1_RT_1DP1V8_CPU1_RT_1DSMB_RT_CPU1_P1_ROM_MUX_1D_R_SCLSMB_RT_CPU1_P1_ROM_MUX_1D_SCL1%49.9CHIP0201LF1/20WSMB_RT_CPU1_P1_ROM_MUX_1D_R_SDASMB_RT_CPU1_P1_ROM_MUX_1D_SDA18518618518633233233233233218433233233281332332332332332332 332332332332
3323323323323323323323323321843328133281332332332332332332183183 813321/20WCHIP2001%0201LFJTAG_TDI_RT_CPU1_P1JTAG_TMS_RT_CPU1_P1JTAG_TDO_RT_CPU1_P1JTAG_TCK_RT_CPU1_P10201LF1/20W 1/20W1%4.7KTEST0_RT_CPU1_P1SMB_RT_CPU1_P1_R_SDA5%4.7KEMPTY5%4.7KEMPTY0201LF5%1/20WEMPTY0201LF1K1/20WEMPTY0201LF0JTAG_TEST_MODE_RT_CPU1_P1JTAG_TRST_RT_CPU1_P1_NJTAG_TDI_RT_CPU1_P11/20W5%4.7K0201LFCHIPRST_RT_CPU1_P1_RESET_N0201LF0201LFCHIPJTAG_TMS_RT_CPU1_P1CHIPRST_RT_CPU1_P1_PERST_R_N0201LFJTAG_TDO_RT_CPU1_P1MODE_RT_CPU1_P1RXDET_BYP_RT_CPU1_P11KJTAG_TCK_RT_CPU1_P11KRT_CPU1_P1_SCAN_MODE5% EMPTY1/20W1%0201LFCHIP1%10K1/20W0201LFRXDET_BYP_RT_CPU1_P1RT_CPU1_P1_SCAN_MODEGPIO3_RT_CPU1_P1RT_CPU1_P1_ADDR2
1/20WEMPTY0201LFRT_CPU1_P1_ADDR1RT_CPU1_P1_ADDR2RT_CPU1_P1_ADDR30201LFEMPTY1/20W1K1%1%1KCHIP0201LF1/20WCHIP0201LF20K1% 1%1K0201LF1/20W1K1%1/20W1K1%0201LF1/20W4.7K5%EMPTY1%10K1/20WCHIP0201LF10K0201LF1/20WCHIP1%4.7K5%1/20WCHIP0201LFEMPTY5%4.7K0201LFEMPTY0201LF5%4.7K1/20W4.7K5%EMPTY0201LF1/20W1/20W5%4.7K0201LFEMPTY1/20WCHIP0201LF4.7K5%0201LF5%4.7K1/20WCHIP5%1/20W4.7K0201LFCHIP1/20W5%CHIP05%0201LFEMPTY1/20W4.7K5%4.7K1/20W0201LFEMPTY4.7K5%1/20W0201LFCHIP10K1%1/20WCHIP0201LF10K1%1/20WCHIP0201LF0201LFEMPTY1/20W4.7KMODE_RT_CPU1_P1JTAG_TEST_MODE_RT_CPU1_P1GPIO3_RT_CPU1_P1TEST0_RT_CPU1_P1TEST1_RT_CPU1_P1TEST2_RT_CPU1_P1SMB_RT_CPU1_P1_R_SCLGPIO2_RT_CPU1_P1
51.11% 1%51.11/20W0201LF
IC
RETIMER_CPU1_P1(5)1/20WEMPTY EMPTY0201LF
PT5161LRSCHIP5%01/20WSMLFRST_RT_CPU1_P1_RESET_R_NRST_RT_CPU1_P1_PERST_R_N1/20WEMPTY
SMB_RT_CPU1_P1_R2_SDASMB_RT_CPU1_P1_R2_SCLCHIP0201LFGPIO2_RT_CPU1_P11/20W0201LF
TEST1_RT_CPU1_P1TEST2_RT_CPU1_P1RT_CPU1_P1_ADDR1RT_CPU1_P1_ADDR3CLK_100M_RETIMER_CPU1_P1_R_DPCLK_100M_RETIMER_CPU1_P1_R_DNCHIP0201LF0201LFCLK_100M_RETIMER_CPU1_P1_DNCLK_100M_RETIMER_CPU1_P1_DPRST_RT_CPU1_P1_PERST_NCLKREQ_RT_CPU1_P1_NRST_RT_CPU1_P1_RESET_R_N4.7K00201LF
R749R752
FF30
FF27
FF24
E30
B28
B31
B25
B23
F34
FF33
E11
FF11
FJ16
FF18
B16
E18
F2
FJ9
E8
B12
FF8
B9
B6
B3
FJ31
FJ28
FJ25
FJ23
FJ6
FJ3
FF5
G35
U6015
CLOCK
3/11
EE_DAT
EE_CLK
CLKREQ_N
TEST2
TEST1
TEST0
T_SENSE
SMBDAT
SMBCLK
SMB_ADDR3
SMB_ADDR2
SMB_ADDR1
SCAN_MODE
RXDET_BYP
RESET_N
REFCLKP
REFCLKN
REFCLK_OUTP
REFCLK_OUTN
PERST_N
MODE
JTAG_TRST_N
JTAG_TMS
JTAG_TEST_MODE
JTAG_TDO
JTAG_TDI
JTAG_TCK
INT_N
GPIO3
GPIO2
GPIO1
GPIO0
MISCJTAGTEST EEPROMSMBUSGPIO
2
1
2
1
R1461
2
1
R1373
2
1
2
1
2
1
2
1
R1378
2
1
R1377
21R1372
21
2
1
2
1
2
1
2
1
R735
2
1
R746
2
1
R741
2
1
R758
2
1
2
1
21
21
2
1
R793
2
1
R794
2
1
R759
2
1
R788
2
1
R786
2
1
R792
2
1
R791
2
1
R787
21
21
21
21
21
21
2
1
2
1
2
1
R784
2
1
R781
2
1
R785
2
1
R783
2
1
R782
2
1
R755
SHEETDATE
DEPARTMENT
SIZE
PROJECT DOCUMENT NUMBER REV
REVIEWER
DESIGNER
123
7 3 2 1 6 5 4
E
A
B
C
E
D
C
B
A
7 6 5 4
D
IN
IN
IN
IN
IN
IN
IN
OUT
OUT
OUTOUTOUTOUT
OUT
IN
IN
IN
IN
IN
IN
IN
OUT
IN
BI
IN
OUT
BI
IN
IN
IN
IN
IN
IN
OUTOUT
OUTOUT
IN
IN
OUT
OUT
OUT
R1456R1455R1454
R756
R1376
R795
R796
R745
R732
R731
R779
R780
R670
R671
R598
R597
R626R625
C



Thu Sep 14 16:13:04 2023<NAME_2><NAME_1>MB FABCGT AMDV02332 OF 365
P0V9_CPU1_RT1_2A_2DP1V8_CPU1_RT_1DP1V8_CPU1_RT1_1AP1V8_CPU1_RT1_1A_1DP0V9_CPU1_RT1_2AP0V9_CPU1_RT_2D0201LFCHIP1%1/20W2001/20WEMPTY0201LF1%1KRT_CPU1_P1_VQPS
RETIMER_CPU1_P1 POWER(6)NCF_CPU1_P1_GNDNCF_A1_CPU1_P1_GNDICPT5161LRSSMLF
1/20WCHIP5%00201LF1/20WCHIP5%00201LF
ICPT5161LRSSMLF
FH34
FH2
FG35
FG1
FE34
FE2
D35
D1
C34
C2
A35
A1
V35
V1
U34
U2
T4
T32
T22
T13
L35
L1
K34
K2
J4
J22
H31
H19
H16
H12
FJ19
FJ12
FF21
FF14
FD35
FD1
FC9
FC6
FC3
FC28
FC25
FC23
FC19
FB34
FB2
FA32
FA15
ET35
ET1
ER34
ER2
EP4
EP32
EP22
EP13
EJ35
EJ1
EH34
EH2
EG4
EG32
EG22
EG13
EB35
EB1
EA34
EA2
E33
E27
E14
DY4
DY32
DY22
DY13
DR35
DR1
DP34
DP2
DN4
DN32
DN22
DN13
DH35
DH1
DG34
DG2
DF4
DF32
DF22
DF13
DA35
DA1
CY34
CY2
CW4
CW32
CW22
CW13
CP35
CP1
CN34
CN2
CM4
CM32
CM22
CM13
CG35
CG1
CF34
CF2
CE4
CE32
CE22
CE13
BY35
BY1
BW34
BW2
BV4
BV32
BV22
BV13
BN35
BN1
BM34
BM2
BL4
BL32
BL22
BL13
BF35
BF1
BE34
BE2
BD4
BD32
BD22
BD13
B19
AW35
AW1
AV34
AV2
AU4
AU32
AU22
AU13
AM35
AM1
AL34
AL2
AK4
AK32
AK22
AK13
AE35
AE1
AD34
AD2
AC4
AC32
AC22
AC13
G1
CW20
CW17
BL20
BL17
T20
T17
EP20
EP17
EG20
EG17
DY20
DY17
DN20
DN17
DF20
DF17
BD20
BD17
AU20
AU17
AK20
AK17
AC20
AC17
BV17
CM20
CM17
CE20
CE17
BV20
U6015
U6015
4/11
PWR_2A_20
PWR_2A_19
PWR_2A_18
PWR_2A_17
PWR_2A_16
PWR_2A_15
PWR_2A_14
PWR_2A_13
PWR_2A_12
PWR_2A_11
PWR_2A_10
PWR_2A_9
PWR_2A_8
PWR_2A_7
PWR_2A_6
PWR_2A_5
PWR_2A_4
PWR_2A_3
PWR_2A_2
PWR_2A_1
PWR_1D
PWR_2D_4
PWR_2D_3
PWR_2D_2
PWR_2D_1
PWR_1A_5
PWR_1A_4
PWR_1A_3
PWR_1A_2
PWR_1A_1
VQPS
5/11
GND151
GND150
GND149
GND148
GND147
GND146
GND145
GND144
GND143
GND142
GND141
GND140
GND139
GND138
GND137
GND136
GND135
GND134
GND133
GND132
GND131
GND130
GND129
GND128
GND127
GND126
GND125
GND124
GND123
GND122
GND121
GND120
GND119
GND118
GND117
GND116
GND115
GND114
GND113
GND112
GND111
GND110
GND109
GND108
GND107
GND106
GND105
GND104
GND103
GND102
GND101
GND100
GND99
GND98
GND97
GND96
GND95
GND94
GND93
GND92
GND91
GND90
GND89
GND88
GND87
GND86
GND85
GND84
GND83
NCF_GND12
NCF_GND11
NCF_GND10
NCF_GND9
NCF_GND8
NCF_GND7
NCF_GND6
NCF_GND5
NCF_GND4
NCF_GND3
NCF_GND2
NCF_GND1
GND82
GND81
GND80
GND79
GND78
GND77
GND76
GND75
GND74
GND73
GND72
GND71
GND70
GND69
GND68
GND67
GND66
GND65
GND64
GND63
GND62
GND61
GND60
GND59
GND58
GND57
GND56
GND55
GND54
GND53
GND52
GND51
GND50
GND49
GND48
GND47
GND46
GND45
GND44
GND43
GND42
GND41
GND40
GND39
GND38
GND37
GND36
GND35
GND34
GND33
GND32
GND31
GND30
GND29
GND28
GND27
GND26
GND25
GND24
GND23
GND22
GND21
GND20
GND19
GND18
GND17
GND16
GND15
GND14
GND13
GND12
GND11
GND10
GND9
GND8
GND7
GND6
GND5
GND4
GND3
GND2
GND1
0.9V0.9V1.8V/ 1.8V1.2V / 1.5V
2
1
R6730
2
1
2
1
2
1
SHEETDATE
DEPARTMENT
SIZE
PROJECT DOCUMENT NUMBER REV
REVIEWER
DESIGNER
123
7 3 2 1 6 5 4
E
A
B
C
E
D
C
B
A
7 6 5 4
D
R6731
R6732
R6733
C



RETIMER EEPRO ADDRESS: 0XA0 (8 BIT) / 0X50 (7 BIT)
Thu Sep 14 16:13:00 2023<NAME_2><NAME_1>MB FABCGT AMDV02333 OF 365
P1V8_CPU1_RT_1D185186185186SMB_RT_CPU1_P1_ROM_SDASMB_RT_CPU1_P1_ROM_R_SDA1%33.2SMB_RT_CPU1_P1_ROM_SCLSMB_RT_CPU1_P1_ROM_R_SCL0201LFCHIP1/20WM24M02-DRMN6TPU19_E20.1UFICX7S10%C020110VCHIP0201LF1K1%1/20WSMLF
RETIMER_CPU1_P1(7)
7
4
8
5
6 3
2
1
U19
DU1
DU2
E2
VSSSDA
SCL
WC_N
VCC
2
1C7502
2
1
21 21
SHEETDATE
DEPARTMENT
SIZE
PROJECT DOCUMENT NUMBER REV
REVIEWER
DESIGNER
123
7 3 2 1 6 5 4
E
A
B
C
E
D
C
B
A
7 6 5 4
D
INBI R6789R689R690
C



Thu Sep 14 16:13:04 2023<NAME_2><NAME_1>MB FABCGT AMDV02334 OF 365
EMPTYP1V8_CPU1_RT_1DP1V8_CPU1_RT1_1A_1DP1V8_CPU1_RT1_1AP0V9_CPU1_RT_2D
P0V9_CPU1_RT1_2A_2D
P0V9_CPU1_RT1_2AC08054VX6S100UF20%100UFX6S4V20%C0805100UFC08054VX6S20%20%4V100UFC0805X6S100UFX6SC080520%4V100UFX6S20%4VC0805100UFC080520%X6S4V X7S X7S X7S2.5V 2.5V4V100UF10% 10%10V 10V20%470UF470UF0.1UF0.1UF0.1UF0.1UF10VSMLF0.1UF20%4VC020110%10V02016.3VC02016.3V20%C04021/16WBLM15PD121SN1D/1300MA0.1UF10VC0201C020110%20%6.3VBLM21SN300SN1D/5A10V10%X7SC040220%040220%4V4.7UFX6S02011UF 1UF10%10%10V4V1UFX6S X6SX6S4V4.7UF20%1UF10UF20%C0402C0402X6S20%6.3V10UF6.3V20%X6SX6S20%4V4VC040220%22UF4V4VC0402X6SX6S10%X6S100NH/16A0.1UF0.1UF10%X7SX6S20%10UF4V20%6.3V22UF10UFC0402 0201X6S1UF20%X6SX6S10%20%C0402X6S20%4V4VC04020.1UF10VX6SX6S10V04026.3V0.1UF0201X6S20%4.7UF10UF20%20%0402
INDSMLFL31/R704 COLAY WITH R653/R6640402LF5%EMPTY0INDSMLFC040220%6.3VX6S22UF0201X6SRETIMER_CPU1_P1 DECAPS(8)
05%00402LF5%1/16W1UF20%4V5%01/4WCHIP05%22UFX6S20%SMLFIND10UF6.3VX6S10UFX6S X6SX6S4.7UF4V6.3V4.7UFX6S4V1UFC04020402LF1/16W EMPTYR705 AND R712 COLAY0603LFEMPTY1/4W10%0.1UF10VX7SC0201X7SC020110V10%X7S10%10V0.1UF10VX7S0.1UF10%10VX7SC0201X7S X7SC0201
10%0.1UF10VX7S10%10VX7SC020110%10VX7SC020110%X7SC02016.3VX6S04021UF20%4.7UF4VC0201X7S4V0402C04024V20%C0201C0201 C0201 C0201
0.1UF10V20%02010.1UFX6S6.3VC0402 C040222UFX6S6.3V20%22UF22UF20% 20%X6SX6S6.3V0402X7S X7S0.1UF20%02010201X6S4.7UF02014V0201 020110V10V0.1UF0603LF20% 20% 20%4V4V4V1UF 1UF 1UF 1UF0.1UF0.1UF1UF20%X6S10V10%X7S4V20%X6S0201020102011UFC02011UF020120%X6S040220%X7SC020110%C02014V1UF20%X6S0201 0201X6S20%4V1UFX6SC020120%X6SC0805SPCAPSPCAPSMLF20%C020110%0.1UF
C110
C7025
C200C127
C195
C102
C111C103
C203
2121
2 1
L6L5
1 21 2
L3112
2
1
2
1C7024
2
1C7023
2
1
2
1
2
1
2
1
2
1
2
1
2
1
2
1
2
1
2
1
2
1
2
1
2
1
2
1
2
1
2
1
2
1
2
1
2
1
2
1
2
1
2
1
2
1
2
1
2
1
2
1
2
1
2
1
2
1
2
1
2
1
2
1
2
1
2
1
2
1
2
1
2
1
2
1
2
1
2
1
2
1
2
1
2
1
2
1
2
1
2
1
2
1
2
1
2
1
2
1
2
1
2
1
2
1
2
1
2
1
2
1
2
1
2
1
2
1
2
1
2
1
2
1
2
1
2
1
2
1
21
2
1
2
1
2
1
21
21R664
CAD NOTE:
CAD NOTE:
R704
C204C202C199
R653
SHEETDATE
DEPARTMENT
SIZE
PROJECT DOCUMENT NUMBER REV
REVIEWER
DESIGNER
123
7 3 2 1 6 5 4
E
A
B
C
E
D
C
B
A
7 6 5 4
D
C350C341
C315C306
C333 C290 C292 C311C300
C354C339
C342C338
C318C351C335C329
C327C323
C328C324C320C317
C353C289
C334C322
C301C293
C346
C336C343
C337C314
C319C291C349C312
C330
C331C325C321
C326C307
C332
C294
C344C340
C316C313
C288C287C217C205
R712
R705
C206
C



Thu Aug 24 10:16:54 2023<NAME_2><NAME_1>MB FABCGT AMDV02335 OF 365RETIMER_CPU1_P1(9)
SHEETDATE
DEPARTMENT
SIZE
PROJECT DOCUMENT NUMBER REV
REVIEWER
DESIGNER
123
7 3 2 1 6 5 4
E
A
B
C
E
D
C
B
A
7 6 5 4
D
C



Thu Aug 24 10:16:55 2023<NAME_2><NAME_1>MB FABCGT AMDV02336 OF 365RETIMER_CPU1_P1(10)
SHEETDATE
DEPARTMENT
SIZE
PROJECT DOCUMENT NUMBER REV
REVIEWER
DESIGNER
123
7 3 2 1 6 5 4
E
A
B
C
E
D
C
B
A
7 6 5 4
D
C



Thu Aug 24 10:16:56 2023<NAME_2><NAME_1>MB FABCGT AMDV02337 OF 365BLANK
SHEETDATE
DEPARTMENT
SIZE
PROJECT DOCUMENT NUMBER REV
REVIEWER
DESIGNER
123
7 3 2 1 6 5 4
E
A
B
C
E
D
C
B
A
7 6 5 4
D
C



CPU TO RETIMER CPU TO RETIMER
P5E_CPU1_P2_TX_C_DP/DN<0-15> LANE REVERSALP/N SWAPP/N SWAPP/N SWAPP/N SWAPP/N SWAPP/N SWAPP/N SWAPP/N SWAPP/N SWAPP/N SWAPP/N SWAPP/N SWAPP/N SWAPP/N SWAPP/N SWAP
Thu Sep 14 16:12:55 2023<NAME_2><NAME_1>MB FABCGT AMDV02338 OF 365
66666666P5E_CPU1_P2_TX_C_DP<15:8>P5E_CPU1_P2_TX_C_DN<15:8>
RETIMER_CPU1_P2(1)
SMLFPT5161LRSICICSMLFPT5161LRSP5E_CPU1_P2_TX_C_DP<7:0>P5E_CPU1_P2_TX_C_DN<7:0>
EV34
EL34
ED34
DU34
DK34
DC34
CT34
CJ34
EY35
EN35
EF35
DW35
DM35
DE35
CV35
CL35
CB34
BR34
BH34
BA34
AP34
AG34
Y34
N34
CD35
BU35
BK35
BC35
AT35
AJ35
AB35
R35
1
15
9
10
12
13
14
11
8
9
10
11
12
13
14
15
8
7
0
2
3
4
5
6
0
2
3
4
6
7
5
1
U6016
U6016
9/11
B_PERN15
B_PERP15
B_PERN14
B_PERP14
B_PERN13
B_PERP13
B_PERN12
B_PERP12
B_PERN11
B_PERP11
B_PERN10
B_PERP10
B_PERN9
B_PERP9
B_PERN8
B_PERP8
8/11
B_PERN7
B_PERP7
B_PERN6
B_PERP6
B_PERN5
B_PERP5
B_PERN4
B_PERP4
B_PERN3
B_PERP3
B_PERN2
B_PERP2
B_PERN1
B_PERP1
B_PERN0
B_PERP0
RX : B_PER[15:8]
RX : B_PER[7:0]
SHEETDATE
DEPARTMENT
SIZE
PROJECT DOCUMENT NUMBER REV
REVIEWER
DESIGNER
123
7 3 2 1 6 5 4
E
A
B
C
E
D
C
B
A
7 6 5 4
D
IN
IN
IN
IN
C



RETIMER TO CPURETIMER TO CPU
P5E_CPU1_P2_RX_DP/DN<0-15> LANE REVERSAL
Thu Sep 14 16:12:55 2023<NAME_2><NAME_1>MB FABCGT AMDV02339 OF 365
52525252P5E_CPU1_P2_RX_DN<7:0>P5E_CPU1_P2_RX_DP<7:0>PT5161LRSSMLF
RETIMER_CPU1_P2(2)
ICPT5161LRSSMLFICP5E_CPU1_P2_RX_DN<15:8>P5E_CPU1_P2_RX_DP<15:8>
EU26
EK26
EC26
DT26
DJ26
DB26
CR26
CH26
EW29
EM29
EE29
DV29
DL29
DD29
CU29
CK29
CA26
BP26
BG26
AY26
AN26
AF26
W26
M26
CC29
BT29
BJ29
BB29
AR29
AH29
AA29
P29
14 6
7
7
6
2
13
11
12
1
5
5
4
4
3
3
2
1
0
0
13
11
10
12
10
9
8
9
8
14
15
15
U6016
U6016
7/11
A_PETN15
A_PETP15
A_PETN14
A_PETP14
A_PETN13
A_PETP13
A_PETN12
A_PETP12
A_PETN11
A_PETP11
A_PETN10
A_PETP10
A_PETN9
A_PETP9
A_PETN8
A_PETP8
6/11
A_PETN7
A_PETP7
A_PETN6
A_PETP6
A_PETN5
A_PETP5
A_PETN4
A_PETP4
A_PETN3
A_PETP3
A_PETN2
A_PETP2
A_PETN1
A_PETP1
A_PETN0
A_PETP0
TX : A_PET[15:8]
TX : A_PET[7:0]
SHEETDATE
DEPARTMENT
SIZE
PROJECT DOCUMENT NUMBER REV
REVIEWER
DESIGNER
123
7 3 2 1 6 5 4
E
A
B
C
E
D
C
B
A
7 6 5 4
D
OUT
OUT
OUT
OUT
C



EXAMAX TO RETIMEREXAMAX TO RETIMER
P5E_CPU1_P2_RX_BUF_DP/DN<0-15> LANE REVERSAL
Thu Sep 14 16:12:55 2023<NAME_2><NAME_1>MB FABCGT AMDV02340 OF 365
119120120119P5E_CPU1_P2_RX_BUF_DP<15:8>P5E_CPU1_P2_RX_BUF_DN<7:0>P5E_CPU1_P2_RX_BUF_DP<7:0>P5E_CPU1_P2_RX_BUF_DN<15:8>SMLFICPT5161LRSPT5161LRSICSMLF
RETIMER_CPU1_P2(3)
EY1
EN1
EF1
DW1
DM1
DE1
CV1
CL1
EV2
EL2
ED2
DU2
DK2
DC2
CT2
CJ2
CD1
BU1
BK1
BC1
AT1
AJ1
AB1
R1
CB2
BR2
BH2
BA2
AP2
AG2
Y2
N2 7
6
5
4
3
2
1
0
0
1
2
3
4
5
6
7
15
14
13
12
11
10
9
8
8
9
10
11
12
13
14
15
U6016U6016
2/11
A_PERN15
A_PERP15
A_PERN14
A_PERP14
A_PERN13
A_PERP13
A_PERN12
A_PERP12
A_PERN11
A_PERP11
A_PERN10
A_PERP10
A_PERN9
A_PERP9
A_PERN8
A_PERP8
1/11
A_PERN7
A_PERP7
A_PERN6
A_PERP6
A_PERN5
A_PERP5
A_PERN4
A_PERP4
A_PERN3
A_PERP3
A_PERN2
A_PERP2
A_PERN1
A_PERP1
A_PERN0
A_PERP0
RX : A_PER[15:8]
RX : A_PER[7:0]
SHEETDATE
DEPARTMENT
SIZE
PROJECT DOCUMENT NUMBER REV
REVIEWER
DESIGNER
123
7 3 2 1 6 5 4
E
A
B
C
E
D
C
B
A
7 6 5 4
D
IN
ININ
IN
C



P5E_CPU1_P2_TX_BUF_DP/DN<0-15> LANE REVERSAL
RETIMER TO EXAMAXRETIMER TO EXAMAXThu Sep 14 16:12:55 2023<NAME_2><NAME_1>MB FABCGT AMDV02341 OF 365342342120120342342119119
342342342342
DIFF BUS_0.22UFDIFF BUS_0.22UFP5E_CPU1_P2_TX_BUF_DP<7:0>P5E_CPU1_P2_TX_BUF_DN<7:0>P5E_CPU1_P2_TX_BUF_C_DP<7:0>P5E_CPU1_P2_TX_BUF_C_DN<7:0>DIFF BUS_0.22UFDIFF BUS_0.22UFDIFF BUS_0.22UFDIFF BUS_0.22UFDIFF BUS_0.22UFDIFF BUS_0.22UFDIFF BUS_0.22UFDIFF BUS_0.22UFDIFF BUS_0.22UFDIFF BUS_0.22UFDIFF BUS_0.22UFDIFF BUS_0.22UFDIFF BUS_0.22UFC0201X6SDIFF BUS_0.22UF20%6.3VP5E_CPU1_P2_TX_BUF_DN<15:8>P5E_CPU1_P2_TX_BUF_DP<15:8> P5E_CPU1_P2_TX_BUF_C_DP<15:8>P5E_CPU1_P2_TX_BUF_C_DN<15:8>DIFF BUS_0.22UFDIFF BUS_0.22UFDIFF BUS_0.22UFDIFF BUS_0.22UFDIFF BUS_0.22UFDIFF BUS_0.22UFDIFF BUS_0.22UFDIFF BUS_0.22UFDIFF BUS_0.22UFDIFF BUS_0.22UFDIFF BUS_0.22UFDIFF BUS_0.22UFDIFF BUS_0.22UFDIFF BUS_0.22UFDIFF BUS_0.22UF20%C0201X6S6.3VDIFF BUS_0.22UF
P5E_CPU1_P2_TX_BUF_DN<15:8>
RETIMER_CPU1_P2(4)
SMLFPT5161LRSICSMLFICPT5161LRSP5E_CPU1_P2_TX_BUF_DP<15:8>P5E_CPU1_P2_TX_BUF_DP<7:0>P5E_CPU1_P2_TX_BUF_DN<7:0>
2 1
2 1
2 1
2 1
2 1
2 1
2 1
2 1
2 1
2 1
2 1
2 1
2 1
2 1
2 1
2 1
2 1
2 1
2 1
2 1
2 1
2 1
2 1
2 1
2 1
2 1
2 1
2 1
2 1
2 1
2 1
2 1
EU7
EK7
EC7
DT7
DJ7
DB7
CR7
CH7
EW10
EM10
EE10
DV10
DL10
DD10
CU10
CK10
CA7
BP7
BG7
AY7
AN7
AF7
W7
M7
CC10
BT10
BJ10
BB10
AR10
AH10
AA10
P10
7
6
5
4
3
2
1
0
7
6
5
4
3
2
1
0
7
5
6
7
6
5
3
2
4
4
3
2
0
1
1
0
15
14
15
14
12
13
13
12
10
11
9
11
10
9
8
8
15
14
15
14
13
12
12
11
10
9
11
10
9
8
8
13
8 0
2
15
14
13
12
11
10
9
8
9
10
11
12
13
14
15
7
6
5
4
3
2
1
0
1
3
4
5
6
7
U6016
C6710
C6709
C6711
C6712
C6713
C6714
C6715
C6716
C6717
C6718
C6719
C6720
C6721
C6722
C6723
C6724
C6694
C6693
U6016
C6697
C6695
C6696
C6698
C6700
C6699
C6701
C6702
C6703
C6704
C6705
C6706
C6707
C6708
10/11
B_PETN7
B_PETP7
B_PETN6
B_PETP6
B_PETN5
B_PETP5
B_PETN4
B_PETP4
B_PETN3
B_PETP3
B_PETN2
B_PETP2
B_PETN1
B_PETP1
B_PETN0
B_PETP0
11/11
B_PETN15
B_PETP15
B_PETN14
B_PETP14
B_PETN13
B_PETP13
B_PETN12
B_PETP12
B_PETN11
B_PETP11
B_PETN10
B_PETP10
B_PETN9
B_PETP9
B_PETN8
B_PETP8
TX : B_PET[7:0]
TX : B_PET[15:8]
2 12 1
2 12 1
2 12 1
2 12 1
2 12 1
2 12 1
2 12 1
2 12 1
2 12 1
2 1
2 12 1
2 1
2 12 1
2 12 1
2 12 1
2 12 1
2 12 1
SHEETDATE
DEPARTMENT
SIZE
PROJECT DOCUMENT NUMBER REV
REVIEWER
DESIGNER
123
7 3 2 1 6 5 4
E
A
B
C
E
D
C
B
A
7 6 5 4
D
OUT
OUT
ININ
OUTOUTIN
OUT
OUT
OUTOUT
IN
C



CPU1 P1 RT ADDR: 0X48 (8-BIT) / 0X24 (7-BIT)
Thu Sep 14 16:13:05 2023<NAME_2><NAME_1>MB FABCGT AMDV02342 OF 365
P1V8_CPU1_RT_1DP1V8_CPU1_RT_1D P1V8_CPU1_RT_1DP1V8_CPU1_RT_1DP1V8_CPU1_RT_1DP1V8_CPU1_RT_1DP1V8_CPU1_RT_1DSMB_RT_CPU1_P2_ROM_MUX_1D_R_SCLSMB_RT_CPU1_P2_ROM_MUX_1D_SCL1%49.90201LF1/20W CHIPSMB_RT_CPU1_P2_ROM_MUX_1D_R_SDASMB_RT_CPU1_P2_ROM_MUX_1D_SDA1851861851863433433433433433433433438134381343343183343343183343343343343
8134381343343343343343343343 343
343
3431843433433433433431843433433430201LF1%2001/20WCHIPJTAG_TCK_RT_CPU1_P2JTAG_TMS_RT_CPU1_P2JTAG_TDI_RT_CPU1_P2JTAG_TDO_RT_CPU1_P2EMPTY5%0201LF4.7K1/20W4.7K5%1/20W0201LFEMPTY1/20W1%1K0201LFEMPTY4.7K1/20W5%0201LFEMPTYJTAG_TDI_RT_CPU1_P2JTAG_TMS_RT_CPU1_P2JTAG_TDO_RT_CPU1_P2JTAG_TCK_RT_CPU1_P20201LFRST_RT_CPU1_P2_RESET_R_NCHIP0RST_RT_CPU1_P2_PERST_R_NCHIP0201LF1KRXDET_BYP_RT_CPU1_P2CLK_100M_RETIMER_CPU1_P2_R_DPCHIP0201LF0201LF1/20W5%0CHIP51.11/20WEMPTY1%0201LFEMPTY1%0201LF51.11/20W
ICPT5161LRSSMLFEMPTY1/20W4.7K5%0201LF10K1%1/20WCHIP0201LF10K1%1/20WCHIP0201LF5%0201LFEMPTY4.7K1/20W0201LF0CHIP1/20W5%4.7K5%1/20W0201LFCHIP4.7K5%0201LFCHIP1/20WCHIP0201LF4.7K5%1/20W1/20WCHIP4.7K5%0201LF5%0201LFEMPTY1/20W4.7K1/20W5%4.7K0201LFEMPTY4.7K1/20WEMPTY0201LF5%1/20WEMPTY5%4.7K0201LFEMPTY5%0201LF1/20W4.7K4.7K5%1/20WCHIP0201LF
0201LF00201LF0201LF1/20W1%1KEMPTY20K1%1/20WCHIP0201LFCHIP0201LF1/20W1%1KEMPTY1/20W1K1%0201LF1K0201LF1/20W1%CHIP0201LF1/20W1K1%EMPTYCHIP0201LF10K1/20W1%10K1/20W1%CHIP0201LF0201LFEMPTY4.7K1/20W5%
TEST1_RT_CPU1_P2TEST2_RT_CPU1_P2CLK_100M_RETIMER_CPU1_P2_R_DNRT_CPU1_P2_ADDR2GPIO2_RT_CPU1_P2RT_CPU1_P2_ADDR1SMB_RT_CPU1_P2_R2_SDART_CPU1_P2_ADDR3
RST_RT_CPU1_P2_RESET_R_NRST_RT_CPU1_P2_PERST_R_NMODE_RT_CPU1_P2 RT_CPU1_P2_ADDR3JTAG_TEST_MODE_RT_CPU1_P2TEST2_RT_CPU1_P2TEST1_RT_CPU1_P2TEST0_RT_CPU1_P2 RT_CPU1_P2_ADDR1
TEST0_RT_CPU1_P2
RT_CPU1_P2_ADDR2
CLK_100M_RETIMER_CPU1_P2_DNRETIMER_CPU1_P2(5)SMB_RT_CPU1_P2_R_SDAGPIO2_RT_CPU1_P2GPIO3_RT_CPU1_P2GPIO3_RT_CPU1_P2
CLK_100M_RETIMER_CPU1_P2_DPMODE_RT_CPU1_P2RT_CPU1_P2_SCAN_MODESMB_RT_CPU1_P2_R2_SCLSMB_RT_CPU1_P2_R_SCLRT_CPU1_P2_SCAN_MODEJTAG_TEST_MODE_RT_CPU1_P2JTAG_TRST_RT_CPU1_P2_NCLKREQ_RT_CPU1_P2_NRXDET_BYP_RT_CPU1_P21%1/20W0201LFEMPTY1K0201LF1/20W10K1%CHIP4.7KRST_RT_CPU1_P2_PERST_N4.7K5%1/20W0201LFCHIPRST_RT_CPU1_P2_RESET_N
R866R867
FF30
FF27
FF24
E30
B28
B31
B25
B23
F34
FF33
E11
FF11
FJ16
FF18
B16
E18
F2
FJ9
E8
B12
FF8
B9
B6
B3
FJ31
FJ28
FJ25
FJ23
FJ6
FJ3
FF5
G35
U6016
CLOCK
3/11
EE_DAT
EE_CLK
CLKREQ_N
TEST2
TEST1
TEST0
T_SENSE
SMBDAT
SMBCLK
SMB_ADDR3
SMB_ADDR2
SMB_ADDR1
SCAN_MODE
RXDET_BYP
RESET_N
REFCLKP
REFCLKN
REFCLK_OUTP
REFCLK_OUTN
PERST_N
MODE
JTAG_TRST_N
JTAG_TMS
JTAG_TEST_MODE
JTAG_TDO
JTAG_TDI
JTAG_TCK
INT_N
GPIO3
GPIO2
GPIO1
GPIO0
MISCJTAGTEST EEPROMSMBUSGPIO
2
1
2
1
2
1
R1499
2
1
R1417
2
1
2
1
2
1
R1426
2
1
R1427
21R1416
21
2
1
2
1
R870
2
1
2
1
2
1
2
1
2
1
2
1
R861
2
1
R865
2
1
R863
21
21
2
1
R885
2
1
R886
2
1
R871
2
1
R882
2
1
R880
2
1
R878
2
1
R884
2
1
R883
2
1
R881
2
1
R879
2
1
21
21
21
21
21
21
2
1
R874
2
1
R876
2
1
R875
2
1
R868
SHEETDATE
DEPARTMENT
SIZE
PROJECT DOCUMENT NUMBER REV
REVIEWER
DESIGNER
123
7 3 2 1 6 5 4
E
A
B
C
E
D
C
B
A
7 6 5 4
D
IN
IN
IN
IN
IN
OUT
OUT
OUT
OUT
IN
IN
IN
IN
IN
OUTOUT
OUT
OUTOUT
OUT
IN
IN
IN
IN
IN
OUT
IN
BI
BI
OUT
IN
IN
IN
IN
IN
IN
OUTOUTOUTOUT
IN
IN
R1489 R1490R1488
R869
R1421
R637
R887
R892
R864
R854
R860
R640
R873
R872
R691
R692
R619
R620
C



Thu Sep 14 16:13:05 2023<NAME_2><NAME_1>MB FABCGT AMDV02343 OF 365
P0V9_CPU1_RT_2DP0V9_CPU1_RT2_2A_2DP0V9_CPU1_RT2_2AP1V8_CPU1_RT_1DP1V8_CPU1_RT2_1AP1V8_CPU1_RT2_1A_1DCHIP1/20W2001%0201LF0201LF1/20W1%1KEMPTYRT_CPU1_P2_VQPS
RETIMER_CPU1_P2 POWER(6)NCF_CPU1_P2_GNDNCF_A1_CPU1_P2_GND005%1/20WCHIP0201LF
ICPT5161LRSSMLF
1/20W5%0201LF
ICPT5161LRSSMLF
CHIP
FH34
FH2
FG35
FG1
FE34
FE2
D35
D1
C34
C2
A35
A1
V35
V1
U34
U2
T4
T32
T22
T13
L35
L1
K34
K2
J4
J22
H31
H19
H16
H12
FJ19
FJ12
FF21
FF14
FD35
FD1
FC9
FC6
FC3
FC28
FC25
FC23
FC19
FB34
FB2
FA32
FA15
ET35
ET1
ER34
ER2
EP4
EP32
EP22
EP13
EJ35
EJ1
EH34
EH2
EG4
EG32
EG22
EG13
EB35
EB1
EA34
EA2
E33
E27
E14
DY4
DY32
DY22
DY13
DR35
DR1
DP34
DP2
DN4
DN32
DN22
DN13
DH35
DH1
DG34
DG2
DF4
DF32
DF22
DF13
DA35
DA1
CY34
CY2
CW4
CW32
CW22
CW13
CP35
CP1
CN34
CN2
CM4
CM32
CM22
CM13
CG35
CG1
CF34
CF2
CE4
CE32
CE22
CE13
BY35
BY1
BW34
BW2
BV4
BV32
BV22
BV13
BN35
BN1
BM34
BM2
BL4
BL32
BL22
BL13
BF35
BF1
BE34
BE2
BD4
BD32
BD22
BD13
B19
AW35
AW1
AV34
AV2
AU4
AU32
AU22
AU13
AM35
AM1
AL34
AL2
AK4
AK32
AK22
AK13
AE35
AE1
AD34
AD2
AC4
AC32
AC22
AC13
G1
CW20
CW17
BL20
BL17
T20
T17
EP20
EP17
EG20
EG17
DY20
DY17
DN20
DN17
DF20
DF17
BD20
BD17
AU20
AU17
AK20
AK17
AC20
AC17
BV17
CM20
CM17
CE20
CE17
BV20
U6016
U6016
4/11
PWR_2A_20
PWR_2A_19
PWR_2A_18
PWR_2A_17
PWR_2A_16
PWR_2A_15
PWR_2A_14
PWR_2A_13
PWR_2A_12
PWR_2A_11
PWR_2A_10
PWR_2A_9
PWR_2A_8
PWR_2A_7
PWR_2A_6
PWR_2A_5
PWR_2A_4
PWR_2A_3
PWR_2A_2
PWR_2A_1
PWR_1D
PWR_2D_4
PWR_2D_3
PWR_2D_2
PWR_2D_1
PWR_1A_5
PWR_1A_4
PWR_1A_3
PWR_1A_2
PWR_1A_1
VQPS
5/11
GND151
GND150
GND149
GND148
GND147
GND146
GND145
GND144
GND143
GND142
GND141
GND140
GND139
GND138
GND137
GND136
GND135
GND134
GND133
GND132
GND131
GND130
GND129
GND128
GND127
GND126
GND125
GND124
GND123
GND122
GND121
GND120
GND119
GND118
GND117
GND116
GND115
GND114
GND113
GND112
GND111
GND110
GND109
GND108
GND107
GND106
GND105
GND104
GND103
GND102
GND101
GND100
GND99
GND98
GND97
GND96
GND95
GND94
GND93
GND92
GND91
GND90
GND89
GND88
GND87
GND86
GND85
GND84
GND83
NCF_GND12
NCF_GND11
NCF_GND10
NCF_GND9
NCF_GND8
NCF_GND7
NCF_GND6
NCF_GND5
NCF_GND4
NCF_GND3
NCF_GND2
NCF_GND1
GND82
GND81
GND80
GND79
GND78
GND77
GND76
GND75
GND74
GND73
GND72
GND71
GND70
GND69
GND68
GND67
GND66
GND65
GND64
GND63
GND62
GND61
GND60
GND59
GND58
GND57
GND56
GND55
GND54
GND53
GND52
GND51
GND50
GND49
GND48
GND47
GND46
GND45
GND44
GND43
GND42
GND41
GND40
GND39
GND38
GND37
GND36
GND35
GND34
GND33
GND32
GND31
GND30
GND29
GND28
GND27
GND26
GND25
GND24
GND23
GND22
GND21
GND20
GND19
GND18
GND17
GND16
GND15
GND14
GND13
GND12
GND11
GND10
GND9
GND8
GND7
GND6
GND5
GND4
GND3
GND2
GND1
0.9V0.9V1.8V/ 1.8V1.2V / 1.5V
2
1
R6794
2
1
2
1
2
1
SHEETDATE
DEPARTMENT
SIZE
PROJECT DOCUMENT NUMBER REV
REVIEWER
DESIGNER
123
7 3 2 1 6 5 4
E
A
B
C
E
D
C
B
A
7 6 5 4
D
R6795
R6796
R6797
C



RETIMER EEPRO ADDRESS: 0XA0 (8 BIT) / 0X50 (7 BIT)
Thu Sep 14 16:13:00 2023<NAME_2><NAME_1>MB FABCGT AMDV02344 OF 365
P1V8_CPU1_RT_1D1851861851861%33.2SMB_RT_CPU1_P2_ROM_SCLSMB_RT_CPU1_P2_ROM_R_SCL0201LF1/20W CHIPSMB_RT_CPU1_P2_ROM_SDASMB_RT_CPU1_P2_ROM_R_SDAM24M02-DRMN6TPU20_E210V10%0.1UFC0201X7S0201LFCHIP1K1%1/20WSMLF
RETIMER_CPU1_P2(7)
IC
7
4
8
5
6 3
2
1
U20
DU1
DU2
E2
VSSSDA
SCL
WC_N
VCC
2
1C7503
2
1
21 21
SHEETDATE
DEPARTMENT
SIZE
PROJECT DOCUMENT NUMBER REV
REVIEWER
DESIGNER
123
7 3 2 1 6 5 4
E
A
B
C
E
D
C
B
A
7 6 5 4
D
BIIN R6790R693R694
C



Thu Sep 14 16:13:06 2023<NAME_2><NAME_1>MB FABCGT AMDV02345 OF 365
P0V9_CPU1_RT2_2AP1V8_CPU1_RT2_1AP1V8_CPU1_RT_1D
P0V9_CPU1_RT2_2A_2DP1V8_CPU1_RT2_1A_1DP0V9_CPU1_RT_2DX6S4V100UFC080520%4V20%X6SC0805100UFX6S20%100UF4VC080520%100UF4VC0805X6S4VX6S20%100UFC0805100UFX6S20%4VC080520%100UF4VC0805X6SX6S2.5V20% 20%4V 4V47UF47UF4V4V20%47UF20% 20%470UFSPCAPC0805X6S47UFC0805X6SC0805X6SX6SC0805SMLF20%0402C0402X6S20%6.3V10UFC04020201X6SX6SC0402X6S22UF20%4V10UF6.3V20%6.3V4.7UF10%X7S10%10V0.1UFC0201X7S10%10V0.1UFC020110V10%X7S0.1UF1UF02010.1UFC0201X6S10VC0201C02014V20%02014VX6S0.1UF10%C02010.1UF1UF 1UFX6S20%X6S6.3V1UFX6S02011UF6.3V20%X6S4VC040220%X6SC04026.3V20%4V22UF
0.1UF0.1UF0201C0201C0201X7S10%4V1UF1UF10VX7SX6S0.1UF10V4.7UF22UFBLM21SN300SN1D/5A0BLM15PD121SN1D/1300MASMLFINDEMPTY0402LF1/16WL32/R857 COLAY WITH R852/R8531/16W5%020%4VINDSMLFR858 AND R859 COLAY0603LFEMPTYC0201EMPTY100NH/16ASMLFX7S10%X7S10%X6S20%X6S20%X6S20%X6S020120%1UF01/4WX7S10%X7SC0201X7S10V10%C0201X7S10V10%
20%04026.3V20%20%1/4W05%C0201X7S10%10V10V10%22UFX7S10V0.1UF10%X6S0201EMPTY1/16W5%0402LF00402LF5% X7SRETIMER_CPU1_P2 DECAPS(8)
X6S0.1UFC04024VC0402X6SX6SC04021UFX6SC040220%10UF6.3V4V10UF6.3V4V20% 20%X6SC0201X7S10%0.1UFX6S5%C0201X7SX6S20%X6S02010.1UF0402X6S20%6.3V4.7UFIND6.3V4V22UF4VX6S20%22UF 10UF6.3V20%20%20%4.7UF10UFX6SC04021UF4V1UFX6SC04024V4.7UF6.3V10%10VX6S4V1UF4V10V10%X7SC0201X7S10%X6S10V0.1UF02010402040210UF6.3V1UF4V1UF10%X6SC0402C04024V10V0.1UF20% 20% 20%20%4V4V20%20%0201X6S4V20%020110V0.1UF0603LFCHIP0402 0402 0201 0201 0201X6S20%4.7UF4V1UF20%X6S02010201X6S20%1UF4V
4VC08054VX6S47UFC080520%2.5VSPCAP470UFSMLF20%SMLF2.5V20%X7SSPCAP470UF47UFX6S20%0.1UF10V
C02010201C0402X6S20%22UF4.7UF10%X7S0.1UF0.1UF0.1UF10V10V10VC020110VX7SC020120%X6SC0805100UF4V470UF20%SPCAPSMLF2.5VSPCAP2.5VSMLF470UF20%C020110%0.1UFC0201C020120%4V1UF
C368
C7041C7040C7039C7038C7037
C7028
C7006C7004
C373C370C366
C371C369
C375
C367
2121
2 1
L8L7
1 21 2
L3212
2
1
2
1
2
1
2
1
2
1
2
1
2
1C7027
2
1C7026
2
1
2
1
2
1C7005
2
1
2
1
2
1
2
1
2
1
2
1
2
1
2
1
2
1
2
1
2
1
2
1
2
1
2
1
2
1
2
1
2
1
2
1
2
1
2
1
2
1
2
1
2
1
2
1
2
1
2
1
2
1
2
1
2
1
2
1
2
1
2
1
2
1
2
1
2
1
2
1
2
1
2
1
2
1
2
1
2
1
2
1
2
1
2
1
2
1
21
2
1
2
1
2
1
2
1
2
1
2
1
2
1
2
1
2
1
2
1
2
1
2
1
2
1
2
1
2
1
2
1
2
1
2
1
2
1
2
1
2
1
2
1
2
1
2
1
21R853
21
CAD NOTE:
CAD NOTE:
R857
C376C374C372
R852
SHEETDATE
DEPARTMENT
SIZE
PROJECT DOCUMENT NUMBER REV
REVIEWER
DESIGNER
123
7 3 2 1 6 5 4
E
A
B
C
E
D
C
B
A
7 6 5 4
D
C7007
C428C426
C394C390
C409C405
C392C388C385C383C423C419C414C408C404
C431
C382
C429C424
C389C425
C395C411C403
C402C399
C386C412
C417
C413C416
C422C418C415C391C407
C406
C401C398
C420C410
C387C384
R859
C400C430C393C427
C397C396
C421
R858
C381C380C379C377
C378
C



Thu Aug 24 10:17:04 2023<NAME_2><NAME_1>MB FABCGT AMDV02346 OF 365RETIMER_CPU1_P2(9)
SHEETDATE
DEPARTMENT
SIZE
PROJECT DOCUMENT NUMBER REV
REVIEWER
DESIGNER
123
7 3 2 1 6 5 4
E
A
B
C
E
D
C
B
A
7 6 5 4
D
C



Thu Aug 24 10:17:04 2023<NAME_2><NAME_1>MB FABCGT AMDV02347 OF 365RETIMER_CPU1_P2(10)
SHEETDATE
DEPARTMENT
SIZE
PROJECT DOCUMENT NUMBER REV
REVIEWER
DESIGNER
123
7 3 2 1 6 5 4
E
A
B
C
E
D
C
B
A
7 6 5 4
D
C



Thu Aug 24 10:17:05 2023<NAME_2><NAME_1>MB FABCGT AMDV02348 OF 365BLANK
SHEETDATE
DEPARTMENT
SIZE
PROJECT DOCUMENT NUMBER REV
REVIEWER
DESIGNER
123
7 3 2 1 6 5 4
E
A
B
C
E
D
C
B
A
7 6 5 4
D
C



P5E_CPU1_P3_TX_C_DP/DN<0-15> LANE REVERSAL
CPU TO RETIMERCPU TO RETIMERP/N SWAPP/N SWAPP/N SWAPP/N SWAPP/N SWAPP/N SWAPP/N SWAPP/N SWAPP/N SWAPP/N SWAPP/N SWAPP/N SWAPP/N SWAPP/N SWAP
Thu Sep 14 16:12:55 2023<NAME_2><NAME_1>MB FABCGT AMDV02349 OF 365
67676767P5E_CPU1_P3_TX_C_DP<15:8>ICSMLFPT5161LRSIC SMLFPT5161LRS
RETIMER_CPU1_P3(1)
P5E_CPU1_P3_TX_C_DP<7:0>P5E_CPU1_P3_TX_C_DN<7:0>P5E_CPU1_P3_TX_C_DN<15:8>
EV34
EL34
ED34
DU34
DK34
DC34
CT34
CJ34
EY35
EN35
EF35
DW35
DM35
DE35
CV35
CL35
CB34
BR34
BH34
BA34
AP34
AG34
Y34
N34
CD35
BU35
BK35
BC35
AT35
AJ35
AB35
R35
1
7
6
7
5
4
3
2
0
0
2
3
4
5
6
13
12
11
10
9
8
13
12
11
10
9
8
15
15
1
14
14
U6017
U6017
9/11
B_PERN15
B_PERP15
B_PERN14
B_PERP14
B_PERN13
B_PERP13
B_PERN12
B_PERP12
B_PERN11
B_PERP11
B_PERN10
B_PERP10
B_PERN9
B_PERP9
B_PERN8
B_PERP8
8/11
B_PERN7
B_PERP7
B_PERN6
B_PERP6
B_PERN5
B_PERP5
B_PERN4
B_PERP4
B_PERN3
B_PERP3
B_PERN2
B_PERP2
B_PERN1
B_PERP1
B_PERN0
B_PERP0
RX : B_PER[15:8]
RX : B_PER[7:0]
SHEETDATE
DEPARTMENT
SIZE
PROJECT DOCUMENT NUMBER REV
REVIEWER
DESIGNER
123
7 3 2 1 6 5 4
E
A
B
C
E
D
C
B
A
7 6 5 4
D
IN
ININ
IN
C



P5E_CPU1_P3_RX_DP/DN<0-15> LANE REVERSAL
RETIMER TO CPURETIMER TO CPUThu Sep 14 16:12:56 2023<NAME_2><NAME_1>MB FABCGT AMDV02350 OF 365
52525252SMLFICPT5161LRSICSMLFPT5161LRS
RETIMER_CPU1_P3(2)
P5E_CPU1_P3_RX_DP<15:8>P5E_CPU1_P3_RX_DN<15:8>P5E_CPU1_P3_RX_DP<7:0>P5E_CPU1_P3_RX_DN<7:0>
EU26
EK26
EC26
DT26
DJ26
DB26
CR26
CH26
EW29
EM29
EE29
DV29
DL29
DD29
CU29
CK29
CA26
BP26
BG26
AY26
AN26
AF26
W26
M26
CC29
BT29
BJ29
BB29
AR29
AH29
AA29
P29
9
10
11
12
12
8
9
8
10
11
13
15
13
15
0
1
2
3
4
1
2
3
4
6
7
5
6
5
0
7
14
14
U6017
U6017
7/11
A_PETN15
A_PETP15
A_PETN14
A_PETP14
A_PETN13
A_PETP13
A_PETN12
A_PETP12
A_PETN11
A_PETP11
A_PETN10
A_PETP10
A_PETN9
A_PETP9
A_PETN8
A_PETP8
6/11
A_PETN7
A_PETP7
A_PETN6
A_PETP6
A_PETN5
A_PETP5
A_PETN4
A_PETP4
A_PETN3
A_PETP3
A_PETN2
A_PETP2
A_PETN1
A_PETP1
A_PETN0
A_PETP0
TX : A_PET[15:8]
TX : A_PET[7:0]
SHEETDATE
DEPARTMENT
SIZE
PROJECT DOCUMENT NUMBER REV
REVIEWER
DESIGNER
123
7 3 2 1 6 5 4
E
A
B
C
E
D
C
B
A
7 6 5 4
D
OUT
OUT
OUT
OUT
C



EXAMAX TO RETIMEREXAMAX TO RETIMER
P5E_CPU1_P3_RX_BUF_DP/DN<0-15> LANE REVERSAL
Thu Sep 14 16:12:56 2023<NAME_2><NAME_1>MB FABCGT AMDV02351 OF 365
119119120120IC IC
RETIMER_CPU1_P3(3)
PT5161LRSSMLFSMLFPT5161LRSP5E_CPU1_P3_RX_BUF_DP<15:8>P5E_CPU1_P3_RX_BUF_DN<15:8>P5E_CPU1_P3_RX_BUF_DP<7:0>P5E_CPU1_P3_RX_BUF_DN<7:0>
EY1
EN1
EF1
DW1
DM1
DE1
CV1
CL1
EV2
EL2
ED2
DU2
DK2
DC2
CT2
CJ2
CD1
BU1
BK1
BC1
AT1
AJ1
AB1
R1
CB2
BR2
BH2
BA2
AP2
AG2
Y2
N2
15
13
14
12
11
10
8
9
8
9
10
11
12
13
14
15
7
0
1
2
3
4
5
6
1
2
3
5
6
7
0
4
U6017U6017
2/11
A_PERN15
A_PERP15
A_PERN14
A_PERP14
A_PERN13
A_PERP13
A_PERN12
A_PERP12
A_PERN11
A_PERP11
A_PERN10
A_PERP10
A_PERN9
A_PERP9
A_PERN8
A_PERP8
1/11
A_PERN7
A_PERP7
A_PERN6
A_PERP6
A_PERN5
A_PERP5
A_PERN4
A_PERP4
A_PERN3
A_PERP3
A_PERN2
A_PERP2
A_PERN1
A_PERP1
A_PERN0
A_PERP0
RX : A_PER[15:8]
RX : A_PER[7:0]
SHEETDATE
DEPARTMENT
SIZE
PROJECT DOCUMENT NUMBER REV
REVIEWER
DESIGNER
123
7 3 2 1 6 5 4
E
A
B
C
E
D
C
B
A
7 6 5 4
D
IN
ININ
IN
C



RETIMER TO EXAMAXRETIMER TO EXAMAXThu Sep 14 16:12:56 2023<NAME_2><NAME_1>MB FABCGT AMDV02352 OF 365353353120120353353119119
353353353353
P5E_CPU1_P3_TX_BUF_DN<7:0>P5E_CPU1_P3_TX_BUF_DP<7:0> P5E_CPU1_P3_TX_BUF_C_DP<7:0>P5E_CPU1_P3_TX_BUF_C_DN<7:0>DIFF BUS_0.22UFDIFF BUS_0.22UFDIFF BUS_0.22UFDIFF BUS_0.22UFDIFF BUS_0.22UFDIFF BUS_0.22UFDIFF BUS_0.22UFDIFF BUS_0.22UFDIFF BUS_0.22UFDIFF BUS_0.22UFDIFF BUS_0.22UFDIFF BUS_0.22UFDIFF BUS_0.22UFDIFF BUS_0.22UFDIFF BUS_0.22UF6.3VX6S20%C0201DIFF BUS_0.22UFP5E_CPU1_P3_TX_BUF_DN<15:8>P5E_CPU1_P3_TX_BUF_DP<15:8> P5E_CPU1_P3_TX_BUF_C_DP<15:8>P5E_CPU1_P3_TX_BUF_C_DN<15:8>DIFF BUS_0.22UFDIFF BUS_0.22UFDIFF BUS_0.22UFDIFF BUS_0.22UFDIFF BUS_0.22UFDIFF BUS_0.22UFDIFF BUS_0.22UFDIFF BUS_0.22UFDIFF BUS_0.22UFDIFF BUS_0.22UFDIFF BUS_0.22UFDIFF BUS_0.22UFDIFF BUS_0.22UFDIFF BUS_0.22UFDIFF BUS_0.22UF6.3VX6SC020120%DIFF BUS_0.22UF
SMLFPT5161LRSIC SMLFPT5161LRSIC
RETIMER_CPU1_P3(4)
P5E_CPU1_P3_TX_BUF_DN<15:8>P5E_CPU1_P3_TX_BUF_DP<15:8>P5E_CPU1_P3_TX_BUF_DP<7:0>P5E_CPU1_P3_TX_BUF_DN<7:0>
2 1
2 1
2 1
2 1
2 1
2 1
2 1
2 1
2 1
2 1
2 1
2 1
2 1
2 1
2 1
2 1
2 1
2 1
2 1
2 1
2 1
2 1
2 1
2 1
2 1
2 1
2 1
2 1
2 1
2 1
2 1
2 1
EU7
EK7
EC7
DT7
DJ7
DB7
CR7
CH7
EW10
EM10
EE10
DV10
DL10
DD10
CU10
CK10
CA7
BP7
BG7
AY7
AN7
AF7
W7
M7
CC10
BT10
BJ10
BB10
AR10
AH10
AA10
P10
7
6
7
5
4
3
1
2
6
5
4
3
2
7
6
5
4
3
2
0
0
1
0
1
7
6
5
4
3
2
1
0
15
14
15
14
11
13
12
13
12
11
10
9
10
9
8
8
15
14
15
14
13
12
11
13
12
11
10
9
10
9
8
8
15
8
9
10
11
12
13
14
8
9
10
11
12
13
14
15
7
6
5
4
3
2
1
0
0
1
2
3
4
6
7
5
U6017
C6741
C6742
C6743
C6744
C6745
C6746
C6747
C6748
C6749
C6750
C6751
C6752
C6753
C6754
C6755
C6756
C6725
C6726
U6017
C6727
C6729
C6728
C6730
C6732
C6731
C6733
C6734
C6735
C6736
C6737
C6740
C6739
C6738
10/11
B_PETN7
B_PETP7
B_PETN6
B_PETP6
B_PETN5
B_PETP5
B_PETN4
B_PETP4
B_PETN3
B_PETP3
B_PETN2
B_PETP2
B_PETN1
B_PETP1
B_PETN0
B_PETP0
11/11
B_PETN15
B_PETP15
B_PETN14
B_PETP14
B_PETN13
B_PETP13
B_PETN12
B_PETP12
B_PETN11
B_PETP11
B_PETN10
B_PETP10
B_PETN9
B_PETP9
B_PETN8
B_PETP8
TX : B_PET[7:0]
TX : B_PET[15:8]
2 12 1
2 12 1
2 12 1
2 12 1
2 12 1
2 12 1
2 12 1
2 12 1
2 12 1
2 1
2 1
2 1
2 1
2 12 1
2 12 1
2 12 1
2 1
2 12 1
2 1
SHEETDATE
DEPARTMENT
SIZE
PROJECT DOCUMENT NUMBER REV
REVIEWER
DESIGNER
123
7 3 2 1 6 5 4
E
A
B
C
E
D
C
B
A
7 6 5 4
D
OUT
OUT
ININ
OUTOUTIN
OUT
OUT
OUTOUT
IN
C



CPU1 P1 RT ADDR: 0X48 (8-BIT) / 0X24 (7-BIT)
Thu Sep 14 16:13:06 2023<NAME_2><NAME_1>MB FABCGT AMDV02353 OF 365
P1V8_CPU1_RT_1DP1V8_CPU1_RT_1DP1V8_CPU1_RT_1DP1V8_CPU1_RT_1DP1V8_CPU1_RT_1DP1V8_CPU1_RT_1DP1V8_CPU1_RT_1D0201LFCHIP1/20W221%SMB_RT_CPU1_P3_ROM_MUX_1D_SCLSMB_RT_CPU1_P3_ROM_MUX_1D_R_SCL354TEST0_RT_CPU1_P3354SMB_RT_CPU1_P3_ROM_MUX_1D_SDACHIP354SMB_RT_CPU1_P3_ROM_MUX_1D_R_SDA0201LF1%1/20W49.9185186185186354354184354354354354354354354354354354354354354
354354
354
354
183
81354813541841833543543548135481354354354354354354354354CHIP1/20W2001%0201LFCLKREQ_RT_CPU1_P3_NJTAG_TCK_RT_CPU1_P3RT_CPU1_P3_SCAN_MODECHIP0201LF5%TEST2_RT_CPU1_P3TEST1_RT_CPU1_P3SMB_RT_CPU1_P3_R_SCLRT_CPU1_P3_SCAN_MODE0201LFEMPTY1/20WGPIO3_RT_CPU1_P3CHIP1%10K1/20W0201LF1KEMPTY0201LF1/20W1%RXDET_BYP_RT_CPU1_P3GPIO2_RT_CPU1_P35%SMLFMODE_RT_CPU1_P3JTAG_TEST_MODE_RT_CPU1_P3TEST2_RT_CPU1_P3TEST0_RT_CPU1_P3GPIO3_RT_CPU1_P3GPIO2_RT_CPU1_P3TEST1_RT_CPU1_P3PT5161LRSRT_CPU1_P3_ADDR1RT_CPU1_P3_ADDR2
RT_CPU1_P3_ADDR1RT_CPU1_P3_ADDR2
RT_CPU1_P3_ADDR3
RT_CPU1_P3_ADDR3
CHIP0201LFCLK_100M_RETIMER_CPU1_P3_R_DN5%00201LF1%1/20WEMPTY0201LF
IC
RETIMER_CPU1_P3(5)51.151.11%0201LFEMPTY1/20WCLK_100M_RETIMER_CPU1_P3_DN1/20W CHIPCLK_100M_RETIMER_CPU1_P3_DP
RST_RT_CPU1_P3_PERST_R_NRST_RT_CPU1_P3_RESET_R_NSMB_RT_CPU1_P3_R2_SCLSMB_RT_CPU1_P3_R_SDA SMB_RT_CPU1_P3_R2_SDA
5%1/20W4.7KEMPTY0201LFCHIP1/20W0201LF1%10KCHIP1%1/20W10K0201LFEMPTY1%1K0201LF1/20W1%0201LF1K1/20WCHIP1%1K1/20WEMPTY0201LF1%CHIP1/20W0201LF20K1K1%1/20W0201LFCHIP1K1%1/20W0201LFEMPTY
00
0201LFCHIP1/20W5%4.7K4.7K1/20W0201LF5%EMPTY4.7K5%EMPTY1/20W0201LF5%0201LFEMPTY1/20W4.7K4.7K5%1/20W0201LFEMPTY5%CHIP0201LF4.7K1/20W5%4.7K0201LFCHIP1/20WCHIP1/20W5%0201LF4.7K1/20W CHIP0201LF0
4.7K1/20WEMPTY0201LF5%4.7K1/20WEMPTY0201LF5%4.7K1/20WCHIP0201LF5%0201LF1%10KCHIP1/20W0201LFCHIP1/20W1%10K5%4.7KCLK_100M_RETIMER_CPU1_P3_R_DP4.7K1/20WRXDET_BYP_RT_CPU1_P3MODE_RT_CPU1_P3JTAG_TCK_RT_CPU1_P3RST_RT_CPU1_P3_RESET_R_NRST_RT_CPU1_P3_PERST_R_N0201LF0201LF4.7KEMPTY0201LF1K1/20W1%1/20W5%EMPTY0201LFEMPTY0201LF4.7K1/20W5%4.7K5%1/20W0201LFEMPTYRST_RT_CPU1_P3_PERST_NJTAG_TMS_RT_CPU1_P3RST_RT_CPU1_P3_RESET_NJTAG_TDI_RT_CPU1_P30201LF0201LFCHIPJTAG_TEST_MODE_RT_CPU1_P3JTAG_TRST_RT_CPU1_P3_NJTAG_TDO_RT_CPU1_P3JTAG_TMS_RT_CPU1_P3JTAG_TDI_RT_CPU1_P31KCHIP4.7KJTAG_TDO_RT_CPU1_P3
R907R908
FF30
FF27
FF24
E30
B28
B31
B25
B23
F34
FF33
E11
FF11
FJ16
FF18
B16
E18
F2
FJ9
E8
B12
FF8
B9
B6
B3
FJ31
FJ28
FJ25
FJ23
FJ6
FJ3
FF5
G35
U6017
CLOCK
3/11
EE_DAT
EE_CLK
CLKREQ_N
TEST2
TEST1
TEST0
T_SENSE
SMBDAT
SMBCLK
SMB_ADDR3
SMB_ADDR2
SMB_ADDR1
SCAN_MODE
RXDET_BYP
RESET_N
REFCLKP
REFCLKN
REFCLK_OUTP
REFCLK_OUTN
PERST_N
MODE
JTAG_TRST_N
JTAG_TMS
JTAG_TEST_MODE
JTAG_TDO
JTAG_TDI
JTAG_TCK
INT_N
GPIO3
GPIO2
GPIO1
GPIO0
MISCJTAGTEST EEPROMSMBUSGPIO
21R695
2
1
2
1
2
1
R1513
2
1
R1430
2
1
2
1
2
1
R1434
2
1
R1435
21R1429
21
2
1
R911
2
1
2
1
2
1
2
1
2
1
2
1
R906
2
1
R902
2
1
R903
21
21
2
1
R925
2
1
R926
2
1
R912
2
1
R922
2
1
R920
2
1
R924
2
1
R923
2
1
R921
2
1
21
21
21
21
21
2
1
2
1
R918
2
1
R915
2
1
R919
2
1
R917
2
1
R916
2
1
R909
SHEETDATE
DEPARTMENT
SIZE
PROJECT DOCUMENT NUMBER REV
REVIEWER
DESIGNER
123
7 3 2 1 6 5 4
E
A
B
C
E
D
C
B
A
7 6 5 4
D
IN
IN
OUT
OUT
OUT
IN
IN
IN
IN
IN
OUT
OUT
OUT
OUTOUT
OUTOUT
IN
IN
IN
IN
IN
IN
OUT
BI
IN
IN
IN
OUT
BI
IN
IN
IN
IN
IN
IN
OUTOUT
OUTOUT
IN
IN
R1512R1510 R1511
R910
R1433
R927
R949
R904
R901
R895
R642
R913
R914
R696
R621
R622
R641
C



Thu Sep 14 16:13:06 2023<NAME_2><NAME_1>MB FABCGT AMDV02354 OF 365
0201LFP1V8_CPU1_RT3_1A_1DP0V9_CPU1_RT3_2A_2DP0V9_CPU1_RT3_2AP1V8_CPU1_RT3_1AP1V8_CPU1_RT_1DP0V9_CPU1_RT_2DCHIP1/20W2001%1/20W0201LF1%1KEMPTYRT_CPU1_P3_VQPS1/20W0201LFCHIP5%0NCF_CPU1_P3_GNDNCF_A1_CPU1_P3_GNDRETIMER_CPU1_P3 POWER(6)
ICPT5161LRSSMLF
01/20W5%0201LFCHIP
ICPT5161LRSSMLF
FH34
FH2
FG35
FG1
FE34
FE2
D35
D1
C34
C2
A35
A1
V35
V1
U34
U2
T4
T32
T22
T13
L35
L1
K34
K2
J4
J22
H31
H19
H16
H12
FJ19
FJ12
FF21
FF14
FD35
FD1
FC9
FC6
FC3
FC28
FC25
FC23
FC19
FB34
FB2
FA32
FA15
ET35
ET1
ER34
ER2
EP4
EP32
EP22
EP13
EJ35
EJ1
EH34
EH2
EG4
EG32
EG22
EG13
EB35
EB1
EA34
EA2
E33
E27
E14
DY4
DY32
DY22
DY13
DR35
DR1
DP34
DP2
DN4
DN32
DN22
DN13
DH35
DH1
DG34
DG2
DF4
DF32
DF22
DF13
DA35
DA1
CY34
CY2
CW4
CW32
CW22
CW13
CP35
CP1
CN34
CN2
CM4
CM32
CM22
CM13
CG35
CG1
CF34
CF2
CE4
CE32
CE22
CE13
BY35
BY1
BW34
BW2
BV4
BV32
BV22
BV13
BN35
BN1
BM34
BM2
BL4
BL32
BL22
BL13
BF35
BF1
BE34
BE2
BD4
BD32
BD22
BD13
B19
AW35
AW1
AV34
AV2
AU4
AU32
AU22
AU13
AM35
AM1
AL34
AL2
AK4
AK32
AK22
AK13
AE35
AE1
AD34
AD2
AC4
AC32
AC22
AC13
G1
CW20
CW17
BL20
BL17
T20
T17
EP20
EP17
EG20
EG17
DY20
DY17
DN20
DN17
DF20
DF17
BD20
BD17
AU20
AU17
AK20
AK17
AC20
AC17
BV17
CM20
CM17
CE20
CE17
BV20
U6017
U6017
4/11
PWR_2A_20
PWR_2A_19
PWR_2A_18
PWR_2A_17
PWR_2A_16
PWR_2A_15
PWR_2A_14
PWR_2A_13
PWR_2A_12
PWR_2A_11
PWR_2A_10
PWR_2A_9
PWR_2A_8
PWR_2A_7
PWR_2A_6
PWR_2A_5
PWR_2A_4
PWR_2A_3
PWR_2A_2
PWR_2A_1
PWR_1D
PWR_2D_4
PWR_2D_3
PWR_2D_2
PWR_2D_1
PWR_1A_5
PWR_1A_4
PWR_1A_3
PWR_1A_2
PWR_1A_1
VQPS
5/11
GND151
GND150
GND149
GND148
GND147
GND146
GND145
GND144
GND143
GND142
GND141
GND140
GND139
GND138
GND137
GND136
GND135
GND134
GND133
GND132
GND131
GND130
GND129
GND128
GND127
GND126
GND125
GND124
GND123
GND122
GND121
GND120
GND119
GND118
GND117
GND116
GND115
GND114
GND113
GND112
GND111
GND110
GND109
GND108
GND107
GND106
GND105
GND104
GND103
GND102
GND101
GND100
GND99
GND98
GND97
GND96
GND95
GND94
GND93
GND92
GND91
GND90
GND89
GND88
GND87
GND86
GND85
GND84
GND83
NCF_GND12
NCF_GND11
NCF_GND10
NCF_GND9
NCF_GND8
NCF_GND7
NCF_GND6
NCF_GND5
NCF_GND4
NCF_GND3
NCF_GND2
NCF_GND1
GND82
GND81
GND80
GND79
GND78
GND77
GND76
GND75
GND74
GND73
GND72
GND71
GND70
GND69
GND68
GND67
GND66
GND65
GND64
GND63
GND62
GND61
GND60
GND59
GND58
GND57
GND56
GND55
GND54
GND53
GND52
GND51
GND50
GND49
GND48
GND47
GND46
GND45
GND44
GND43
GND42
GND41
GND40
GND39
GND38
GND37
GND36
GND35
GND34
GND33
GND32
GND31
GND30
GND29
GND28
GND27
GND26
GND25
GND24
GND23
GND22
GND21
GND20
GND19
GND18
GND17
GND16
GND15
GND14
GND13
GND12
GND11
GND10
GND9
GND8
GND7
GND6
GND5
GND4
GND3
GND2
GND1
0.9V0.9V1.8V/ 1.8V1.2V / 1.5V
2
1
R6900
2
1
2
1
2
1
SHEETDATE
DEPARTMENT
SIZE
PROJECT DOCUMENT NUMBER REV
REVIEWER
DESIGNER
123
7 3 2 1 6 5 4
E
A
B
C
E
D
C
B
A
7 6 5 4
D
R6901
R6902
R6903
C



RETIMER EEPRO ADDRESS: 0XA0 (8 BIT) / 0X50 (7 BIT)
Thu Sep 14 16:13:01 2023<NAME_2><NAME_1>MB FABCGT AMDV02355 OF 365
P1V8_CPU1_RT_1D1/20W05%0201LFCHIPSMB_RT_CPU1_P3_ROM_R_SCL SMB_RT_CPU1_P3_ROM_SCL1/20WCHIP10VX7SM24M02-DRMN6TPU21_E2SMLF10%1/20W1%1KCHIP
RETIMER_CPU1_P3(7)
IC0.1UF0201LF186 185186 1850201LF1%SMB_RT_CPU1_P3_ROM_SDAC020133.2SMB_RT_CPU1_P3_ROM_R_SDA
7
4
8
5
6 3
2
1
U21
DU1
DU2
E2
VSSSDA
SCL
WC_N
VCC
21R697
2
1
2
1C7504
21
SHEETDATE
DEPARTMENT
SIZE
PROJECT DOCUMENT NUMBER REV
REVIEWER
DESIGNER
123
7 3 2 1 6 5 4
E
A
B
C
E
D
C
B
A
7 6 5 4
D
BIIN R6791R698
C



Thu Sep 14 16:13:07 2023<NAME_2><NAME_1>MB FABCGT AMDV02356 OF 365P0V9_CPU1_RT3_2A_2DP1V8_CPU1_RT3_1A_1DP1V8_CPU1_RT_1DP1V8_CPU1_RT3_1AP0V9_CPU1_RT_2DP0V9_CPU1_RT3_2A100UF4V20%C0805X6SX6S100UFC08054V20%X6S20%C08054V100UFX6S4V100UF20%C0805100UF4VX6S20%C0805X6S20%4VC0805100UF4V100UFC0805X6S20%C040222UF4.7UF4V020110%X7S10V 10V20% 20%2.5VSPCAPX7SX7S10%10V 10V470UF2.5VSPCAPSMLFX7S10% 10%0.1UF4V0201X6S20%4V1UF20%X6S0201X7SC0201C0201X7S10%10VX7S0.1UF20%020120% 20%X6S4V 4V 4V 4V10%1UF20%020120%20%X6S6.3V10UF4VC0402 C040220%X6S20%22UF20%6.3VX6SC040222UF22UF20%C0201
0.1UF0.1UF0.1UF10V 10V 10V10%X7S10%X7SC0201X7S4.7UF20%X6S040222UF4VX6SC0201040220%4V10%IND4V10%X7SC02014VINDSMLFC020104021UF20%4VX6SX7SX6S02011UF20%X6SX7SC0201X7SC0201C0402C040220%X6S4VX6S020110%10VX7SC020105%CHIP1/4W0.1UF10%10V
0.1UF10VX7S10%0.1UF10VX7S10%10VX7S10%X7S0201X6S4.7UF0402X6S20%X6S02016.3V20%X6S4.7UFX6SC040220%6.3V10UF4V20%X6S22UF5%00603LFEMPTY1/4W0201X6S20%4V5%0EMPTY0EMPTY5%0.1UF10VX7SC0201RETIMER_CPU1_P3 DECAPS(8)R705 AND R712 COLAYX6SEMPTY0402LF5%1/16W0SMLFBLM15PD121SN1D/1300MA0402LF1/16W0402LF1/16WL33/R897 COLAY WITH R893/R894INDSMLFBLM21SN300SN1D/5AX6S6.3V4V10UF6.3V20%C040222UF0.1UF10V0.1UFC040220%10%1UFC0201C0201C02014V1UF1UF20%C0402X6S10UF6.3V20%C040220%6.3VC020110%0201C02011UF4VX6S20%0201X6S20%4V1UF0.1UF10V100NH/16A4VX6S20%X6S10UFC0402X6S X6S10UFC0402X6S20%X6SC040220%1UF0603LF040220%02010.1UFX6S1UF10V4.7UF1UF 1UF 1UF02014.7UF 4.7UF6.3V20%X6S X6S020120%X6S02011UF4V4V0.1UF10V10% 10%10V0.1UF 0.1UF 0.1UF0.1UFC0201X7SC020102011UFC020110%10V0.1UF10%6.3V0.1UF1UF6.3V 6.3V 6.3V20%6.3V20%X6S04020402X6S20%10UF10V4VX6SC0201C0201470UFSMLF20%X6SC08054V100UF0.1UF
C434
C7031
C439C436
C438
C432
C435C433
C441
2121
2 1
L10L9
1 21 2
L3312
2
1
2
1C7030
2
1C7029
2
1
2
1
2
1
2
1
2
1
2
1
2
1
2
1
2
1
2
1
2
1
2
1
2
1
2
1
2
1
2
1
2
1
2
1
2
1
2
1
2
1
2
1
2
1
2
1
2
1
2
1
2
1
2
1
2
1
2
1
2
1
2
1
2
1
2
1
2
1
2
1
2
1
2
1
2
1
2
1
2
1
2
1
2
1
2
1
2
1
2
1
2
1
2
1
2
1
21
2
1
2
1
2
1
2
1
2
1
2
1
2
1
2
1
2
1
2
1
2
1
2
1
2
1
2
1
2
1
2
1
2
1
2
1
2
1
21
21R894
CAD NOTE:
CAD NOTE:
R897
C442C440C437
R893
SHEETDATE
DEPARTMENT
SIZE
PROJECT DOCUMENT NUMBER REV
REVIEWER
DESIGNER
123
7 3 2 1 6 5 4
E
A
B
C
E
D
C
B
A
7 6 5 4
D
C498C496
C460C456
C479
C483
C486
C452
C462
C458C493C451C449
C482C499C487
C454C484C489
C476C501C475
C478C474
C471C466
C455C497
C457C481
C492
C491C494C469C472
C488C485
C450C477
C453C448
C473C500
C490C480
C459C470
C495
R900
C464C463
C447C446C445C443
R898
C444
C



0X46 (7-BIT)ADDRESS : 0X8E (8-BIT)0X48 (7-BIT)ADDRESS : 0X90 (8-BIT)0X47 (7-BIT)ADDRESS : 0X8C (8-BIT)
Thu Sep 14 16:13:11 2023<NAME_2><NAME_1>MB FABCGT AMDV02357 OF 365
P12V_OCP_V3_2_RP12V_OCP_SFF_R P12V_OCP_SFF
P3V3_AUX
P3V3_AUXP3V3_AUXP3V3_AUXP3V3_AUXP3V3_AUXP3V3_AUX
P12V_E1S_0_R P12V_E1S_0P12V_OCP_V3_2P12V_OCP_SFF
P3V3_AUXP3V3_AUXP12V_E1S_0P12V_OCP_V3_223782252252252 2388225225225223782POWER MONITOR WILL CHANGE TO AL00023000125V10%0402LF1/16W5%0CHIP05%CHIP1/16W0402LF05%CHIP0402LF1/16W
NC_INA230_6_NC2P12V_OCP_V3_2_ADC_ALERT_RNC_INA230_7_NC1NC_INA230_7_NC3E1S_0_P3V3_P12V_ADC_R_ALERTCHIP4.7K4.7K0402LF1/16W0402LFSMB_INA230_8_3V3AUX_SCL_R1SMB_INA230_8_3V3AUX_SDA_R14.7K1/16W0402LF1/16W5%0SMB_INA230_7_3V3AUX_SDA_R1/16W4.7K1/16WSMB_INA230_6_3V3AUX_SDA_RSMB_INA230_6_3V3AUX_SCL_R2512LFCHIP0402LF0402LFCHIPCHIP0402LFX7R25V0.1UFX7R1%1%4.7K EMPTY1%CHIP4.7K0402LF1%EMPTY 0402LF4.7K 1/16W4.7K EMPTY1/16W1%1%IC10%
CHIP1%CHIP04020.1UF
P12V_E1S_0_ADC_ALERT_R0402LFEMPTY1/16W1%1K1K1%1/16WOCP_V3_2_P3V3_P12V_ADC_R_ALERT0402LFEMPTY0402LF1%1KP12V_OCP_SFF_ADC_ALERT_R0402LFCHIP0
0402LFCHIPNC_INA230_8_NC1NC_INA230_8_NC2NC_INA230_8_NC3NC_INA230_8_NC4NC_INA230_8_NC0
NC_INA230_6_NC3NC_INA230_6_NC5NC_INA230_6_NC410
0.1UF
0.002 2512LF101%0.1UFX7R0402CHIPCHIP
CHIP2512LF2W0.0021%040210%25VX7R1%CHIP1/16W100402LF1%0402LF101/16W CHIP1/16W0CHIP5%CHIP05%040225V0.1UF10%X7R0IC100.1UF10%X7R04021%0.0022W0.1UF25V10%101/16W1%5%010%25VCHIP0IC0402LF5%CHIP25V0402X7R10%25V5%0402LF1/16W0402X7R0.1UF2W1%
POWER MONITOR (4/4)NC_INA230_8_NC5SMB_INA230_8_3V3AUX_SDA_RSMB_INA230_8_3V3AUX_SCL_RVSENSE_P12V_INA230_7_INNVSENSE_P12V_INA230_7_INPNC_INA230_6_NC0
VSENSE_P12V_INA230_8_INPVSENSE_P12V_INA230_8_INN
0402LFEMPTY1/16W1/16WCHIP04.7K1/16W0402LF0
0402LF1/16W1/16W EMPTY1%0402LFCHIP1/16W0402LF
EMPTY1%EMPTY1%SMB_INA230_7_3V3AUX_SCL_R0402LF0402INA230_6_A1INA230_6_A0SMB_INA230_6_3V3AUX_SCL_R1SMB_INA230_6_3V3AUX_SDA_R1VSENSE_P12V_INA230_6_INPVSENSE_P12V_INA230_6_INNCHIPISL28022FRZ-TSMLF0.1UFINA230_7_A1INA230_7_A0SMB_INA230_7_3V3AUX_SCL_R1SMB_INA230_7_3V3AUX_SDA_R125V10%SMLFISL28022FRZ-TINA230_8_A10402INA230_8_A00402LF
X7RISL28022FRZ-TSMLFOCP_SFF_P3V3_P12V_ADC_R_ALERTNC_INA230_6_NC1NC_INA230_7_NC5NC_INA230_7_NC4NC_INA230_7_NC2NC_INA230_7_NC0
R1308
R1350
R1360
R1269
R1271
R1270
R1317
R1355
R1292
R1283
R1305
R1302
R1310
R1307
R1291
R1309
R1306
R1301
R1284
13
12
9
11
TH
4
5
16
15
14
8
7
6
10
3
1
2
13
12
9
11
TH
4
5
16
15
14
8
7
6
10
3
1
2
13
12
9
11
TH
4
5
16
15
14
8
7
6
10
3
1
2
U52
U56
U55
TH_GND
GND
NC5
NC4
NC3
NC2
NC1
NC0
EXT_CLK||INT
VINM
VINP
VBUS
SDA||SMBDAT
SCL|||SMBCLK
A0
A1
VCC
TH_GND
GND
NC5
NC4
NC3
NC2
NC1
NC0
EXT_CLK||INT
VINM
VINP
VBUS
SDA||SMBDAT
SCL|||SMBCLK
A0
A1
VCC
TH_GND
GND
NC5
NC4
NC3
NC2
NC1
NC0
EXT_CLK||INT
VINM
VINP
VBUS
SDA||SMBDAT
SCL|||SMBCLK
A0
A1
VCC
21
2
1
2
1
2
1
2
1
2
1
2
1
2
1
21
2
1
21
21
21
21R1272 21R1275
2
1
2
1
21
21 2
1
21
2
1 21
21
21
21R1274 21R1277
2
1
2
1
21
21R1273
21
2
1
2
1
2
1
21R1276
21 21
21
21
2
1
21
BOM NOTE:
SHEETDATE
DEPARTMENT
SIZE
PROJECT DOCUMENT NUMBER REV
REVIEWER
DESIGNER
123
7 3 2 1 6 5 4
E
A
B
C
E
D
C
B
A
7 6 5 4
D
BIIN
BI
OUT
IN
BIIN
OUT
OUT
R1326
R1328
R1327
R1323
C1107
C1110
C1096
C1112
R1325
C1109
R1322 C1106
C1097R1320
C1111
C1108
R1324
C



0 01ID0ID11ASTERA_LABSBOARD ID(RT)PARADERENESAS01RSVD10
Thu Sep 14 16:13:04 2023<NAME_2><NAME_1>MB FABCGT AMDV02358 OF 365
P1V8_AUX82821/16WCHIP0402LFEMPTY0402LF 0402LFRT_BOARD_ID_ID1RT_BOARD_ID_ID01K1%1%1/16WEMPTY1/16W1%1/16WCHIP1K
BOARD ID (RETIMER)
1%1K1K0402LF
2
1
2
1
2
1
2
1
SHEETDATE
DEPARTMENT
SIZE
PROJECT DOCUMENT NUMBER REV
REVIEWER
DESIGNER
123
7 3 2 1 6 5 4
E
A
B
C
E
D
C
B
A
7 6 5 4
D
OUT
OUT
R6743R6742
R6745R6744
C



Thu Aug 24 10:17:15 2023<NAME_2><NAME_1>MB FABCGT AMDV02359 OF 365Blank
SHEETDATE
DEPARTMENT
SIZE
PROJECT DOCUMENT NUMBER REV
REVIEWER
DESIGNER
123
7 3 2 1 6 5 4
E
A
B
C
E
D
C
B
A
7 6 5 4
D
C



2ND AL053319002 / RS53319LR / REEDSEMIBOM NOTE1ST AL008633005 / MPQ8633BGLE-C838-Z/ MPSBOM CHANGE R&C TABLE
WORK FREQUENCY=600KHZSLEW RATE=1A/USLOAD STEP=7.2AOCP=17.52A (IOUT MAX*1.2)IOUT MAX=15.72AAC + DC =1.710-1.890OUTPUT VOLTAGE=1.8V +/- 5%IOUT TDC=14.6AEFFICIENCY > 90% @TDC3RD=CV+10G0MZ08PG2289.101HLTISAT:13A@100C2ND=CC7390JMZ11ESR=10M OHM5.0*5.8RBPCMC135T-1R0MF13*13*5.0SPECFICATION
FSW=600KHZDCR:0.105M OHM2ND=CV+10G0MZ124.5*4.7*4.5FCCMVOUT=0.6(1+RA/RB)=1.8VRADCR=2.5M OHMP1V8_CPU0_RT_1D2ND=CV-10^0MZ03ISAT:47A@100C
Thu Sep 14 16:13:01 2023<NAME_2><NAME_1>MB FABCGT AMDV02360 OF 365
P3V3_AUXP12V_AUXP1V8_CPU0_RT_1DP3V3_AUXC0402X6SP1V8_RETIMER_CPU0_CS0.22UF3322UF16V22UFX6S20%SMLFP1V8_RETIMER_CPU0_MODE0402LF5%X6S20%16VP1V8_RETIMER_CPU0_ENMPQ8633BGLE-C838-ZX6S22UFC0805 C0805 C080520%20% 20%1/16WC0805 C080522UF 22UF16VX6S16V16V16VOSCONX6SSMLF270UF20%0402LFPWRGD_P1V8_RETIMER_CPU0SMLF1UH20%X6SC08051/16WP1V8_RETIMER_CPU0_FB0.1UFX7R5%X7R0402C0805X6SC0805X6S20% 20%20%X6SC080522UF
P1V8_CPU0_RT_1D
CHIP040220KNPOC0402CHIP4V22UF22UFCHIP22UFX6S20%P1V8_RETIMER_CPU0_VCC25VINDFM_PWRGD_P1V8_RETIMER_CPU0P1V8_RETIMER_CPU0_REF4VSMLF100NH/16A05%7.15K0402LF1/16W1%04020.1UF10K5%0402LF2.20402LFCHIP1%10K50V0402IND4V1000PF50V2.5V0.1UF10%IC010%1/16W1/16WCHIP0402LFCHIPX7R10%25VC0805X6S150PFSW _P1V8_RETIMER_CPU0_BST_R0402LFSW_P1V8_RETIMER_CPU0_SWSW_P1V8_RETIMER_CPU0_BST4V 20%ALUM390UF2.5V25VALUM20%390UFSMLF5%4VSMLF22UFCHIP22UF16VX6SC080520%22UF22UF16V20%X6SC080516V20%X6SC0805SW_P12V_AUX_P1V8_RETIMER_CPU0_FLT25V1UF10%040210%25VEMPTY0.1UF040216V10%X7RX6S10%C04021UF25V80 81
PC6512
21
10
19
5
20
6
9
11_18
4
7
8
3
1
2
PU6500
2
1 PC6514PC6805
2
1 PC6513
2
1 PC6511
2
1 PC6510
2
1 PC6509
2
1 PC6508
21 R6506
21
PL6501
21
PR6505
21
PC6515
2
1
PR6507
2
1
PC6507PR6800
2
1
R6505
2
1 PC6518
2
1 PC6505
2
1 PC6504
21
PR6500
2
1
PR6502
2
1 PC6503
2
1 PC6502
2
1 PC6501
2
1
PR6501
2
1
PC6506
PL6500
PC6802
2
1C6757
PC6500 PC6900 PC6901 PC6902
C6758
21 1 2
VIN2
CS
MODE
TRK_REF
SW
RGND
VCC
AGND
FB
BST
EN
PGND
PGOODVIN1
1 2
2
1
2
1
2
1
2
1
2
1
2
1
21
2
1
2
1PC6800
2
1
SHEETDATE
DEPARTMENT
SIZE
PROJECT DOCUMENT NUMBER REV
REVIEWER
DESIGNER
123
7 3 2 1 6 5 4
E
A
B
C
E
D
C
B
A
7 6 5 4
D
OUT
IN
C



BOM NOTE1ST AL008633005 / MPQ8633BGLE-C838-Z/ MPS2ND AL053319002 / RS53319LR / REEDSEMI
SPECFICATIONIOUT MAX=15.72ALOAD STEP=7.2AEFFICIENCY > 90% @TDCSLEW RATE=1A/USWORK FREQUENCY=600KHZOCP=17.52A (IOUT MAX*1.2)IOUT TDC=14.6AAC + DC =1.710-1.890OUTPUT VOLTAGE=1.8V +/- 5%3RD=CV+10G0MZ082ND=CV+10G0MZ12DCR:0.105M OHM4.5*4.7*4.5ISAT:13A@100CESR=10M OHM2ND=CC7390JMZ115.0*5.8PCMC135T-1R0MFRA13*13*5.0DCR=2.5M OHMVOUT=0.6(1+RA/RB)=1.8VFSW=600KHZBOM CHANGE R&C TABLE
PG2289.101HLTFCCMISAT:47A@100CRB2ND=CV-10^0MZ03P1V8_CPU1_RT_1D
Thu Sep 14 16:13:01 2023<NAME_2><NAME_1>MB FABCGT AMDV02361 OF 365
P3V3_AUXP3V3_AUXP12V_AUXP1V8_CPU1_RT_1D1/16WSW_P1V8_RETIMER_CPU1_SWSW_P1V8_RETIMER_CPU1_BSTP1V8_RETIMER_CPU1_ENC0805X6SC0805X6S20%270UF20%X6SIND16VC0805X6S16V22UF 22UF16VX6SC0805OSCON20%16V 2.5V20%390UF22UF4V22UFC080520%4V20%C0805X6SX6S20%25V0.1UFALUM22UFALUM390UF2.5V0402SMLF22UF4VC08050402LFSW_P1V8_RETIMER_CPU1_BST_RP1V8_RETIMER_CPU1_CS10K50VC080520%22UF0402LFP1V8_RETIMER_CPU1_VCCP1V8_RETIMER_CPU1_MODEP1V8_RETIMER_CPU1_REFP1V8_RETIMER_CPU1_FBPWRGD_P1V8_RETIMER_CPU1 FM_PWRGD_P1V8_RETIMER_CPU110%25VC0402SMLF100NH/16A0402LF1/16W5%0CHIP0402LFCHIP1%7.15K1/16W0402LF5%10%X7R25V04020.1UF2.210K5%1/16WCHIP1%1/16WCHIP0402LF0402150PF5%NPO0402LF20KCHIPSMLFIND1UHX6S20%4V04025%1000PFX7R50VC0805X6S X6S4V20%SMLF10%X7RIC0.1UFCHIP
P1V8_CPU1_RT_1D
CHIP22UFX6S20%20%SMLFC080522UF16V22UF16V0SMLFMPQ8633BGLE-C838-ZC0805X6S16V22UF20%C0805X6S20%22UF16V22UF16V20%X6SC080520%SW_P12V_AUX_P1V8_RETIMER_CPU1_FLT25V10%X6SC04021UF0.1UF25V10%EMPTY040210%25VX6S1UFC04020.22UF040216VX7R10%3380 81
21
10
19
5
20
6
9
11_18
4
7
8
3
1
2
PU6501
2
1 PC6533PC6804
2
1 PC6532
2
1 PC6531
2
1 PC6530
2
1 PC6529
2
1 PC6528
2
1 PC6527
21
PL6502
21 R645
2
1
PC6526
21
PR6524
21
PC6534
2
1
PR6526
2
1
R644
PR6801
2
1 PC6537
2
1 PC6524
2
1 PC6523
21
PR6520
2
1
PR6522
2
1 PC6522
2
1 PC6521
2
1 PC6520
2
1
PR6521
2
1
PC6525
PL6503
PC6803
2
1C105
PC6519 PC6903 PC6904 PC6905
C109
21 1 2
VIN2
CS
MODE
TRK_REF
SW
RGND
VCC
AGND
FB
BST
EN
PGND
PGOODVIN1
1 2
2
1
2
1
2
1
2
1
2
1
21
2
1
2
1PC6801
2
1
SHEETDATE
DEPARTMENT
SIZE
PROJECT DOCUMENT NUMBER REV
REVIEWER
DESIGNER
123
7 3 2 1 6 5 4
E
A
B
C
E
D
C
B
A
7 6 5 4
D
OUT
IN
C



2ND SOURCE: INFENEON BOMPU6502 = TBD / XDPE15284D-0000PR6803,PR6805,PR6817,PR6605 = CS21002FB06PR6810,PR6819,R6801,PR6618 = EMPTYPR6609,PR6610,PR6611,PR6612,PR6613,PR6614 = EMPTYPR6531 = CS01002FB07PR6603 = CS31742FB04
CONFIG/R/17.4K0X600X60 0/0INFENEONRENESASUNUSED
CURRENT STEP = 22ASLEW RATE = 2.5A/USWORK FREQUENCY = 600KHZEFFICIENCY > 85% @TDCREMOTE SENSE LOCAL SENSE
ADDRESS(7-BIT)VR
SVID:UNUSED
PMBUS ADDRESS AND CONFIG
PR6604 = CS25362FB02PC6540 = CH12206KB14PC6601 = CH3104J1B00PC6607 = CH11006JB00PC6606 = CH4106K1B01DIFFERENTIAL PAIRTRACE WIDTH = 10MILTRACE SPACING = 5MILOVER-CURRENT PROTECTION= 92AMAX CURRENT = 57.6ATDC = 54.8AOUTPUT VOLTAGE = 0.86V - 0.945VOUTPUT RIPPLE & NOISE < 46MVTRANSIENT TOLERANCE = 90MVDESIGN SPECIFICATIONPU6502 = TBD / ISL69260IRAZ-TBOM NOTEMAIN SOURCE: RENESAS BOM
Thu Sep 14 16:13:02 2023<NAME_2><NAME_1>MB FABCGT AMDV02362 OF 365
P0V9_RETIMER_CPU0_PWM2C0402P0V9_RETIMER_CPU0_SENSE_R_PP0V9_CPU0_RT_2D P0V9_CPU0_RT_2DP1V8_AUX P3V3_AUX
P5V_AUXP3V3_AUXP3V3_AUXP12V_AUX
P3V3_AUXP3V3_AUX10%X7RPV09_RETIMER_CPU0_VCCS1UF16VISL69260IRAZ-T040250V
1/16WNC_P0V9_RETIMER_CPU0_PWM8P0V9_CPU0_RT_2D_VR_CONTROLLERNC_P0V9_RETIMER_CPU0_PG1NC_P0V9_RETIMER_CPU0_IMON5NC_P0V9_RETIMER_CPU0_PWM5NC_P0V9_RETIMER_CPU0_PWM41/16WNC_P0V9_RETIMER_CPU0_IMON3P0V9_RETIMER_CPU0_IMON2P0V9_RETIMER_CPU0_EN0_RP0V9_RETIMER_CPU0_SVID_SDASMLFICP0V9_RETIMER_CPU0_IMON1P0V9_RETIMER_CPU0_VCC
P0V9_RETIMER_CPU0_EN1_R
P0V9_RETIMER_CPU0_PMSCL_RTP_P0V9_RETIMER_CPU0_SVID_ALERT_N
P0V9_RETIMER_CPU0_VRHOTNC_P0V9_RETIMER_CPU0_IMON4P0V9_RETIMER_CPU0_SVID_CLKTP_P0V9_RETIMER_CPU0_PMALERTP0V9_RETIMER_CPU0_PMSDA_RNC_P0V9_RETIMER_CPU0_PWM3NC_P0V9_RETIMER_CPU0_PWM7
PWRGD_P0V9_RETIMER_CPU0_R
P0V9_RETIMER_CPU0_VMONP0V9_RETIMER_CPU0_TEMP1_RP0V9_RETIMER_CPU0_INALERTNC_P0V9_RETIMER_CPU0_IMON7P0V9_RETIMER_CPU0_PWM1NC_P0V9_RETIMER_CPU0_PWM6NC_P0V9_RETIMER_CPU0_IMON6P0V9_RETIMER_CPU0_CFPP0V9_RETIMER_CPU0_ADDRP0V9_RETIMER_CPU0_TEMP0NC_P0V9_RETIMER_CPU0_IMON8CHIP
20%CHIP6.3V3641/16W81
364
36436415115181SM0402LFSMEMPTYP0V9_RETIMER_CPU0_SENSE_SH_NEMPTYP0V9_RETIMER_CPU0_SENSE_SH_P1/16W1/16W1/16WPWRGD_P0V9_RETIMER_CPU0CHIP 0402LF5%01%1KCHIP 0402LF1K0402LF1/16WEMPTY1%00402LF1/16WEMPTY5%0402LF5%1/16W01K1000PF1/16W1/16W1%
1/16WCHIPCHIP0402LF
CHIP1/16W1K1%CHIP
5%0CHIP 1/16W05%05%CHIP05%CHIP 1/16W05%1/16WCHIP05%1/16WCHIP05%1/16W0EMPTY10%50V0402X7R
25V04021K1%1/16W0402LFEMPTY1K1%0402LF
CHIP11/16WX6S10%16V1UF
1/16WCHIP1%0402LF1KCHIP5%1%10K0402LF
50V100NFC0402X6S10UF10%X6SC0402
50V10%CHIP1/16W5%025V0.1UF10%0402
0CHIP
0402LFEMPTY1%0
1%CHIP0402LF49.91%0
TP_P0V9_RETIMER_CPU0_VRHOT
5%5%3300PF5%
05%0402LF1/16W
00
EMPTY1/16W470PF0402X7R1/16WCHIP
5%1KCHIP1%49.94.7K
05%5%5.36K5%EMPTY0P0V9_RETIMER_CPU0_VINSEN
1%0402LF
1/16W1/16W0
1%5%0402LF5%0402LF
0.1UF10%X7REMPTY0402LF
C0402EMPTYCHIP1/16W1%1KP0V9_RETIMER_CPU0_PMSDA0402LFEMPTY1%1KEMPTYEMPTYP0V9_RETIMER_CPU0_PMSCLP0V9_RETIMER_CPU0_EN0402LF364364
PU6502
21
21
R6860 R643
PR883
R649
PR6817
PR6819
PR6803
PR6805
PR6810
R651
R650
C101
R647
R646
21
21
37
38
14
19
11
15
32
21
40
39
TH
36
35
18
17
31
22
8
7
6
5
4
3
2
1
9
10
16
12
20
13
23
24
25
26
27
28
29
30
33
34
PJ09_P0_N
PJ09_P0_P
CS0
PWM0
TEMP0
ADDR_CFG
TH_GND
CFP
CS2
PWM2
CS3
PWM3
PWM7
CS1
RGND1
VSEN1
nPINALERT#||nPSYSCRIT#
TEMP1||ISYS
VINSEN||VSYS
VMON||IINSEN||VSYS||ISYS
VCCS
PWM6
PG0
PWM1
VSEN0
PWM5
PWM4
PMSDA
RGND0
EN0
nPMALERT#
SVCLK
PG1
CS4
CS5
nVRHOT#
nSVALERT#
CS6
SVDATA
PMSCL
EN1
VCC
CS7
SHORT
1 2
SHORT
1 2
21 21
2
1
2
1
21
21PR6618
21PR6614
21
21
21
21
21
21PR6603
21PR6604
21
2
1
21
21
2
1
21R6801
21PR6606
21PR6807
2
1
2
1PR6605
2
1
2
1PC6605
2
1
2
1
2
1
PR6814
21PR6616
2
1
PR6615
2
1
21
2
1
2
1
2
1
2
1PC6602
2
1
21
21
21
21PR6531
21
21
PR6530
PR6532
R6786
PC6601
PC6607
PC6606
PC6603 PC6604
PR6608
R652R655
PR6607
PC6540
SHEETDATE
DEPARTMENT
SIZE
PROJECT DOCUMENT NUMBER REV
REVIEWER
DESIGNER
123
7 3 2 1 6 5 4
E
A
B
C
E
D
C
B
A
7 6 5 4
D
OUT
OUT
IN
IN
OUT
IN
IN
OUT
BI
IN
PR6613
PR6612
PR6611
PR6610
PR6609
C



P0V9_CPU0_RT_2D_PHASE1ESR=27M OHMRI=3A5*5.84.5*4.5*4.5HCBS4545-101DCR = 0.105M OHMDCR=0.17MOHMISAT=60 @100CPGL6312.121AHLT6.5*6.5*10ISAT=60 @100CPGL6312.121AHLTDCR=0.17MOHM
ISAT = 13A @ 100CP0V9_CPU0_RT_2D_PHASE26.5*6.5*10ESR=27M OHM5*5.8RI=3A
BOM NOTEPC6553_1,PC6576 = EMPTYPU6503,PU6504 = AL099390004 / ISL99390FRZ-TR5935MAIN SOURCE: RENESAS BOM2ND SOURCE: INFENEON BOMPC6563,PC6584 = CH4224K1B01PR6556,PR6564,PR6557 = EMPTYPR6554,PR6562,PR6553,PR6561 = CS00002JB13PU6503,PU6504 = AL021590000 / TDA21590
Thu Sep 14 16:13:02 2023<NAME_2><NAME_1>MB FABCGT AMDV02363 OF 365
SW_P12V_AUX_P0V9_RETIMER_CPU0_FLT
P0V9_CPU0_RT_2DSW_P12V_AUX_P0V9_RETIMER_CPU0_FLTP0V9_RETIMER_CPU0_PVCCP0V9_CPU0_RT_2DP5V_AUX P3V3_AUX
P0V9_RETIMER_CPU0_PVCCP12V_AUX22UF363364363364363363363364363363364363 390UF390UF20%SMLFSMLFSMLFC0805X6SSMLFC0805OSCON20%SW_P0V9_RETIMER_CPU0_SW10402SW_P0V9_RETIMER_CPU0_BOOT1ISL99390FRZ-TR5935SMLFEMPTYIC2.2UF10%C0402P0V9_RETIMER_CPU0_VCC122UF25V10%3300PF50VX7RSW_P0V9_RETIMER_CPU0_BOOT1_RC560PFSW_P0V9_RETIMER_CPU0_SW1_RCNC_PV09_RETIMER_CPU0_GL1_1NC_PV09_RETIMER_CPU0_GL2_10402LFSW_P0V9_RETIMER_CPU0_PH1C040210%1%C080520%
5.6SW_P0V9_RETIMER_CPU0_BOOT2_RCSW_P0V9_RETIMER_CPU0_BOOT21/16W1%0402LFCHIP5.61/16WCHIP
SPCAP2.5V470UF20%2.5V20%SPCAP2.5V470UFSMLF20%SPCAP2.5VSMLF470UF20%SPCAP2.5V20%470UF
SPCAP2.5V470UF20%0402X7R50V3300PF10%100UF20%SMLF16VOSCON16V100UFP0V9_CPU0_RT_2D VR PHASE1 & 2SMLF1/10WC0402C080520%2.5V49922UF10%20%390UF2.5VCHIPSMLFX6S16V22UF20%
SMLFIND100NH/16A1/16W00402LFCHIP5%0402LF1/16W05% 0603LF1%4V20%C0805X6S22UF22UF16VX6S20%C080522UFC080520%16VC0805X6S20%16V22UFC080516VX6S1/16W0402LF1%8.87KEMPTY4V22UF20%X6SSMLFALUM20%C080516VX6S20%
C080522UF20%X6S22UF16V20%C0805X6SC080520%16V22UFC0805X6S22UF16V20%22UF16VX6S20%22UF4VC080550VINDC040225VX6S10%1UF5%00402LF1/16WC0402X6S10%10V2.2UF2.25%CHIP1/16W0402LFX6S16VICISL99390FRZ-TR5935C0402X6S10V2.2UFEMPTY1/16W8.87K100NFC040210%50VX7R1%1.5EMPTY1/8W10%50VC0402EMPTY
1/8W0402LFEMPTY560PFC0402EMPTY10%50V
X6S1UF0.1UF25V0402X7R100NFX7R10%C0402C040210%100NF50VIND120NH/69ASMLF0402LF05%1/16WCHIP10VX6S2.2UFX6S10VC04021/16WCHIP5%2.20402LF50V100NF10%X7RC0402PV09_RETIMER_CPU0_VCCSP0V9_RETIMER_CPU0_IMON1P0V9_RETIMER_CPU0_TEMP0P0V9_RETIMER_CPU0_PWM1P0V9_RETIMER_CPU0_VCC2P0V9_RETIMER_CPU0_LSET2P0V9_RETIMER_CPU0_PWM2P0V9_RETIMER_CPU0_TEMP0NC_PV09_RETIMER_CPU0_DNC2PV09_RETIMER_CPU0_VCCSP0V9_RETIMER_CPU0_IMON2 SW_P0V9_RETIMER_CPU0_SW2P0V9_RETIMER_CPU0_VOS2NC_PV09_RETIMER_CPU0_GL2_2NC_PV09_RETIMER_CPU0_GL1_2SW_P0V9_RETIMER_CPU0_PH2390UFALUM100NFP0V9_RETIMER_CPU0_LSET1NC_PV09_RETIMER_CPU0_DNC110% X7RSW_P0V9_RETIMER_CPU0_SW2_RCCHIP1.50402LF1%100NF120NH/69A50VSMLFX7R16VC040210%X6S X6S22UF4V20%
20%X6SP0V9_RETIMER_CPU0_VOS150VX7RC0805 SMLF0402LF1%2.5V20%SMLFSMLFSPCAP ALUMALUM2.5V470UF
PC6562
PC6812
PC6567_1PC6566_1
PC6585
PR6563
PC6564
PR6555
2
1
2
1
2
1
2
1
21
2
1
21
2
1
2
1
PR6562
PC6586_2 PC6587_2 PC6811 PC534 PC6573 PC6574
PC6571PC6570PC6569PC6568 PC6572
PR6554
1
30
25_29
3
36
10_19
39
34
4
32
40
7_9-20_24
5
37
38
41
6
35
31
33
2
21
21
1
30
25_29
3
36
10_19
39
34
4
32
40
7_9-20_24
5
37
38
41
6
35
31
33
2
21
PU6504
PR6560
PL6506
PL6504
PC6553_1
PR6552
PU6503
PC6552
PC6550_09P0_1
PR6556
PL6505
PC6565
PC6563
PC6554_1PC6555_1
PGND2
GL2
GL1
DNC
EN
PGND3
VOS
VIN2
PGND1
SW
LSET
IOUT
TOUT_FLT
PVCC
PHASE
VIN1
BOOT
AGND
VCC
REFIN
PWM
1 2
PGND2
GL2
GL1
DNC
EN
PGND3
VOS
VIN2
PGND1
SW
LSET
IOUT
TOUT_FLT
PVCC
PHASE
VIN1
BOOT
AGND
VCC
REFIN
PWM
1 2
1 2
2
1
2
1
2
1
2
1
2
1
2
1
2
1
2
1
2
1
2
1
21
21
2
1
2
1
2
1
21
2
1
2
1
2
1
2
1
2
1
2
1
2
1
2
1
2
1
2
1
2
1
2
1
2
1
2
1PC6810
2
1
2
1
2
1
2
1
2
1
2
1
21
2
1
2
1
2
1
2
1
2
1PC6561
2
1
2
1
PR6557
2
1
PR6551
2
1
PR6550
2
1PC6556_1
2
1PC6557_1
2
1PC6558_1
SHEETDATE
DEPARTMENT
SIZE
PROJECT DOCUMENT NUMBER REV
REVIEWER
DESIGNER
123
7 3 2 1 6 5 4
E
A
B
C
E
D
C
B
A
7 6 5 4
D
OUT
IN
OUT
IN
OUT
IN
OUT
IN
PC6576
PR6561
PC6575
PC6551_09P0_2
PR6564
PC6578_2 PC6577_2
PC6806
PC6584
PC6579_2 PC6580_2 PC6581_2 PC6582_2 PC6583 PC6817
PR6553
PC6560 PC6816PC6559_1
C



DIFFERENTIAL PAIRTRACE WIDTH = 10MILLOCAL SENSETRACE SPACING = 5MILREMOTE SENSETDC = 54.7AWORK FREQUENCY = 600KHZEFFICIENCY > 85% @TDCSLEW RATE = 2.5A/USCURRENT STEP = 22ADESIGN SPECIFICATIONOUTPUT VOLTAGE = 0.86V - 0.945VOUTPUT RIPPLE & NOISE < 46MVTRANSIENT TOLERANCE = 90MVMAX CURRENT = 57.6AOVER-CURRENT PROTECTION= 92APC523 = CH11006JB00PC6546 = CH4106K1B01PC514 = CH3104J1B00PC6600 = CH12206KB14PR6804,PR6806,PR6818,PR6821 = CS21002FB06R6800,PR6811,PR6820,PR6539,PR6540 = EMPTYPR6541,PR6542,PR6543,PR6544,PR6548 = EMPTYPR6533 = CS14752FB04PR885 = CS25362FB02PR6601 =CS01002FB07
INFENEON 0X76ADDRESS(7-BIT)VRRENESAS 0X76 0/22.1KCONFIG/RPMBUS ADDRESS AND CONFIG/475
PU6510 = TBD / XDPE15284D-00002ND SOURCE: INFENEON BOMPU6510 = TBD / ISL69260IRAZ-TMAIN SOURCE: RENESAS BOMBOM NOTE
Thu Sep 14 16:13:02 2023<NAME_2><NAME_1>MB FABCGT AMDV02364 OF 365
1/16WP0V9_RETIMER_CPU1_PWM13661/16WP0V9_CPU1_RT_2D P0V9_CPU1_RT_2DP3V3_AUXP3V3_AUX
P3V3_AUX
P5V_AUXP12V_AUX
P3V3_AUXP3V3_AUXP1V8_AUX
P0V9_CPU1_RT_2D_VR_CONTROLLERP0V9_RETIMER_CPU1_EN1_RP0V9_RETIMER_CPU1_INALERTNC_P0V9_RETIMER_CPU1_IMON5NC_P0V9_RETIMER_CPU1_PWM5CHIP366X6SP0V9_RETIMER_CPU1_IMON1P0V9_RETIMER_CPU1_EN0_RP0V9_RETIMER_CPU1_SENSE_R_PPV09_RETIMER_CPU1_VCCSP0V9_RETIMER_CPU1_SVID_SDATP_P0V9_RETIMER_CPU1_SVID_ALERT_NICISL69260IRAZ-TSMLFP0V9_RETIMER_CPU1_VCCP0V9_RETIMER_CPU1_PMSCL_RP0V9_RETIMER_CPU1_IMON2P0V9_RETIMER_CPU1_VRHOTNC_P0V9_RETIMER_CPU1_IMON3NC_P0V9_RETIMER_CPU1_IMON4NC_P0V9_RETIMER_CPU1_PG1
P0V9_RETIMER_CPU1_SVID_CLKTP_P0V9_RETIMER_CPU1_PMALERTP0V9_RETIMER_CPU1_PMSDA_RNC_P0V9_RETIMER_CPU1_PWM4NC_P0V9_RETIMER_CPU1_PWM3NC_P0V9_RETIMER_CPU1_PWM7
PWRGD_P0V9_RETIMER_CPU1_RP0V9_RETIMER_CPU1_PWM2
P0V9_RETIMER_CPU1_VMONP0V9_RETIMER_CPU1_TEMP1_RNC_P0V9_RETIMER_CPU1_IMON7NC_P0V9_RETIMER_CPU1_PWM6NC_P0V9_RETIMER_CPU1_IMON6P0V9_RETIMER_CPU1_CFPP0V9_RETIMER_CPU1_TEMP0NC_P0V9_RETIMER_CPU1_PWM8NC_P0V9_RETIMER_CPU1_IMON8151151
366
3663663668181P0V9_RETIMER_CPU1_SENSE_SH_PSMEMPTYP0V9_RETIMER_CPU1_SENSE_SH_NSMEMPTY49.91%0402LF0402LF
CHIPCHIP 1/16W0402LF
CHIP1K1%1/16WP0V9_RETIMER_CPU1_PMSDAP0V9_RETIMER_CPU1_PMSCL
0402LF
CHIP1/16WCHIP0402LF5%0EMPTY4.7K1/16W 0402LF5%01%5%
05%1/16W5%05%5%TP_P0V9_RETIMER_CPU1_VRHOT005%05%5%005%1/16WC0402C0402X6S10%16V1UF100NF50V1%0402LFCHIP1/16WCHIPP0V9_RETIMER_CPU1_ADDR1%0.1UF25VP0V9_RETIMER_CPU1_VINSENEMPTYCHIP1%1K1/16W0402LF49.91%3300PF50V0402X7R10%
5%0
1%1KEMPTY1%1K05%00402LF004025%
0402LFEMPTY1%1K10%EMPTY040225V0.1UFX7R50V470PF0402CHIP 1/16W1/16WEMPTY1%0402LF10K00402LFCHIP 1/16W1/16WCHIP1/16WCHIP1/16WCHIP
1%
C0402X6S20%6.3V10UF10%16V1UF10%X7RC040211/16W
1K0402LF1%CHIP1/16W
EMPTY5%
1/16W5.36K0402X7R1/16W10%10%CHIP
0402LF5%CHIP
0402LFCHIP1/16W
EMPTY50V1000PF1K 1%01/16WCHIP0402LF5%005%0402LF1/16WCHIP22.1K5%05%0EMPTY
0402LF1/16WEMPTY1/16W1%1KEMPTYP0V9_RETIMER_CPU1_EN5%0PWRGD_P0V9_RETIMER_CPU1CHIP0402LF1/16W 0402LF1/16WCHIP1%EMPTY 1/16W 0402LF1K1%1K
PU6510
R6861 R656
R660
C107
PR6802PR6820PR6811
R661
R662
PR6806
PR6804
R657
PR6818
R658
21
21
37
38
14
19
11
15
32
21
40
39
TH
36
35
18
17
31
22
8
7
6
5
4
3
2
1
9
10
16
12
20
13
23
24
25
26
27
28
29
30
33
34
PJ09_P1_N
PJ09_P1_P
SHORT
1 2
SHORT
1 2
CS0
PWM0
TEMP0
ADDR_CFG
TH_GND
CFP
CS2
PWM2
CS3
PWM3
PWM7
CS1
RGND1
VSEN1
nPINALERT#||nPSYSCRIT#
TEMP1||ISYS
VINSEN||VSYS
VMON||IINSEN||VSYS||ISYS
VCCS
PWM6
PG0
PWM1
VSEN0
PWM5
PWM4
PMSDA
RGND0
EN0
nPMALERT#
SVCLK
PG1
CS4
CS5
nVRHOT#
nSVALERT#
CS6
SVDATA
PMSCL
EN1
VCC
CS7
21 2 1
2
1
21
2
1
PR6812
21
2
1
2
1
2
1PC6545
2
1
21
21
21
21
21
21
21PR6816
2
1
PR6815
21
2
1
2
1PC819
2
1
21
2
1
2
1
2
1
21
21
21
21
21
21
21
2
1
21PR6601
21PR6600
21PR6602
2
1
2
1
21PR6533
21PR6808
21PR6809
21PR885
2
1
2
1
PR6821
21
R6787
PR6538
PC6544PC6543
PC6546
PC523
PR6813
PC6600
R663R665
PC514
SHEETDATE
DEPARTMENT
SIZE
PROJECT DOCUMENT NUMBER REV
REVIEWER
DESIGNER
123
7 3 2 1 6 5 4
E
A
B
C
E
D
C
B
A
7 6 5 4
D
IN
OUT
IN
OUT
OUT
IN
IN
BI
OUT
IN
PR6539
PR6540
PR6541
PR6542
PR6543
PR6544
PR6548
R6800
C



ISAT=60 @100CDCR=0.17MOHM2ND SOURCE: INFENEON BOMPU6511,PU6512 = AL021590000 / TDA21590PR6623,PR6629,PR6622,PR6628 = CS00002JB13PR6626,PR6631,PR6625 = EMPTYPC6621,PC6640 = CH4224K1B01PC6611_1,PC6646 = EMPTYPU6511,PU6512 = AL099390004 / ISL99390FRZ-TR5935BOM NOTEMAIN SOURCE: RENESAS BOMP0V9_CPU1_RT_2D_PHASE1DCR = 0.105M OHM6.5*6.5*10ISAT = 13A @ 100C4.5*4.5*4.5RI=3APGL6312.121AHLT5*5.8
DCR=0.17MOHMESR=27M OHMRI=3A5*5.8ISAT=60 @100C6.5*6.5*10
HCBS4545-101ESR=27M OHM
PGL6312.121AHLTP0V9_CPU1_RT_2D_PHASE2Thu Sep 14 16:13:03 2023<NAME_2><NAME_1>MB FABCGT AMDV02365 OF 365
22UFX6SX6S0402LFCHIP20%X6SX6SC040236636536636536536536636536536636536522UF390UF20%ALUMSMLF2.5VSMLF2.5VNC_PV09_RETIMER_CPU1_DNC1P0V9_RETIMER_CPU1_TEMP0P0V9_RETIMER_CPU1_TEMP0P0V9_RETIMER_CPU1_PWM20402LFP0V9_CPU1_RT_2D VR PHASE1 & 2
0402
NC_PV09_RETIMER_CPU1_GL1_2SW_P0V9_RETIMER_CPU1_SW2_RCALUM390UF20%20%X6S22UF22UF4V100NF50VC0402X6S16V22UF 22UF16V16V16V16V25V10%P0V9_RETIMER_CPU1_LSET2NC_PV09_RETIMER_CPU1_DNC2PV09_RETIMER_CPU1_VCCSP0V9_RETIMER_CPU1_IMON2P0V9_RETIMER_CPU1_VCC2EMPTYALUM ALUM1/10W2.5V2.5V20%4V20%4V22UF22UF10%50V560PF100NF50V16V16V22UF 22UF22UF22UF1UF10%P0V9_RETIMER_CPU1_VCC1P0V9_RETIMER_CPU1_PWM10402LFEMPTYX6SC080522UFC0805X6SC0402X7R10%390UF 390UFSMLF20%2.2UFSW_P0V9_RETIMER_CPU1_SW1_RCP0V9_RETIMER_CPU1_LSET1NC_PV09_RETIMER_CPU1_GL2_1NC_PV09_RETIMER_CPU1_GL1_1SW_P0V9_RETIMER_CPU1_SW1SW_P0V9_RETIMER_CPU1_PH1
NC_PV09_RETIMER_CPU1_GL2_2P0V9_RETIMER_CPU1_VOS2SW_P0V9_RETIMER_CPU1_SW2SW_P0V9_RETIMER_CPU1_PH2P0V9_RETIMER_CPU1_VOS1CHIP1%4990603LFSMLF20%16V20%C080520%
20%C080522UFC0805X6SC080520%X6S16VX7R10%C040216V20%C080520%16VC0805X6SC0805X6SC080550VX7RC0402INDSMLF10%25VC0402CHIP 1/16W 0402LF5%01/16W5%02.2UF10V5%2.21/16W10VX6SC0402SMLFICISL99390FRZ-TR5935
EMPTY8.87K1%1/16W1%EMPTY8.87K1/16W0402LF5%00402LFCHIP1/16WC0402X7R100NF10%50VC0805X6S20%X6S20%20%C08054VC080522UFX6S20%C0805100NF50V10% X7R22UF20%X6SC0805INDSMLF120NH/69AC0402X6S1UFX7R10%100NF50VC04020CHIP5%1/16W 0402LFX6S2.2UFC040210V10%SMLFICISL99390FRZ-TR59350.1UFX7R10%25V
1.51/8W1%0402LFEMPTY2.25%0402LFCHIP1/16WC0402EMPTY10%50V560PFC0402EMPTY1/8W1%0402LF1.5100NH/16ASMLFIND20%X6SC080516V
2.2UF10VC0402X6S16V100UF20%OSCONSMLF
20%100UF16VOSCONSMLF50V10%3300PFX7R0402
3300PF50VX7R10%0402SMLF20%470UF2.5VSPCAP20%SMLF470UF2.5VSPCAP470UF20%SMLF2.5VSPCAP470UF20%SMLF2.5VSPCAP20%SMLF470UF2.5VSPCAP20%SMLF470UF2.5VSPCAP1/16W1%0402LFCHIPSW_P0V9_RETIMER_CPU1_BOOT2 SW_P0V9_RETIMER_CPU1_BOOT2_RC5.61%1/16W 0402LFCHIPSW_P0V9_RETIMER_CPU1_BOOT1 SW_P0V9_RETIMER_CPU1_BOOT1_RC5.6100NFX6S
SW_P12V_AUX_P0V9_RETIMER_CPU1_FLTP0V9_CPU1_RT_2DP0V9_RETIMER_CPU1_PVCCP3V3_AUX
SW_P12V_AUX_P0V9_RETIMER_CPU1_FLTP0V9_RETIMER_CPU1_PVCC
P5V_AUXP12V_AUX
P0V9_CPU1_RT_2D120NH/69A10%PV09_RETIMER_CPU1_VCCSP0V9_RETIMER_CPU1_IMON1
PC6620
PR6630
PC6641
PC6622
PR6624
PC6630PC6629PC6628
PC6632PC6631PC6815
PC6627PC6626PC6625_1PC6624_1
PR6623
PC6814PC6813PC6643_2PC6642_2
PR6629
21
21
1
30
25_29
3
36
10_19
39
34
4
32
40
7_9-20_24
5
37
38
41
6
35
31
33
2
21
1
30
25_29
3
36
10_19
39
34
4
32
40
7_9-20_24
5
37
38
41
6
35
31
33
2
PL6510
PL6511
PR6621
PU6511
PL6512
PU6512
PR6627
1 2
PGND2
GL2
GL1
DNC
EN
PGND3
VOS
VIN2
PGND1
SW
LSET
IOUT
TOUT_FLT
PVCC
PHASE
VIN1
BOOT
AGND
VCC
REFIN
PWM
1 2
PGND2
GL2
GL1
DNC
EN
PGND3
VOS
VIN2
PGND1
SW
LSET
IOUT
TOUT_FLT
PVCC
PHASE
VIN1
BOOT
AGND
VCC
REFIN
PWM
1 2
2
1
2
1
2
1
2
1
2
1
2
1PC6619
2
1
2
1
PR6625
2
1
2
1
2
1
2
1PC473
2
1
2
1
2
1
2
1
2
1
2
1
2
1
21
2
1
2
1
2
1
2
1
2
1
2
1
2
1
2
1
21
2
1
21
2
1
PR6620
2
1
2
1
2
1
2
1
2
1
PR6619
2
1
2
1
2
1
2
1
2
1
2
1
2
1
2
1
2
1
21
2
1
2
1
2
1
21
2
1
21
2
1
2
1
2
1
2
1
2
1
SHEETDATE
DEPARTMENT
SIZE
PROJECT DOCUMENT NUMBER REV
REVIEWER
DESIGNER
123
7 3 2 1 6 5 4
E
A
B
C
E
D
C
B
A
7 6 5 4
D
OUT
IN
IN
IN
OUT
IN
OUT
OUT
PC6819
PC6818
PC6618PC6617_1PC6616_1
PC6621
PC6615_1PC6614_1
PC6623
PC6612_1PC6613_1
PR6626
PC6609_09P1_1
PC6610
PR6622
PC6611_1
PC6639PC6638_2PC6637_2PC6636_2
PC6640
PC6635_2
PC6807
PC6633_2PC6634_2
PR6631
PC6644_09P1_2
PC6645
PR6628
PC6646
C